LOGICAL PART CROSS REFERENCE - 25-Aug-2023 AT 17:03:33

DRAWING: @SCM_LIB.SCM(SCH_1):PAGE10 

Q_RES_0402LF-33.2,1%,1/16W,CHIA  I293  R243
   1 PWRGD_PSU_AC_PWROK      A @SCM_LIB.SCM(SCH_1):PWRGD_PSU_AC_PWROK
   2 PWRGD_PSU_AC_PWROK_R      B @SCM_LIB.SCM(SCH_1):PWRGD_PSU_AC_PWROK_R

Q_RES_0402LF-0,5%,1/16W,CHIP,CA  I456  R822
   1 FM_PRSNT_1_N      A @SCM_LIB.SCM(SCH_1):FM_PRSNT_1_N
   2 FM_PRSNT_0_R_N      B @SCM_LIB.SCM(SCH_1):FM_PRSNT_0_R_N

Q_RES_0402LF-33.2,1%,1/16W,CHIA  I458  R36
   1 SMB_BMC_MM14_SCL      A @SCM_LIB.SCM(SCH_1):SMB_BMC_MM14_SCL
   2 SMB_BMC_MM14_R1_SCL      B @SCM_LIB.SCM(SCH_1):SMB_BMC_MM14_R1_SCL

Q_RES_0402LF-33.2,1%,1/16W,CHIA  I459  R46
   1 SMB_BMC_MM14_SDA      A @SCM_LIB.SCM(SCH_1):SMB_BMC_MM14_SDA
   2 SMB_BMC_MM14_R1_SDA      B @SCM_LIB.SCM(SCH_1):SMB_BMC_MM14_R1_SDA

Q_CAP_0402-0.1UF,25V,10%,EMPTYA  I503  C174
   1 P3V_BAT_R      A @SCM_LIB.SCM(SCH_1):P3V_BAT_R
   2    GND      B @SCM_LIB.SCM(SCH_1):GND

FCONN168_ME1016810202011_SCM-FA  I553  GF1
 OA1 P12V_AUX P12V_AUX_OA1 @SCM_LIB.SCM(SCH_1):P12V_AUX
 OA2 P12V_AUX P12V_AUX_OA2 @SCM_LIB.SCM(SCH_1):P12V_AUX
 OA3    GND GND_OA3 @SCM_LIB.SCM(SCH_1):GND
 OA4    GND GND_OA4 @SCM_LIB.SCM(SCH_1):GND
 OA5 I3C1_SPD_SCL I3C_0_SCL @SCM_LIB.SCM(SCH_1):I3C1_SPD_SCL
 OA6 I3C1_SPD_SDA I3C_0_SDA @SCM_LIB.SCM(SCH_1):I3C1_SPD_SDA
 OA7 I3C2_SPD_SCL I3C_1_SCL @SCM_LIB.SCM(SCH_1):I3C2_SPD_SCL
 OA8 I3C2_SPD_SDA I3C_1_SDA @SCM_LIB.SCM(SCH_1):I3C2_SPD_SDA
 OA9 I3C3_SPD_SCL I3C_2_SCL @SCM_LIB.SCM(SCH_1):I3C3_SPD_SCL
OA10 I3C3_SPD_SDA I3C_2_SDA @SCM_LIB.SCM(SCH_1):I3C3_SPD_SDA
OA11 I3C4_SPD_SCL I3C_3_SCL @SCM_LIB.SCM(SCH_1):I3C4_SPD_SCL
OA12 I3C4_SPD_SDA I3C_3_SDA @SCM_LIB.SCM(SCH_1):I3C4_SPD_SDA
OA13    GND GND_OA13 @SCM_LIB.SCM(SCH_1):GND
OA14 FM_VIRTUAL_RESEAT VIRTUAL_RESEAT @SCM_LIB.SCM(SCH_1):FM_VIRTUAL_RESEAT
  A1 SMB_BMC_MM14_R1_SCL I2C_0_SCL @SCM_LIB.SCM(SCH_1):SMB_BMC_MM14_R1_SCL
  A2 SMB_BMC_MM14_R1_SDA I2C_0_SDA @SCM_LIB.SCM(SCH_1):SMB_BMC_MM14_R1_SDA
  A3 SMB_BMC_MM1_SCL I2C_1_SCL @SCM_LIB.SCM(SCH_1):SMB_BMC_MM1_SCL
  A4 SMB_BMC_MM1_SDA I2C_1_SDA @SCM_LIB.SCM(SCH_1):SMB_BMC_MM1_SDA
  A5 SMB_BMC_MM2_SCL_R1 I2C_2_SCL @SCM_LIB.SCM(SCH_1):SMB_BMC_MM2_SCL_R1
  A6 SMB_BMC_MM2_SDA I2C_2_SDA @SCM_LIB.SCM(SCH_1):SMB_BMC_MM2_SDA
  A7 SMB_BMC_MM3_SCL I2C_3_SCL @SCM_LIB.SCM(SCH_1):SMB_BMC_MM3_SCL
  A8 SMB_BMC_MM3_SDA I2C_3_SDA @SCM_LIB.SCM(SCH_1):SMB_BMC_MM3_SDA
  A9 SMB_BMC_MM4_SCL I2C_4_SCL @SCM_LIB.SCM(SCH_1):SMB_BMC_MM4_SCL
 A10 SMB_BMC_MM4_SDA I2C_4_SDA @SCM_LIB.SCM(SCH_1):SMB_BMC_MM4_SDA
 A11 SMB_BMC_MM5_SCL I2C_5_SCL @SCM_LIB.SCM(SCH_1):SMB_BMC_MM5_SCL
 A12 SMB_BMC_MM5_SDA I2C_5_SDA @SCM_LIB.SCM(SCH_1):SMB_BMC_MM5_SDA
 A13    GND GND_A13 @SCM_LIB.SCM(SCH_1):GND
 A14 CLK_100M_PCH_DP CLK_100M_PCIE_DP @SCM_LIB.SCM(SCH_1):CLK_100M_PCH_DP
 A15 CLK_100M_PCH_DN CLK_100M_PCIE_DN @SCM_LIB.SCM(SCH_1):CLK_100M_PCH_DN
 A16    GND GND_A16 @SCM_LIB.SCM(SCH_1):GND
 A17 P2E_PCH_RX_DP PCIE_BMC_TX_DP @SCM_LIB.SCM(SCH_1):P2E_PCH_RX_DP
 A18 P2E_PCH_RX_DN PCIE_BMC_TX_DN @SCM_LIB.SCM(SCH_1):P2E_PCH_RX_DN
 A19    GND GND_A19 @SCM_LIB.SCM(SCH_1):GND
 A20 P2E_PCH_TX_C_DP PCIE_BMC_RX_DP @SCM_LIB.SCM(SCH_1):P2E_PCH_TX_C_DP
 A21 P2E_PCH_TX_C_DN PCIE_BMC_RX_DN @SCM_LIB.SCM(SCH_1):P2E_PCH_TX_C_DN
 A22    GND GND_A22 @SCM_LIB.SCM(SCH_1):GND
 A23 SMB_BMC_MM6_SCL I2C_6_SCL @SCM_LIB.SCM(SCH_1):SMB_BMC_MM6_SCL
 A24 SMB_BMC_MM6_SDA I2C_6_SDA @SCM_LIB.SCM(SCH_1):SMB_BMC_MM6_SDA
 A25 SMB_BMC_MM7_SCL I2C_7_SCL @SCM_LIB.SCM(SCH_1):SMB_BMC_MM7_SCL
 A26 SMB_BMC_MM7_SDA I2C_7_SDA @SCM_LIB.SCM(SCH_1):SMB_BMC_MM7_SDA
 A27 SMB_BMC_MM8_SCL I2C_8_SCL @SCM_LIB.SCM(SCH_1):SMB_BMC_MM8_SCL
 A28 SMB_BMC_MM8_SDA I2C_8_SDA @SCM_LIB.SCM(SCH_1):SMB_BMC_MM8_SDA
 A29 SMB_BMC_MM9_SCL I2C_9_SCL @SCM_LIB.SCM(SCH_1):SMB_BMC_MM9_SCL
 A30 SMB_BMC_MM9_SDA I2C_9_SDA @SCM_LIB.SCM(SCH_1):SMB_BMC_MM9_SDA
 A31 SMB_BMC_MM10_SCL I2C_10_SCL @SCM_LIB.SCM(SCH_1):SMB_BMC_MM10_SCL
 A32 SMB_BMC_MM10_SDA I2C_10_SDA @SCM_LIB.SCM(SCH_1):SMB_BMC_MM10_SDA
 A33    GND GND_A33 @SCM_LIB.SCM(SCH_1):GND
 A34 JTAG_MB_TCK JTAG_TCK @SCM_LIB.SCM(SCH_1):JTAG_MB_TCK
 A35 JTAG_MB_TMS JTAG_TMS @SCM_LIB.SCM(SCH_1):JTAG_MB_TMS
 A36 JTAG_MB_TDI JTAG_TDI @SCM_LIB.SCM(SCH_1):JTAG_MB_TDI
 A37 JTAG_MB_TDO JTAG_TDO @SCM_LIB.SCM(SCH_1):JTAG_MB_TDO
 A38 SMB_BMC_MM12_SCL I2C_11_SCL @SCM_LIB.SCM(SCH_1):SMB_BMC_MM12_SCL
 A39 SMB_BMC_MM12_SDA I2C_11_SDA @SCM_LIB.SCM(SCH_1):SMB_BMC_MM12_SDA
 A40 SMB_BMC_MM13_SCL I2C_12_SCL @SCM_LIB.SCM(SCH_1):SMB_BMC_MM13_SCL
 A41 SMB_BMC_MM13_SDA I2C_12_SDA @SCM_LIB.SCM(SCH_1):SMB_BMC_MM13_SDA
 A42    GND GND_A42 @SCM_LIB.SCM(SCH_1):GND
 A43 FM_JTAG_SEL HPM_FW_RECOVERY @SCM_LIB.SCM(SCH_1):FM_JTAG_SEL
 A44 PWRGD_PSU_AC_PWROK_R HPM_STBY_RDY @SCM_LIB.SCM(SCH_1):PWRGD_PSU_AC_PWROK_R
 A45 TP_GF_A45 HPM_STBY_EN @SCM_LIB.SCM(SCH_1):TP_GF_A45
 A46 RST_MB_STBY_N HPM_STBY_RST_N @SCM_LIB.SCM(SCH_1):RST_MB_STBY_N
 A47 SYS_PWRBTN_N SYS_PWRBTN_N @SCM_LIB.SCM(SCH_1):SYS_PWRBTN_N
 A48 PWRGD_SYS_PWROK SYS_PWROK @SCM_LIB.SCM(SCH_1):PWRGD_SYS_PWROK
 A49 FM_DBP_CPU_PREQ_GF_R_N DBP_PREQ_N @SCM_LIB.SCM(SCH_1):FM_DBP_CPU_PREQ_GF_R_N
 A50 FM_DBP_BMC_PRDY_N DBP_PRDY_N @SCM_LIB.SCM(SCH_1):FM_DBP_BMC_PRDY_N
 A51 RST_PLTRST_N RST_PLTRST_BUF_N @SCM_LIB.SCM(SCH_1):RST_PLTRST_N
 A52 FM_BMC_UARTSW_MSB_N SPARE1 @SCM_LIB.SCM(SCH_1):FM_BMC_UARTSW_MSB_N
 A53 RST_ROT_CPU_N ROT_CPU_RST_N @SCM_LIB.SCM(SCH_1):RST_ROT_CPU_N
 A54 FM_INTRUDER_N CHASI_N @SCM_LIB.SCM(SCH_1):FM_INTRUDER_N
 A55 FM_BMC_UARTSW_LSB_N SPARE0 @SCM_LIB.SCM(SCH_1):FM_BMC_UARTSW_LSB_N
 A56 IRQ_SMI_ACTIVE_GF_N  IRQ_N @SCM_LIB.SCM(SCH_1):IRQ_SMI_ACTIVE_GF_N
 A57 FM_PRSNT_1_N PRSNT1_N @SCM_LIB.SCM(SCH_1):FM_PRSNT_1_N
 A58    GND GND_A58 @SCM_LIB.SCM(SCH_1):GND
 A59 USB3_FPNL_RXP PCIE_HPM_RXP_0 @SCM_LIB.SCM(SCH_1):USB3_FPNL_RXP
 A60 USB3_FPNL_RXN PCIE_HPM_RXN_0 @SCM_LIB.SCM(SCH_1):USB3_FPNL_RXN
 A61    GND GND_A61 @SCM_LIB.SCM(SCH_1):GND
 A62 TP_GF_A62 PCIE_HPM_RXP_1 @SCM_LIB.SCM(SCH_1):TP_GF_A62
 A63 TP_GF_A63 PCIE_HPM_RXN_1 @SCM_LIB.SCM(SCH_1):TP_GF_A63
 A64    GND GND_A64 @SCM_LIB.SCM(SCH_1):GND
 A65 P2E_GPU_RX_DP PCIE_HPM_RXP_2 @SCM_LIB.SCM(SCH_1):P2E_GPU_RX_DP
 A66 P2E_GPU_RX_DN PCIE_HPM_RXN_2 @SCM_LIB.SCM(SCH_1):P2E_GPU_RX_DN
 A67    GND GND_A67 @SCM_LIB.SCM(SCH_1):GND
 A68 CLK_100M_GPU_DP PCIE_HPM_RXP_3 @SCM_LIB.SCM(SCH_1):CLK_100M_GPU_DP
 A69 CLK_100M_GPU_DN PCIE_HPM_RXN_3 @SCM_LIB.SCM(SCH_1):CLK_100M_GPU_DN
 A70    GND GND_A70 @SCM_LIB.SCM(SCH_1):GND
 OB1 P12V_AUX P12V_AUX_OB1 @SCM_LIB.SCM(SCH_1):P12V_AUX
 OB2 P12V_AUX P12V_AUX_OB2 @SCM_LIB.SCM(SCH_1):P12V_AUX
 OB3 FM_PRSNT_0_R_N PRSNT0_N @SCM_LIB.SCM(SCH_1):FM_PRSNT_0_R_N
 OB4    GND GND_OB4 @SCM_LIB.SCM(SCH_1):GND
 OB5 UART_BIC_GF_TXD UART1_SCM_TX @SCM_LIB.SCM(SCH_1):UART_BIC_GF_TXD
 OB6 UART_BIC_GF_RXD UART1_SCM_RX @SCM_LIB.SCM(SCH_1):UART_BIC_GF_RXD
 OB7    GND GND_OB7 @SCM_LIB.SCM(SCH_1):GND
 OB8 UART_SYS_DBG_TX UART0_SCM_TX @SCM_LIB.SCM(SCH_1):UART_SYS_DBG_TX
 OB9 UART_SYS_DBG_RX UART0_SCM_RX @SCM_LIB.SCM(SCH_1):UART_SYS_DBG_RX
OB10    GND GND_OB10 @SCM_LIB.SCM(SCH_1):GND
OB11 RST_SRST_PLD_BMC_R_N SPI0_CLK @SCM_LIB.SCM(SCH_1):RST_SRST_PLD_BMC_R_N
OB12 SPI_TPM_CS_N SPI0_CS_N @SCM_LIB.SCM(SCH_1):SPI_TPM_CS_N
OB13 H_CPU_CATERR_LVC2_R2_N SPI0_MOSI @SCM_LIB.SCM(SCH_1):H_CPU_CATERR_LVC2_R2_N
OB14 FM_SOL_UART_CH_SEL SPI0_MISO @SCM_LIB.SCM(SCH_1):FM_SOL_UART_CH_SEL
  B1 ESPI_HOST_LPC_BMC_CLK ESPI_CLK @SCM_LIB.SCM(SCH_1):ESPI_HOST_LPC_BMC_CLK
  B2 ESPI_HOST_LPC_BMC_LFRAME_N ESPI_CS0_N @SCM_LIB.SCM(SCH_1):ESPI_HOST_LPC_BMC_LFRAME_N
  B3 IRQ_BMC_LPC_SERIRQ_ESPI_GF ESPI_ALERT_N @SCM_LIB.SCM(SCH_1):IRQ_BMC_LPC_SERIRQ_ESPI_GF
  B4 RST_BMC_LPC_ESPI_N ESPI_RESET_N @SCM_LIB.SCM(SCH_1):RST_BMC_LPC_ESPI_N
  B5 ESPI_LPC_LAD0_IO0 ESPI_IO0 @SCM_LIB.SCM(SCH_1):ESPI_LPC_LAD0_IO0
  B6 ESPI_LPC_LAD1_IO1 ESPI_IO1 @SCM_LIB.SCM(SCH_1):ESPI_LPC_LAD1_IO1
  B7 ESPI_LPC_LAD2_IO2 ESPI_IO2 @SCM_LIB.SCM(SCH_1):ESPI_LPC_LAD2_IO2
  B8 ESPI_LPC_LAD3_IO3 ESPI_IO3 @SCM_LIB.SCM(SCH_1):ESPI_LPC_LAD3_IO3
  B9 LPC_ESPI_SEL  RSVD3 @SCM_LIB.SCM(SCH_1):LPC_ESPI_SEL
 B10    GND GND_B10 @SCM_LIB.SCM(SCH_1):GND
 B11 SPI_SYS_R_CLK QSPI0_CLK @SCM_LIB.SCM(SCH_1):SPI_SYS_R_CLK
 B12 SPI_SYS_CS0_N QSPI0_CS0_N @SCM_LIB.SCM(SCH_1):SPI_SYS_CS0_N
 B13 SPI_SYS_R_MOSI QSPI0_D0 @SCM_LIB.SCM(SCH_1):SPI_SYS_R_MOSI
 B14 SPI_SYS_R_MISO QSPI0_D1 @SCM_LIB.SCM(SCH_1):SPI_SYS_R_MISO
 B15 SPI_SYS_WP_R_IO2 QSPI0_D2 @SCM_LIB.SCM(SCH_1):SPI_SYS_WP_R_IO2
 B16 SPI_SYS_HOLD_R_IO3 QSPI0_D3 @SCM_LIB.SCM(SCH_1):SPI_SYS_HOLD_R_IO3
 B17    GND GND_B17 @SCM_LIB.SCM(SCH_1):GND
 B18 RMII_OCP_RCLKI NCSI_CLK @SCM_LIB.SCM(SCH_1):RMII_OCP_RCLKI
 B19 RMII_CSRDV NCSI_CRS_DV @SCM_LIB.SCM(SCH_1):RMII_CSRDV
 B20 RMII_TXEN NCSI_TXEN @SCM_LIB.SCM(SCH_1):RMII_TXEN
 B21 RMII_TXD0 NCSI_TXD0 @SCM_LIB.SCM(SCH_1):RMII_TXD0
 B22 RMII_TXD1 NCSI_TXD1 @SCM_LIB.SCM(SCH_1):RMII_TXD1
 B23 RMII_RXER NCSI_RXER @SCM_LIB.SCM(SCH_1):RMII_RXER
 B24 RMII_RXD0 NCSI_RXD0 @SCM_LIB.SCM(SCH_1):RMII_RXD0
 B25 RMII_RXD1 NCSI_RXD1 @SCM_LIB.SCM(SCH_1):RMII_RXD1
 B26    GND GND_B26 @SCM_LIB.SCM(SCH_1):GND
 B27 PECI_BMC PECI_BMC @SCM_LIB.SCM(SCH_1):PECI_BMC
 B28 PVCCIO_PECI_BMC PVCCIO_PECI @SCM_LIB.SCM(SCH_1):PVCCIO_PECI_BMC
 B29 SGPIO_DO_0 SGPIO0_DO @SCM_LIB.SCM(SCH_1):SGPIO_DO_0
 B30 SGPIO_CLK_0 SGPIO_CLK @SCM_LIB.SCM(SCH_1):SGPIO_CLK_0
 B31 SGPIO_DI_0 SGPIO0_DI @SCM_LIB.SCM(SCH_1):SGPIO_DI_0
 B32 SGPIO_LD_0 SGPIO0_LD @SCM_LIB.SCM(SCH_1):SGPIO_LD_0
 B33    GND GND_B33 @SCM_LIB.SCM(SCH_1):GND
 B34 SGPIO_DO_1 SGPIO1_DO @SCM_LIB.SCM(SCH_1):SGPIO_DO_1
 B35 SGPIO_CLK_1  RSVD2 @SCM_LIB.SCM(SCH_1):SGPIO_CLK_1
 B36 SGPIO_DI_1 SGPIO1_DI @SCM_LIB.SCM(SCH_1):SGPIO_DI_1
 B37 SGPIO_LD_1 SGPIO1_LD @SCM_LIB.SCM(SCH_1):SGPIO_LD_1
 B38    GND GND_B38 @SCM_LIB.SCM(SCH_1):GND
 B39 RST_SGPIO_RESET_N SGPIO_RESET_N @SCM_LIB.SCM(SCH_1):RST_SGPIO_RESET_N
 B40 IRQ_SGPIO_N SGPIO_INTR_N @SCM_LIB.SCM(SCH_1):IRQ_SGPIO_N
 B41 P3V_BAT_R P3V0_BAT @SCM_LIB.SCM(SCH_1):P3V_BAT_R
 B42 AC_PWR_BTN_N QSPI0_CS1_N @SCM_LIB.SCM(SCH_1):AC_PWR_BTN_N
 B43 QSPI_2_PLD_CLK QSPI1_CLK @SCM_LIB.SCM(SCH_1):QSPI_2_PLD_CLK
 B44 TP_GF1_B44 QSPI1_CS0_N @SCM_LIB.SCM(SCH_1):TP_GF1_B44
 B45 QSPI_2_PLD_IO0 QSPI1_D0 @SCM_LIB.SCM(SCH_1):QSPI_2_PLD_IO0
 B46 QSPI_2_PLD_IO1 QSPI1_D1 @SCM_LIB.SCM(SCH_1):QSPI_2_PLD_IO1
 B47 QSPI_2_PLD_IO2 QSPI1_D2 @SCM_LIB.SCM(SCH_1):QSPI_2_PLD_IO2
 B48 QSPI_2_PLD_IO3 QSPI1_D3 @SCM_LIB.SCM(SCH_1):QSPI_2_PLD_IO3
 B49    GND GND_B49 @SCM_LIB.SCM(SCH_1):GND
 B50 USB_HOST_BMC_B_DP USB2_DP @SCM_LIB.SCM(SCH_1):USB_HOST_BMC_B_DP
 B51 USB_HOST_BMC_B_DN USB2_DN @SCM_LIB.SCM(SCH_1):USB_HOST_BMC_B_DN
 B52    GND GND_B52 @SCM_LIB.SCM(SCH_1):GND
 B53 USB_HOST_BMC_A_DP USB1_DP @SCM_LIB.SCM(SCH_1):USB_HOST_BMC_A_DP
 B54 USB_HOST_BMC_A_DN USB1_DN @SCM_LIB.SCM(SCH_1):USB_HOST_BMC_A_DN
 B55    GND GND_B55 @SCM_LIB.SCM(SCH_1):GND
 B56 USB_FPNL_DP  RSVD0 @SCM_LIB.SCM(SCH_1):USB_FPNL_DP
 B57 USB_FPNL_DN  RSVD1 @SCM_LIB.SCM(SCH_1):USB_FPNL_DN
 B58    GND GND_B58 @SCM_LIB.SCM(SCH_1):GND
 B59 USB3_FPNL_TXP PCIE_HPM_TXP_0 @SCM_LIB.SCM(SCH_1):USB3_FPNL_TXP
 B60 USB3_FPNL_TXN PCIE_HPM_TXN_0 @SCM_LIB.SCM(SCH_1):USB3_FPNL_TXN
 B61    GND GND_B61 @SCM_LIB.SCM(SCH_1):GND
 B62 TP_GF_B62 PCIE_HPM_TXP_1 @SCM_LIB.SCM(SCH_1):TP_GF_B62
 B63 TP_GF_B63 PCIE_HPM_TXN_1 @SCM_LIB.SCM(SCH_1):TP_GF_B63
 B64    GND GND_B64 @SCM_LIB.SCM(SCH_1):GND
 B65 P2E_GPU_TX_C_DP PCIE_HPM_TXP_2 @SCM_LIB.SCM(SCH_1):P2E_GPU_TX_C_DP
 B66 P2E_GPU_TX_C_DN PCIE_HPM_TXN_2 @SCM_LIB.SCM(SCH_1):P2E_GPU_TX_C_DN
 B67    GND GND_B67 @SCM_LIB.SCM(SCH_1):GND
 B68 HDD_LED_R_N PCIE_HPM_TXP_3 @SCM_LIB.SCM(SCH_1):HDD_LED_R_N
 B69 PCH_BEEP_R_LED PCIE_HPM_TXN_3 @SCM_LIB.SCM(SCH_1):PCH_BEEP_R_LED
 B70    GND GND_B70 @SCM_LIB.SCM(SCH_1):GND

Q_RES_0402LF-33.2,1%,1/16W,CHIA  I557  R455
   1 SMB_BMC_MM2_SCL      A @SCM_LIB.SCM(SCH_1):SMB_BMC_MM2_SCL
   2 SMB_BMC_MM2_SCL_R1      B @SCM_LIB.SCM(SCH_1):SMB_BMC_MM2_SCL_R1

Q_RES_0402LF-0,5%,1/16W,EMPTY,A  I562  R564
   1 HDD_LED_N      A @SCM_LIB.SCM(SCH_1):HDD_LED_N
   2 HDD_LED_R_N      B @SCM_LIB.SCM(SCH_1):HDD_LED_R_N

Q_RES_0402LF-0,5%,1/16W,EMPTY,A  I565  R811
   1 PCH_BEEP_LED      A @SCM_LIB.SCM(SCH_1):PCH_BEEP_LED
   2 PCH_BEEP_R_LED      B @SCM_LIB.SCM(SCH_1):PCH_BEEP_R_LED

Q_RES_0402LF-0,5%,1/16W,CHIP,CA  I568  R838
   1 HDD_LED_N      A @SCM_LIB.SCM(SCH_1):HDD_LED_N
   2 FM_HDD_LED_N      B @SCM_LIB.SCM(SCH_1):FM_HDD_LED_N

Q_RES_0402LF-0,5%,1/16W,CHIP,CA  I569  R847
   1 PCH_BEEP_LED      A @SCM_LIB.SCM(SCH_1):PCH_BEEP_LED
   2 FM_PCH_BEEP_LED      B @SCM_LIB.SCM(SCH_1):FM_PCH_BEEP_LED

Q_CAP_C0805-22UF,16V,20%,X6S,CA  I573  C329
   1 P12V_AUX      A @SCM_LIB.SCM(SCH_1):P12V_AUX
   2    GND      B @SCM_LIB.SCM(SCH_1):GND

Q_CAP_C0805-22UF,16V,20%,X6S,CA  I574  C330
   1 P12V_AUX      A @SCM_LIB.SCM(SCH_1):P12V_AUX
   2    GND      B @SCM_LIB.SCM(SCH_1):GND


DRAWING: @SCM_LIB.SCM(SCH_1):PAGE11 

Q_RES_0402LF-2K,1%,1/16W,CHIP,A  I110  R75
   1 P3V3_AUX      A @SCM_LIB.SCM(SCH_1):P3V3_AUX
   2 SGPIO_DO_1      B @SCM_LIB.SCM(SCH_1):SGPIO_DO_1

Q_RES_0402LF-2K,1%,1/16W,CHIP,A  I117  R74
   1 P3V3_AUX      A @SCM_LIB.SCM(SCH_1):P3V3_AUX
   2 SGPIO_DI_1      B @SCM_LIB.SCM(SCH_1):SGPIO_DI_1

Q_RES_0402LF-1K,1%,1/16W,EMPTYA  I118  R73
   1 P3V3_AUX      A @SCM_LIB.SCM(SCH_1):P3V3_AUX
   2 SGPIO_LD_1      B @SCM_LIB.SCM(SCH_1):SGPIO_LD_1

Q_RES_0402LF-1K,1%,1/16W,EMPTYA  I128  R77
   1 P3V3_AUX      A @SCM_LIB.SCM(SCH_1):P3V3_AUX
   2 SGPIO_LD_0      B @SCM_LIB.SCM(SCH_1):SGPIO_LD_0

Q_RES_0402LF-2K,1%,1/16W,CHIP,A  I129  R78
   1 P3V3_AUX      A @SCM_LIB.SCM(SCH_1):P3V3_AUX
   2 SGPIO_DI_0      B @SCM_LIB.SCM(SCH_1):SGPIO_DI_0

Q_RES_0402LF-2K,1%,1/16W,CHIP,A  I130  R79
   1 P3V3_AUX      A @SCM_LIB.SCM(SCH_1):P3V3_AUX
   2 SGPIO_DO_0      B @SCM_LIB.SCM(SCH_1):SGPIO_DO_0

Q_RES_0402LF-2K,1%,1/16W,EMPTYA  I171  R40
   1    GND      A @SCM_LIB.SCM(SCH_1):GND
   2 PWRGD_SYS_PWROK      B @SCM_LIB.SCM(SCH_1):PWRGD_SYS_PWROK

Q_RES_0402LF-4.7K,1%,1/16W,EMPA  I175  R44
   1 P3V3_AUX      A @SCM_LIB.SCM(SCH_1):P3V3_AUX
   2 SYS_PWRBTN_N      B @SCM_LIB.SCM(SCH_1):SYS_PWRBTN_N

Q_RES_0402LF-4.7K,1%,1/16W,CHIA  I176  R45
   1 P3V3_AUX      A @SCM_LIB.SCM(SCH_1):P3V3_AUX
   2 FM_THROTTLE_N      B @SCM_LIB.SCM(SCH_1):FM_THROTTLE_N

Q_RES_0402LF-4.7K,1%,1/16W,CHIA  I179  R68
   1 P3V3_AUX      A @SCM_LIB.SCM(SCH_1):P3V3_AUX
   2 IRQ_SGPIO_N      B @SCM_LIB.SCM(SCH_1):IRQ_SGPIO_N

Q_RES_0402LF-100K,1%,1/16W,CHIA  I181  R66
   1    GND      A @SCM_LIB.SCM(SCH_1):GND
   2 PWRGD_PSU_AC_PWROK      B @SCM_LIB.SCM(SCH_1):PWRGD_PSU_AC_PWROK

Q_RES_0402LF-4.7K,1%,1/16W,EMPA  I194  R34
   1 P3V3_RGM      A @SCM_LIB.SCM(SCH_1):P3V3_RGM
   2 RST_PLTRST_N      B @SCM_LIB.SCM(SCH_1):RST_PLTRST_N

Q_RES_0402LF-4.7K,1%,1/16W,CHIA  I212  R163
   1 P3V3_AUX      A @SCM_LIB.SCM(SCH_1):P3V3_AUX
   2 FM_CPU_MSMI_CATERR_LVT3_N      B @SCM_LIB.SCM(SCH_1):FM_CPU_MSMI_CATERR_LVT3_N

Q_RES_0402LF-4.7K,1%,1/16W,CHIA  I214  R101
   1 P3V3_AUX      A @SCM_LIB.SCM(SCH_1):P3V3_AUX
   2 RMII_RXER      B @SCM_LIB.SCM(SCH_1):RMII_RXER

Q_RES_0402LF-4.7K,1%,1/16W,CHIA  I218  R161
   1 P3V3_AUX      A @SCM_LIB.SCM(SCH_1):P3V3_AUX
   2 RMII_CSRDV      B @SCM_LIB.SCM(SCH_1):RMII_CSRDV

Q_RES_0402LF-4.7K,1%,1/16W,CHIA  I219  R103
   1 P3V3_AUX      A @SCM_LIB.SCM(SCH_1):P3V3_AUX
   2 RMII_TXEN      B @SCM_LIB.SCM(SCH_1):RMII_TXEN

Q_RES_0402LF-10K,1%,1/16W,EMPTA  I225  R41
   1 P3V3_AUX      A @SCM_LIB.SCM(SCH_1):P3V3_AUX
   2 LPC_ESPI_SEL      B @SCM_LIB.SCM(SCH_1):LPC_ESPI_SEL

Q_RES_0402LF-4.7K,1%,1/16W,CHIA  I227  R69
   1 P3V3_AUX      A @SCM_LIB.SCM(SCH_1):P3V3_AUX
   2 RST_SGPIO_RESET_N      B @SCM_LIB.SCM(SCH_1):RST_SGPIO_RESET_N

Q_RES_0402LF-2K,1%,1/16W,CHIP,A  I230  R76
   1 P3V3_AUX      A @SCM_LIB.SCM(SCH_1):P3V3_AUX
   2 SGPIO_CLK_1      B @SCM_LIB.SCM(SCH_1):SGPIO_CLK_1

Q_RES_0402LF-0,5%,1/16W,EMPTY,A  I231  R63
   1 SGPIO_CLK_1      A @SCM_LIB.SCM(SCH_1):SGPIO_CLK_1
   2    GND      B @SCM_LIB.SCM(SCH_1):GND

Q_RES_0402LF-2K,1%,1/16W,CHIP,A  I232  R82
   1 P3V3_AUX      A @SCM_LIB.SCM(SCH_1):P3V3_AUX
   2 SGPIO_CLK_0      B @SCM_LIB.SCM(SCH_1):SGPIO_CLK_0

Q_RES_0402LF-0,5%,1/16W,EMPTY,A  I233  R64
   1 SGPIO_CLK_0      A @SCM_LIB.SCM(SCH_1):SGPIO_CLK_0
   2    GND      B @SCM_LIB.SCM(SCH_1):GND

Q_RES_0402LF-100K,1%,1/16W,CHIA  I234  R823
   1    GND      A @SCM_LIB.SCM(SCH_1):GND
   2 FM_VIRTUAL_RESEAT      B @SCM_LIB.SCM(SCH_1):FM_VIRTUAL_RESEAT

Q_RES_0402LF-4.7K,1%,1/16W,EMPA  I241  R828
   1 P3V3_AUX      A @SCM_LIB.SCM(SCH_1):P3V3_AUX
   2 RST_ROT_CPU_N      B @SCM_LIB.SCM(SCH_1):RST_ROT_CPU_N

Q_RES_0402LF-4.7K,1%,1/16W,CHIA  I245  R81
   1 P3V3_AUX      A @SCM_LIB.SCM(SCH_1):P3V3_AUX
   2 PWR_BTN_BMC_N      B @SCM_LIB.SCM(SCH_1):PWR_BTN_BMC_N

Q_RES_0402LF-4.7K,1%,1/16W,CHIA  I256  R169
   1 P3V3_AUX      A @SCM_LIB.SCM(SCH_1):P3V3_AUX
   2 RST_PCA9548_SENSOR_N      B @SCM_LIB.SCM(SCH_1):RST_PCA9548_SENSOR_N


DRAWING: @SCM_LIB.SCM(SCH_1):PAGE12 

Q_RES_0402LF-4.7K,1%,1/16W,EMPA  I2  R117
   1 PGPPA_BMC_AUX      A @SCM_LIB.SCM(SCH_1):PGPPA_BMC_AUX
   2 RST_BMC_LPC_ESPI_N      B @SCM_LIB.SCM(SCH_1):RST_BMC_LPC_ESPI_N

Q_RES_0402LF-4.7K,1%,1/16W,CHIA  I3  R116
   1 PGPPA_BMC_AUX      A @SCM_LIB.SCM(SCH_1):PGPPA_BMC_AUX
   2 IRQ_BMC_LPC_SERIRQ_ESPI_GF      B @SCM_LIB.SCM(SCH_1):IRQ_BMC_LPC_SERIRQ_ESPI_GF

Q_RES_0402LF-4.7K,1%,1/16W,EMPA  I4  R115
   1 PGPPA_BMC_AUX      A @SCM_LIB.SCM(SCH_1):PGPPA_BMC_AUX
   2 ESPI_HOST_LPC_BMC_LFRAME_N      B @SCM_LIB.SCM(SCH_1):ESPI_HOST_LPC_BMC_LFRAME_N

Q_CAP_C0402-0.01UF,50V,10%,EMPA  I24  C21
   1 P0V6_DDR_VREF_AUX      A @SCM_LIB.SCM(SCH_1):P0V6_DDR_VREF_AUX
   2    GND      B @SCM_LIB.SCM(SCH_1):GND

Q_CAP_0402-0.1UF,25V,10%,X7R,CA  I28  C23
   1 P0V6_DDR_VREF_AUX      A @SCM_LIB.SCM(SCH_1):P0V6_DDR_VREF_AUX
   2    GND      B @SCM_LIB.SCM(SCH_1):GND

Q_RES_0402LF-33.2,1%,1/16W,CHIA  I33  R120
   1 RST_BMC_LPC_ESPI_N      A @SCM_LIB.SCM(SCH_1):RST_BMC_LPC_ESPI_N
   2 RST_ESPI_LPC_BMC_N      B @SCM_LIB.SCM(SCH_1):RST_ESPI_LPC_BMC_N

Q_RES_0402LF-33.2,1%,1/16W,CHIA  I34  R119
   1 IRQ_BMC_LPC_SERIRQ_ESPI_GF      A @SCM_LIB.SCM(SCH_1):IRQ_BMC_LPC_SERIRQ_ESPI_GF
   2 IRQ_ESPI_LPC_SERIRQ_ALERT0_N      B @SCM_LIB.SCM(SCH_1):IRQ_ESPI_LPC_SERIRQ_ALERT0_N

Q_RES_0402LF-240,1%,1/16W,CHIPA  I46  R127
   1    GND      A @SCM_LIB.SCM(SCH_1):GND
   2 IBMC_MIOZ      B @SCM_LIB.SCM(SCH_1):IBMC_MIOZ

Q_RES_0402LF-100K,1%,1/16W,CHIA  I53  R118
   1    GND      A @SCM_LIB.SCM(SCH_1):GND
   2 RST_PLTRST_N      B @SCM_LIB.SCM(SCH_1):RST_PLTRST_N

Q_RES_0402LF-33.2,1%,1/16W,CHIA  I88  R142
   1 SMB_BMC_MM6_R_SCL      A @SCM_LIB.SCM(SCH_1):SMB_BMC_MM6_R_SCL
   2 SMB_BMC_MM6_SCL      B @SCM_LIB.SCM(SCH_1):SMB_BMC_MM6_SCL

Q_RES_0402LF-33.2,1%,1/16W,CHIA  I89  R143
   1 SMB_BMC_MM6_R_SDA      A @SCM_LIB.SCM(SCH_1):SMB_BMC_MM6_R_SDA
   2 SMB_BMC_MM6_SDA      B @SCM_LIB.SCM(SCH_1):SMB_BMC_MM6_SDA

Q_RES_0402LF-33.2,1%,1/16W,CHIA  I97  R133
   1 SMB_BMC_MM1_R_SDA      A @SCM_LIB.SCM(SCH_1):SMB_BMC_MM1_R_SDA
   2 SMB_BMC_MM1_SDA      B @SCM_LIB.SCM(SCH_1):SMB_BMC_MM1_SDA

Q_RES_0402LF-33.2,1%,1/16W,CHIA  I98  R132
   1 SMB_BMC_MM1_R_SCL      A @SCM_LIB.SCM(SCH_1):SMB_BMC_MM1_R_SCL
   2 SMB_BMC_MM1_SCL      B @SCM_LIB.SCM(SCH_1):SMB_BMC_MM1_SCL

Q_CAP_0402-0.1UF,25V,10%,X7R,CA  I152  C24
   1 P2E_PCH_TX_DP      A @SCM_LIB.SCM(SCH_1):P2E_PCH_TX_DP
   2 P2E_PCH_TX_C_DP      B @SCM_LIB.SCM(SCH_1):P2E_PCH_TX_C_DP

Q_CAP_0402-0.1UF,25V,10%,X7R,CA  I153  C25
   1 P2E_PCH_TX_DN      A @SCM_LIB.SCM(SCH_1):P2E_PCH_TX_DN
   2 P2E_PCH_TX_C_DN      B @SCM_LIB.SCM(SCH_1):P2E_PCH_TX_C_DN

Q_RES_0402LF-33.2,1%,1/16W,CHIA  I235  R146
   1 SMB_BMC_MM8_R_SCL      A @SCM_LIB.SCM(SCH_1):SMB_BMC_MM8_R_SCL
   2 SMB_BMC_MM8_SCL      B @SCM_LIB.SCM(SCH_1):SMB_BMC_MM8_SCL

Q_RES_0402LF-33.2,1%,1/16W,CHIA  I236  R147
   1 SMB_BMC_MM8_R_SDA      A @SCM_LIB.SCM(SCH_1):SMB_BMC_MM8_R_SDA
   2 SMB_BMC_MM8_SDA      B @SCM_LIB.SCM(SCH_1):SMB_BMC_MM8_SDA

Q_RES_0402LF-33.2,1%,1/16W,CHIA  I244  R236
   1 SMB_BMC_MM15_SDA      A @SCM_LIB.SCM(SCH_1):SMB_BMC_MM15_SDA
   2 SMB_BMC_MM15_R_SDA      B @SCM_LIB.SCM(SCH_1):SMB_BMC_MM15_R_SDA

Q_RES_0402LF-33.2,1%,1/16W,CHIA  I245  R162
   1 SMB_BMC_MM15_SCL      A @SCM_LIB.SCM(SCH_1):SMB_BMC_MM15_SCL
   2 SMB_BMC_MM15_R_SCL      B @SCM_LIB.SCM(SCH_1):SMB_BMC_MM15_R_SCL

Q_RES_0402LF-33.2,1%,1/16W,CHIA  I248  R153
   1 SMB_BMC_MM16_SDA      A @SCM_LIB.SCM(SCH_1):SMB_BMC_MM16_SDA
   2 SMB_BMC_MM16_R_SDA      B @SCM_LIB.SCM(SCH_1):SMB_BMC_MM16_R_SDA

Q_RES_0402LF-33.2,1%,1/16W,CHIA  I249  R152
   1 SMB_BMC_MM16_SCL      A @SCM_LIB.SCM(SCH_1):SMB_BMC_MM16_SCL
   2 SMB_BMC_MM16_R_SCL      B @SCM_LIB.SCM(SCH_1):SMB_BMC_MM16_R_SCL

Q_RES_0402LF-33.2,1%,1/16W,CHIA  I252  R423
   1 SMB_BMC_MM13_R_SCL      A @SCM_LIB.SCM(SCH_1):SMB_BMC_MM13_R_SCL
   2 SMB_BMC_MM13_SCL      B @SCM_LIB.SCM(SCH_1):SMB_BMC_MM13_SCL

Q_RES_0402LF-33.2,1%,1/16W,CHIA  I253  R424
   1 SMB_BMC_MM13_R_SDA      A @SCM_LIB.SCM(SCH_1):SMB_BMC_MM13_R_SDA
   2 SMB_BMC_MM13_SDA      B @SCM_LIB.SCM(SCH_1):SMB_BMC_MM13_SDA

Q_RES_0402LF-33.2,1%,1/16W,CHIA  I254  R425
   1 SMB_BMC_MM14_R_SCL      A @SCM_LIB.SCM(SCH_1):SMB_BMC_MM14_R_SCL
   2 SMB_BMC_MM14_SCL      B @SCM_LIB.SCM(SCH_1):SMB_BMC_MM14_SCL

Q_RES_0402LF-33.2,1%,1/16W,CHIA  I255  R426
   1 SMB_BMC_MM14_R_SDA      A @SCM_LIB.SCM(SCH_1):SMB_BMC_MM14_R_SDA
   2 SMB_BMC_MM14_SDA      B @SCM_LIB.SCM(SCH_1):SMB_BMC_MM14_SDA

Q_RES_0402LF-33.2,1%,1/16W,CHIA  I268  R168
   1 RST_PLTRST_N      A @SCM_LIB.SCM(SCH_1):RST_PLTRST_N
   2 RST_PLTRST_R_N      B @SCM_LIB.SCM(SCH_1):RST_PLTRST_R_N

Q_RES_0402LF-33.2,1%,1/16W,CHIA  I274  R567
   1 SMB_BMC_MM7_R_SCL      A @SCM_LIB.SCM(SCH_1):SMB_BMC_MM7_R_SCL
   2 SMB_BMC_MM7_SCL      B @SCM_LIB.SCM(SCH_1):SMB_BMC_MM7_SCL

Q_RES_0402LF-33.2,1%,1/16W,CHIA  I275  R570
   1 SMB_BMC_MM7_R_SDA      A @SCM_LIB.SCM(SCH_1):SMB_BMC_MM7_R_SDA
   2 SMB_BMC_MM7_SDA      B @SCM_LIB.SCM(SCH_1):SMB_BMC_MM7_SDA

Q_RES_0402LF-33.2,1%,1/16W,CHIA  I276  R93
   1 SMB_BMC_MM5_R_SDA      A @SCM_LIB.SCM(SCH_1):SMB_BMC_MM5_R_SDA
   2 SMB_BMC_MM5_SDA      B @SCM_LIB.SCM(SCH_1):SMB_BMC_MM5_SDA

Q_RES_0402LF-33.2,1%,1/16W,CHIA  I277  R71
   1 SMB_BMC_MM5_R_SCL      A @SCM_LIB.SCM(SCH_1):SMB_BMC_MM5_R_SCL
   2 SMB_BMC_MM5_SCL      B @SCM_LIB.SCM(SCH_1):SMB_BMC_MM5_SCL

Q_RES_0402LF-33.2,1%,1/16W,CHIA  I314  R394
   1 SMB_BMC_MM2_R_SDA      A @SCM_LIB.SCM(SCH_1):SMB_BMC_MM2_R_SDA
   2 SMB_BMC_MM2_SDA      B @SCM_LIB.SCM(SCH_1):SMB_BMC_MM2_SDA

Q_RES_0402LF-33.2,1%,1/16W,CHIA  I315  R165
   1 SMB_BMC_MM2_R_SCL      A @SCM_LIB.SCM(SCH_1):SMB_BMC_MM2_R_SCL
   2 SMB_BMC_MM2_SCL      B @SCM_LIB.SCM(SCH_1):SMB_BMC_MM2_SCL

Q_RES_0402LF-33.2,1%,1/16W,CHIA  I316  R589
   1 SMB_BMC_MM3_R_SCL      A @SCM_LIB.SCM(SCH_1):SMB_BMC_MM3_R_SCL
   2 SMB_BMC_MM3_SCL      B @SCM_LIB.SCM(SCH_1):SMB_BMC_MM3_SCL

Q_RES_0402LF-33.2,1%,1/16W,CHIA  I317  R590
   1 SMB_BMC_MM3_R_SDA      A @SCM_LIB.SCM(SCH_1):SMB_BMC_MM3_R_SDA
   2 SMB_BMC_MM3_SDA      B @SCM_LIB.SCM(SCH_1):SMB_BMC_MM3_SDA

Q_RES_0402LF-33.2,1%,1/16W,CHIA  I318  R582
   1 SMB_BMC_MM9_R_SDA      A @SCM_LIB.SCM(SCH_1):SMB_BMC_MM9_R_SDA
   2 SMB_BMC_MM9_SDA      B @SCM_LIB.SCM(SCH_1):SMB_BMC_MM9_SDA

Q_RES_0402LF-33.2,1%,1/16W,CHIA  I319  R583
   1 SMB_BMC_MM10_R_SCL      A @SCM_LIB.SCM(SCH_1):SMB_BMC_MM10_R_SCL
   2 SMB_BMC_MM10_SCL      B @SCM_LIB.SCM(SCH_1):SMB_BMC_MM10_SCL

Q_RES_0402LF-33.2,1%,1/16W,CHIA  I320  R584
   1 SMB_BMC_MM10_R_SDA      A @SCM_LIB.SCM(SCH_1):SMB_BMC_MM10_R_SDA
   2 SMB_BMC_MM10_SDA      B @SCM_LIB.SCM(SCH_1):SMB_BMC_MM10_SDA

Q_RES_0402LF-33.2,1%,1/16W,CHIA  I321  R580
   1 SMB_BMC_MM9_R_SCL      A @SCM_LIB.SCM(SCH_1):SMB_BMC_MM9_R_SCL
   2 SMB_BMC_MM9_SCL      B @SCM_LIB.SCM(SCH_1):SMB_BMC_MM9_SCL

Q_RES_0402LF-4.7K,1%,1/16W,CHIA  I350  R62
   1 P3V3_AUX      A @SCM_LIB.SCM(SCH_1):P3V3_AUX
   2 FM_PCH_BMC_THERMTRIP_N      B @SCM_LIB.SCM(SCH_1):FM_PCH_BMC_THERMTRIP_N

Q_RES_0402LF-33.2,1%,1/16W,CHIA  I353  R705
   1 FM_BMC_DBP_PRESENT_N      A @SCM_LIB.SCM(SCH_1):FM_BMC_DBP_PRESENT_N
   2 FM_BMC_DBP_PRESENT_R_N      B @SCM_LIB.SCM(SCH_1):FM_BMC_DBP_PRESENT_R_N

Q_RES_0402LF-4.7K,1%,1/16W,CHIA  I354  R706
   1 P3V3_AUX      A @SCM_LIB.SCM(SCH_1):P3V3_AUX
   2 FM_BMC_DBP_PRESENT_N      B @SCM_LIB.SCM(SCH_1):FM_BMC_DBP_PRESENT_N

Q_RES_0402LF-33.2,1%,1/16W,CHIA  I379  R148
   1 SGPIO_CLK_1      A @SCM_LIB.SCM(SCH_1):SGPIO_CLK_1
   2 SGPIO_BMC_M1_CLK      B @SCM_LIB.SCM(SCH_1):SGPIO_BMC_M1_CLK

Q_RES_0402LF-33.2,1%,1/16W,CHIA  I380  R150
   1 SGPIO_LD_1      A @SCM_LIB.SCM(SCH_1):SGPIO_LD_1
   2 SGPIO_BMC_M1_LD      B @SCM_LIB.SCM(SCH_1):SGPIO_BMC_M1_LD

Q_RES_0402LF-33.2,1%,1/16W,CHIA  I381  R151
   1 SGPIO_DO_1      A @SCM_LIB.SCM(SCH_1):SGPIO_DO_1
   2 SGPIO_BMC_M1_DO      B @SCM_LIB.SCM(SCH_1):SGPIO_BMC_M1_DO

Q_RES_0402LF-33.2,1%,1/16W,CHIA  I382  R433
   1 SGPIO_DI_1      A @SCM_LIB.SCM(SCH_1):SGPIO_DI_1
   2 SGPIO_BMC_M1_DI      B @SCM_LIB.SCM(SCH_1):SGPIO_BMC_M1_DI

Q_RES_0402LF-33.2,1%,1/16W,CHIA  I385  R137
   1 SMB_BMC_MM12_R_SCL      A @SCM_LIB.SCM(SCH_1):SMB_BMC_MM12_R_SCL
   2 SMB_BMC_MM12_SCL      B @SCM_LIB.SCM(SCH_1):SMB_BMC_MM12_SCL

Q_RES_0402LF-33.2,1%,1/16W,CHIA  I386  R144
   1 SMB_BMC_MM12_R_SDA      A @SCM_LIB.SCM(SCH_1):SMB_BMC_MM12_R_SDA
   2 SMB_BMC_MM12_SDA      B @SCM_LIB.SCM(SCH_1):SMB_BMC_MM12_SDA

Q_RES_0402LF-100K,1%,1/16W,EMPA  I390  R820
   1 SMB_BMC_MM14_R_SDA      A @SCM_LIB.SCM(SCH_1):SMB_BMC_MM14_R_SDA
   2    GND      B @SCM_LIB.SCM(SCH_1):GND

Q_RES_0402LF-100K,1%,1/16W,EMPA  I391  R819
   1 SMB_BMC_MM14_R_SCL      A @SCM_LIB.SCM(SCH_1):SMB_BMC_MM14_R_SCL
   2    GND      B @SCM_LIB.SCM(SCH_1):GND

Q_RES_0402LF-100K,1%,1/16W,EMPA  I392  R818
   1 SMB_BMC_MM13_R_SDA      A @SCM_LIB.SCM(SCH_1):SMB_BMC_MM13_R_SDA
   2    GND      B @SCM_LIB.SCM(SCH_1):GND

Q_RES_0402LF-100K,1%,1/16W,EMPA  I393  R817
   1 SMB_BMC_MM13_R_SCL      A @SCM_LIB.SCM(SCH_1):SMB_BMC_MM13_R_SCL
   2    GND      B @SCM_LIB.SCM(SCH_1):GND

Q_CAP_0402-0.1UF,25V,10%,X7R,CA  I428  C272
   1 P2E_GPU_TX_DP      A @SCM_LIB.SCM(SCH_1):P2E_GPU_TX_DP
   2 P2E_GPU_TX_C_DP      B @SCM_LIB.SCM(SCH_1):P2E_GPU_TX_C_DP

Q_CAP_0402-0.1UF,25V,10%,X7R,CA  I429  C271
   1 P2E_GPU_TX_DN      A @SCM_LIB.SCM(SCH_1):P2E_GPU_TX_DN
   2 P2E_GPU_TX_C_DN      B @SCM_LIB.SCM(SCH_1):P2E_GPU_TX_C_DN

AST2600A3GP-AST2600A3-GP,SMLF,A  I436  U5
  T5 P0V6_DDR_VREF_AUX MVREF_T5 @SCM_LIB.SCM(SCH_1):P0V6_DDR_VREF_AUX
  P5 IBMC_MIOZ   MIOZ @SCM_LIB.SCM(SCH_1):IBMC_MIOZ
  L3 M_BMC_DDR4_RST_N MRESET# @SCM_LIB.SCM(SCH_1):M_BMC_DDR4_RST_N
  N4 M_BMC_DDR4_ALERT_N MALERT# @SCM_LIB.SCM(SCH_1):M_BMC_DDR4_ALERT_N
  T3 M_BMC_DDR4_DQ<0>   MDQ0 @SCM_LIB.SCM(SCH_1):M_BMC_DDR4_DQ(0)
  R4 M_BMC_DDR4_DQ<1>   MDQ1 @SCM_LIB.SCM(SCH_1):M_BMC_DDR4_DQ(1)
  U1 M_BMC_DDR4_DQ<2>   MDQ2 @SCM_LIB.SCM(SCH_1):M_BMC_DDR4_DQ(2)
  R3 M_BMC_DDR4_DQ<3>   MDQ3 @SCM_LIB.SCM(SCH_1):M_BMC_DDR4_DQ(3)
  R1 M_BMC_DDR4_DQ<4>   MDQ4 @SCM_LIB.SCM(SCH_1):M_BMC_DDR4_DQ(4)
  P1 M_BMC_DDR4_DQ<5>   MDQ5 @SCM_LIB.SCM(SCH_1):M_BMC_DDR4_DQ(5)
  P2 M_BMC_DDR4_DQ<6>   MDQ6 @SCM_LIB.SCM(SCH_1):M_BMC_DDR4_DQ(6)
  P3 M_BMC_DDR4_DQ<7>   MDQ7 @SCM_LIB.SCM(SCH_1):M_BMC_DDR4_DQ(7)
  W2 M_BMC_DDR4_DQ<8>   MDQ8 @SCM_LIB.SCM(SCH_1):M_BMC_DDR4_DQ(8)
  V3 M_BMC_DDR4_DQ<9>   MDQ9 @SCM_LIB.SCM(SCH_1):M_BMC_DDR4_DQ(9)
  W1 M_BMC_DDR4_DQ<10>  MDQ10 @SCM_LIB.SCM(SCH_1):M_BMC_DDR4_DQ(10)
  W3 M_BMC_DDR4_DQ<11>  MDQ11 @SCM_LIB.SCM(SCH_1):M_BMC_DDR4_DQ(11)
  W4 M_BMC_DDR4_DQ<12>  MDQ12 @SCM_LIB.SCM(SCH_1):M_BMC_DDR4_DQ(12)
  U4 M_BMC_DDR4_DQ<13>  MDQ13 @SCM_LIB.SCM(SCH_1):M_BMC_DDR4_DQ(13)
  V4 M_BMC_DDR4_DQ<14>  MDQ14 @SCM_LIB.SCM(SCH_1):M_BMC_DDR4_DQ(14)
  U3 M_BMC_DDR4_DQ<15>  MDQ15 @SCM_LIB.SCM(SCH_1):M_BMC_DDR4_DQ(15)
  T2 M_BMC_DDR4_DQS0_P  MDQS0 @SCM_LIB.SCM(SCH_1):M_BMC_DDR4_DQS0_P
  V2 M_BMC_DDR4_DQS1_P  MDQS1 @SCM_LIB.SCM(SCH_1):M_BMC_DDR4_DQS1_P
  T1 M_BMC_DDR4_DQS0_N MDQS0# @SCM_LIB.SCM(SCH_1):M_BMC_DDR4_DQS0_N
  V1 M_BMC_DDR4_DQS1_N MDQS1# @SCM_LIB.SCM(SCH_1):M_BMC_DDR4_DQS1_N
 AE7 ESPI_HOST_LPC_BMC_CLK_R GPIOW4||LCLK||ESPICK @SCM_LIB.SCM(SCH_1):ESPI_HOST_LPC_BMC_CLK_R
 AF7 ESPI_HOST_LPC_BMC_LFRAME_N_R GPIOW5||LFRAME#||ESPICS# @SCM_LIB.SCM(SCH_1):ESPI_HOST_LPC_BMC_LFRAME_N_R
 AD7 IRQ_ESPI_LPC_SERIRQ_ALERT0_N GPIOW6||LSIRQ#||ESPIALT# @SCM_LIB.SCM(SCH_1):IRQ_ESPI_LPC_SERIRQ_ALERT0_N
 AD8 RST_ESPI_LPC_BMC_N GPIOW7||LPCRST#||ESPIRST# @SCM_LIB.SCM(SCH_1):RST_ESPI_LPC_BMC_N
 D22 BMC_EMMC_CLK GPIOF0||SD1CLK||PWM8 @SCM_LIB.SCM(SCH_1):BMC_EMMC_CLK
 E22 BMC_EMMC_CMD GPIOF1||SD1CMD||PWM9 @SCM_LIB.SCM(SCH_1):BMC_EMMC_CMD
 D23 BMC_EMMC_DT0 GPIOF2||SD1DAT0||PWM10 @SCM_LIB.SCM(SCH_1):BMC_EMMC_DT0
 C23 BMC_EMMC_DT1 GPIOF3||SD1DAT1||PWM11 @SCM_LIB.SCM(SCH_1):BMC_EMMC_DT1
 C22 BMC_EMMC_DT2 GPIOF4||SD1DAT2||PWM12 @SCM_LIB.SCM(SCH_1):BMC_EMMC_DT2
 A25 BMC_EMMC_DT3 GPIOF5||SD1DAT3||PWM13 @SCM_LIB.SCM(SCH_1):BMC_EMMC_DT3
 A24 BMC_EMMC_CD_N GPIOF6||SD1CD#||PWM14 @SCM_LIB.SCM(SCH_1):BMC_EMMC_CD_N
 A23 BMC_EMMC_WP_N GPIOF7||SD1WP#||PWM15 @SCM_LIB.SCM(SCH_1):BMC_EMMC_WP_N
 E21 UART_6_BMC_R_TXD GPIOG0||TXD6||SD2CLK||SALT9 @SCM_LIB.SCM(SCH_1):UART_6_BMC_R_TXD
 B22 UART_6_BMC_R_RXD GPIOG1||RXD6||SD2CMD||SALT10 @SCM_LIB.SCM(SCH_1):UART_6_BMC_R_RXD
 C21 BMC_EMMC_DT4 GPIOG2||TXD7||SD2DAT0||SALT11 @SCM_LIB.SCM(SCH_1):BMC_EMMC_DT4
 A22 BMC_EMMC_DT5 GPIOG3||RXD7||SD2DAT1||SALT12 @SCM_LIB.SCM(SCH_1):BMC_EMMC_DT5
 A21 BMC_EMMC_DT6 GPIOG4||TXD8||SD2DAT2||SALT13 @SCM_LIB.SCM(SCH_1):BMC_EMMC_DT6
 E20 BMC_EMMC_DT7 GPIOG5||RXD8||SD2DAT3||SALT14 @SCM_LIB.SCM(SCH_1):BMC_EMMC_DT7
 D21 SMB_BMC_ALERT15_N GPIOG6||TXD9||SD2CD#||SALT15 @SCM_LIB.SCM(SCH_1):SMB_BMC_ALERT15_N
 B21 FM_BMC_DBP_PRESENT_R_N GPIOG7||RXD9||SD2WP#||SALT16 @SCM_LIB.SCM(SCH_1):FM_BMC_DBP_PRESENT_R_N
 AE4 P2E_PCH_TX_DP  PETXP @SCM_LIB.SCM(SCH_1):P2E_PCH_TX_DP
 AE5 P2E_PCH_TX_DN  PETXN @SCM_LIB.SCM(SCH_1):P2E_PCH_TX_DN
  A7 RST_PLTRST_N PERST# @SCM_LIB.SCM(SCH_1):RST_PLTRST_N
 AD5 CLK_100M_PCH_DP PEREFCLKP @SCM_LIB.SCM(SCH_1):CLK_100M_PCH_DP
 AD6 CLK_100M_PCH_DN PEREFCLKN @SCM_LIB.SCM(SCH_1):CLK_100M_PCH_DN
 AF5 P2E_PCH_RX_DP  PERXP @SCM_LIB.SCM(SCH_1):P2E_PCH_RX_DP
 AF6 P2E_PCH_RX_DN  PERXN @SCM_LIB.SCM(SCH_1):P2E_PCH_RX_DN
  U5 P0V6_DDR_VREF_AUX MVREF_U5 @SCM_LIB.SCM(SCH_1):P0V6_DDR_VREF_AUX
  K1 M_BMC_DDR4_MCLK_DN   MCK# @SCM_LIB.SCM(SCH_1):M_BMC_DDR4_MCLK_DN
  H5 M_BMC_DDR4_MBA1   MBA1 @SCM_LIB.SCM(SCH_1):M_BMC_DDR4_MBA1
  H3 M_BMC_DDR4_MA<3>    MA3 @SCM_LIB.SCM(SCH_1):M_BMC_DDR4_MA(3)
  H1 M_BMC_DDR4_MACT_N MA14||MACT# @SCM_LIB.SCM(SCH_1):M_BMC_DDR4_MACT_N
  G3 M_BMC_DDR4_MBG0 MBA2||MBG0 @SCM_LIB.SCM(SCH_1):M_BMC_DDR4_MBG0
 E19 SMB_BMC_MM2_R_SCL GPIOJ2||HVI3C4SCL||SCL2 @SCM_LIB.SCM(SCH_1):SMB_BMC_MM2_R_SCL
  F3 M_BMC_DDR4_MA<0>    MA0 @SCM_LIB.SCM(SCH_1):M_BMC_DDR4_MA(0)
  K3 M_BMC_DDR4_MA<13>   MA13 @SCM_LIB.SCM(SCH_1):M_BMC_DDR4_MA(13)
 E13 SMB_BMC_MM6_R_SDA GPIOK3||SDA6 @SCM_LIB.SCM(SCH_1):SMB_BMC_MM6_R_SDA
  G4 M_BMC_DDR4_MBA0   MBA0 @SCM_LIB.SCM(SCH_1):M_BMC_DDR4_MBA0
  G1 M_BMC_DDR4_MA<11>   MA11 @SCM_LIB.SCM(SCH_1):M_BMC_DDR4_MA(11)
  N3 M_BMC_DDR4_MDM0   MDM0 @SCM_LIB.SCM(SCH_1):M_BMC_DDR4_MDM0
 D19 SMB_BMC_MM4_R_SDA GPIOJ7||HVI3C6SDA||SDA4 @SCM_LIB.SCM(SCH_1):SMB_BMC_MM4_R_SDA
  M5 M_BMC_DDR4_MA<6>    MA6 @SCM_LIB.SCM(SCH_1):M_BMC_DDR4_MA(6)
  L1 M_BMC_DDR4_MA<5>    MA5 @SCM_LIB.SCM(SCH_1):M_BMC_DDR4_MA(5)
  H2 M_BMC_DDR4_MCS_N   MCS# @SCM_LIB.SCM(SCH_1):M_BMC_DDR4_MCS_N
  M1 M_BMC_DDR4_MA<8>    MA8 @SCM_LIB.SCM(SCH_1):M_BMC_DDR4_MA(8)
  L4 M_BMC_DDR4_MA<12>   MA12 @SCM_LIB.SCM(SCH_1):M_BMC_DDR4_MA(12)
  R5 M_BMC_DDR4_MDM1   MDM1 @SCM_LIB.SCM(SCH_1):M_BMC_DDR4_MDM1
 E11 SMB_BMC_MM7_R_SDA GPIOK5||SDA7 @SCM_LIB.SCM(SCH_1):SMB_BMC_MM7_R_SDA
  M3 M_BMC_DDR4_MBG1 MA15||MBG1 @SCM_LIB.SCM(SCH_1):M_BMC_DDR4_MBG1
 B20 SMB_BMC_MM1_R_SCL GPIOJ0||HVI3C3SCL||SCL1 @SCM_LIB.SCM(SCH_1):SMB_BMC_MM1_R_SCL
 F13 SMB_BMC_MM8_R_SCL GPIOK6||SCL8 @SCM_LIB.SCM(SCH_1):SMB_BMC_MM8_R_SCL
  F2 M_BMC_DDR4_MA<10>   MA10 @SCM_LIB.SCM(SCH_1):M_BMC_DDR4_MA(10)
  J5 M_BMC_DDR4_MRAS_N  MRAS# @SCM_LIB.SCM(SCH_1):M_BMC_DDR4_MRAS_N
  J3 M_BMC_DDR4_MA<4>    MA4 @SCM_LIB.SCM(SCH_1):M_BMC_DDR4_MA(4)
 D11 SMB_BMC_MM7_R_SCL GPIOK4||SCL7 @SCM_LIB.SCM(SCH_1):SMB_BMC_MM7_R_SCL
  N1 M_BMC_DDR4_MA<9>    MA9 @SCM_LIB.SCM(SCH_1):M_BMC_DDR4_MA(9)
 C19 SMB_BMC_MM3_R_SCL GPIOJ4||HVI3C5SCL||SCL3 @SCM_LIB.SCM(SCH_1):SMB_BMC_MM3_R_SCL
  K5 M_BMC_DDR4_MA<1>    MA1 @SCM_LIB.SCM(SCH_1):M_BMC_DDR4_MA(1)
 D12 SMB_BMC_MM6_R_SCL GPIOK2||SCL6 @SCM_LIB.SCM(SCH_1):SMB_BMC_MM6_R_SCL
 D20 SMB_BMC_MM2_R_SDA GPIOJ3||HVI3C4SDA||SDA2 @SCM_LIB.SCM(SCH_1):SMB_BMC_MM2_R_SDA
  J4 M_BMC_DDR4_MCAS_N  MCAS# @SCM_LIB.SCM(SCH_1):M_BMC_DDR4_MCAS_N
 AB7 ESPI_LPC_D0_IO0 GPIOW0||LAD0||ESPID0 @SCM_LIB.SCM(SCH_1):ESPI_LPC_D0_IO0
  K2 M_BMC_DDR4_MCLK_DP    MCK @SCM_LIB.SCM(SCH_1):M_BMC_DDR4_MCLK_DP
  F1 M_BMC_DDR4_MA<2>    MA2 @SCM_LIB.SCM(SCH_1):M_BMC_DDR4_MA(2)
  G5 M_BMC_DDR4_MWE_N   MWE# @SCM_LIB.SCM(SCH_1):M_BMC_DDR4_MWE_N
 C20 SMB_BMC_MM4_R_SCL GPIOJ6||HVI3C6SCL||SCL4 @SCM_LIB.SCM(SCH_1):SMB_BMC_MM4_R_SCL
  M2 M_BMC_DDR4_MA<7>    MA7 @SCM_LIB.SCM(SCH_1):M_BMC_DDR4_MA(7)
 A11 SMB_BMC_MM5_R_SCL GPIOK0||SCL5 @SCM_LIB.SCM(SCH_1):SMB_BMC_MM5_R_SCL
  J1 M_BMC_DDR4_MODT   MODT @SCM_LIB.SCM(SCH_1):M_BMC_DDR4_MODT
 AC7 ESPI_LPC_D3_IO3 GPIOW3||LAD3||ESPID3 @SCM_LIB.SCM(SCH_1):ESPI_LPC_D3_IO3
 A20 SMB_BMC_MM1_R_SDA GPIOJ1||HVI3C3SDA||SDA1 @SCM_LIB.SCM(SCH_1):SMB_BMC_MM1_R_SDA
 AC8 ESPI_LPC_D2_IO2 GPIOW2||LAD2||ESPID2 @SCM_LIB.SCM(SCH_1):ESPI_LPC_D2_IO2
 A19 SMB_BMC_MM3_R_SDA GPIOJ5||HVI3C5SDA||SDA3 @SCM_LIB.SCM(SCH_1):SMB_BMC_MM3_R_SDA
 AB8 ESPI_LPC_D1_IO1 GPIOW1||LAD1||ESPID1 @SCM_LIB.SCM(SCH_1):ESPI_LPC_D1_IO1
  L5 M_BMC_DDR4_MCKE   MCKE @SCM_LIB.SCM(SCH_1):M_BMC_DDR4_MCKE
 C11 SMB_BMC_MM5_R_SDA GPIOK1||SDA5 @SCM_LIB.SCM(SCH_1):SMB_BMC_MM5_R_SDA
 E12 SMB_BMC_MM8_R_SDA GPIOK7||SDA8 @SCM_LIB.SCM(SCH_1):SMB_BMC_MM8_R_SDA
 AE1 CLK_100M_GPU_DP RCREFCLKP @SCM_LIB.SCM(SCH_1):CLK_100M_GPU_DP
 AE2 CLK_100M_GPU_DN RCREFCLKN @SCM_LIB.SCM(SCH_1):CLK_100M_GPU_DN
 AD2 P2E_GPU_RX_DP  RCRXP @SCM_LIB.SCM(SCH_1):P2E_GPU_RX_DP
 AD3 P2E_GPU_RX_DN  RCRXN @SCM_LIB.SCM(SCH_1):P2E_GPU_RX_DN
 AF2 P2E_GPU_TX_DN  RCTXP @SCM_LIB.SCM(SCH_1):P2E_GPU_TX_DN
 AF3 P2E_GPU_TX_DP  RCTXN @SCM_LIB.SCM(SCH_1):P2E_GPU_TX_DP
 AC1 NC_DP_BMC_TX0_P DPTXP0 @SCM_LIB.SCM(SCH_1):NC_DP_BMC_TX0_P
 AB1 NC_DP_BMC_TX0_N DPTXN0 @SCM_LIB.SCM(SCH_1):NC_DP_BMC_TX0_N
 AC3 NC_DP_BMC_AUX_P DPAUXP @SCM_LIB.SCM(SCH_1):NC_DP_BMC_AUX_P
 AB3 NC_DP_BMC_AUX_N DPAUXN @SCM_LIB.SCM(SCH_1):NC_DP_BMC_AUX_N
  C7 DP_BMC_HPD_3V3_BUF  DPHPD @SCM_LIB.SCM(SCH_1):DP_BMC_HPD_3V3_BUF
 AB2 NC_DP_BMC_TX1_P DPTXP1 @SCM_LIB.SCM(SCH_1):NC_DP_BMC_TX1_P
 AA2 NC_DP_BMC_TX1_N DPTXN1 @SCM_LIB.SCM(SCH_1):NC_DP_BMC_TX1_N
 D15 SMB_BMC_MM9_R_SCL GPIOL0||SCL9 @SCM_LIB.SCM(SCH_1):SMB_BMC_MM9_R_SCL
 A14 SMB_BMC_MM9_R_SDA GPIOL1||SDA9 @SCM_LIB.SCM(SCH_1):SMB_BMC_MM9_R_SDA
 E15 SMB_BMC_MM10_R_SCL GPIOL2||SCL10 @SCM_LIB.SCM(SCH_1):SMB_BMC_MM10_R_SCL
 A13 SMB_BMC_MM10_R_SDA GPIOL3||SDA10 @SCM_LIB.SCM(SCH_1):SMB_BMC_MM10_R_SDA
 M24 FM_PFR_DSW_PWROK_N GPIOA0||SCL11||MDC3 @SCM_LIB.SCM(SCH_1):FM_PFR_DSW_PWROK_N
 M25 RST_PFR_OVR_RTC_R GPIOA1||SDA11||MDIO3 @SCM_LIB.SCM(SCH_1):RST_PFR_OVR_RTC_R
 L26 SMB_BMC_MM12_R_SCL GPIOA2||SCL12||MDC4 @SCM_LIB.SCM(SCH_1):SMB_BMC_MM12_R_SCL
 K24 SMB_BMC_MM12_R_SDA GPIOA3||SDA12||MDIO4 @SCM_LIB.SCM(SCH_1):SMB_BMC_MM12_R_SDA
 L23 SMB_BMC_MM14_R_SCL GPIOA6||MAC3LINK||SCL14||SGPM2O||SGPS2I0 @SCM_LIB.SCM(SCH_1):SMB_BMC_MM14_R_SCL
 K25 SMB_BMC_MM14_R_SDA GPIOA7||MAC4LINK||SDA14||SGPM2I||SGPS2I1 @SCM_LIB.SCM(SCH_1):SMB_BMC_MM14_R_SDA
 K26 SMB_BMC_MM13_R_SCL GPIOA4||MAC1LINK||SCL13||SGPM2CK||SGPS2CK @SCM_LIB.SCM(SCH_1):SMB_BMC_MM13_R_SCL
 L24 SMB_BMC_MM13_R_SDA GPIOA5||MAC2LINK||SDA13||SGPM2LD||SGPS2LD @SCM_LIB.SCM(SCH_1):SMB_BMC_MM13_R_SDA
 A18 SGPIO_BMC_M1_CLK GPIOH0||SGPM1CK @SCM_LIB.SCM(SCH_1):SGPIO_BMC_M1_CLK
 B18 SGPIO_BMC_M1_LD GPIOH1||SGPM1LD @SCM_LIB.SCM(SCH_1):SGPIO_BMC_M1_LD
 C18 SGPIO_BMC_M1_DO GPIOH2||SGPM1O @SCM_LIB.SCM(SCH_1):SGPIO_BMC_M1_DO
 A17 SGPIO_BMC_M1_DI GPIOH3||SGPM1I @SCM_LIB.SCM(SCH_1):SGPIO_BMC_M1_DI
 D18 SMB_BMC_MM15_R_SCL GPIOH4||SGPS1CK||SCL15 @SCM_LIB.SCM(SCH_1):SMB_BMC_MM15_R_SCL
 B17 SMB_BMC_MM15_R_SDA GPIOH5||SGPS1LD||SDA15 @SCM_LIB.SCM(SCH_1):SMB_BMC_MM15_R_SDA
 C17 SMB_BMC_MM16_R_SCL GPIOH6||SGPS1I0||SCL16 @SCM_LIB.SCM(SCH_1):SMB_BMC_MM16_R_SCL
 E18 SMB_BMC_MM16_R_SDA GPIOH7||SGPS1I1||SDA16 @SCM_LIB.SCM(SCH_1):SMB_BMC_MM16_R_SDA
 T26 FM_THERMTRIP_DLY_LVC1_R_N GPIOS2||PEWAKE# @SCM_LIB.SCM(SCH_1):FM_THERMTRIP_DLY_LVC1_R_N
 R24 FM_TPM_PRSNT_1_N GPIOS3||OSCCLK @SCM_LIB.SCM(SCH_1):FM_TPM_PRSNT_1_N

Q_RES_0402LF-33.2,1%,1/16W,CHIA  I441  R310
   1 ESPI_HOST_LPC_BMC_CLK      A @SCM_LIB.SCM(SCH_1):ESPI_HOST_LPC_BMC_CLK
   2 ESPI_HOST_LPC_BMC_CLK_R      B @SCM_LIB.SCM(SCH_1):ESPI_HOST_LPC_BMC_CLK_R

Q_RES_0402LF-22,1%,1/16W,CHIP,A  I442  R128
   1 ESPI_LPC_D0_IO0      A @SCM_LIB.SCM(SCH_1):ESPI_LPC_D0_IO0
   2 ESPI_LPC_LAD0_IO0      B @SCM_LIB.SCM(SCH_1):ESPI_LPC_LAD0_IO0

Q_RES_0402LF-22,1%,1/16W,CHIP,A  I443  R131
   1 ESPI_LPC_D3_IO3      A @SCM_LIB.SCM(SCH_1):ESPI_LPC_D3_IO3
   2 ESPI_LPC_LAD3_IO3      B @SCM_LIB.SCM(SCH_1):ESPI_LPC_LAD3_IO3

Q_RES_0402LF-22,1%,1/16W,CHIP,A  I444  R130
   1 ESPI_LPC_D2_IO2      A @SCM_LIB.SCM(SCH_1):ESPI_LPC_D2_IO2
   2 ESPI_LPC_LAD2_IO2      B @SCM_LIB.SCM(SCH_1):ESPI_LPC_LAD2_IO2

Q_RES_0402LF-22,1%,1/16W,CHIP,A  I445  R129
   1 ESPI_LPC_D1_IO1      A @SCM_LIB.SCM(SCH_1):ESPI_LPC_D1_IO1
   2 ESPI_LPC_LAD1_IO1      B @SCM_LIB.SCM(SCH_1):ESPI_LPC_LAD1_IO1

Q_RES_0402LF-33.2,1%,1/16W,CHIA  I447  R311
   1 ESPI_HOST_LPC_BMC_LFRAME_N      A @SCM_LIB.SCM(SCH_1):ESPI_HOST_LPC_BMC_LFRAME_N
   2 ESPI_HOST_LPC_BMC_LFRAME_N_R      B @SCM_LIB.SCM(SCH_1):ESPI_HOST_LPC_BMC_LFRAME_N_R

Q_CAP_0402-0.1UF,25V,10%,X7R,CA  I448  C22
   1 P0V6_DDR_VREF_AUX      A @SCM_LIB.SCM(SCH_1):P0V6_DDR_VREF_AUX
   2    GND      B @SCM_LIB.SCM(SCH_1):GND

Q_RES_0402LF-4.7K,1%,1/16W,EMPA  I454  R400
   1 P3V3_AUX      A @SCM_LIB.SCM(SCH_1):P3V3_AUX
   2 FM_THERMTRIP_DLY_LVC1_R_N      B @SCM_LIB.SCM(SCH_1):FM_THERMTRIP_DLY_LVC1_R_N

Q_RES_0402LF-47K,1%,1/16W,CHIPA  I456  R312
   1 RST_BMC_LPC_ESPI_N      A @SCM_LIB.SCM(SCH_1):RST_BMC_LPC_ESPI_N
   2    GND      B @SCM_LIB.SCM(SCH_1):GND

Q_RES_0402LF-33.2,1%,1/16W,CHIA  I458  R880
   1 SMB_BMC_MM16_R5_SDA      A @SCM_LIB.SCM(SCH_1):SMB_BMC_MM16_R5_SDA
   2 SMB_BMC_MM16_SDA      B @SCM_LIB.SCM(SCH_1):SMB_BMC_MM16_SDA

Q_RES_0402LF-33.2,1%,1/16W,CHIA  I473  R761
   1 UART_6_BMC_TXD      A @SCM_LIB.SCM(SCH_1):UART_6_BMC_TXD
   2 UART_6_BMC_R_TXD      B @SCM_LIB.SCM(SCH_1):UART_6_BMC_R_TXD

Q_RES_0402LF-33.2,1%,1/16W,CHIA  I474  R762
   1 UART_6_BMC_RXD      A @SCM_LIB.SCM(SCH_1):UART_6_BMC_RXD
   2 UART_6_BMC_R_RXD      B @SCM_LIB.SCM(SCH_1):UART_6_BMC_R_RXD

Q_RES_0402LF-100K,1%,1/16W,CHIA  I508  R387
   1    GND      A @SCM_LIB.SCM(SCH_1):GND
   2 DP_BMC_HPD_3V3_BUF      B @SCM_LIB.SCM(SCH_1):DP_BMC_HPD_3V3_BUF

Q_RES_0402LF-200,1%,1/16W,CHIPA  I510  R879
   1 SMB_BMC_MM16_R5_SCL      A @SCM_LIB.SCM(SCH_1):SMB_BMC_MM16_R5_SCL
   2 SMB_BMC_MM16_SCL      B @SCM_LIB.SCM(SCH_1):SMB_BMC_MM16_SCL

Q_RES_0402LF-33.2,1%,1/16W,CHIA  I512  R139
   1 SMB_BMC_MM4_R_SDA      A @SCM_LIB.SCM(SCH_1):SMB_BMC_MM4_R_SDA
   2 SMB_BMC_MM4_SDA      B @SCM_LIB.SCM(SCH_1):SMB_BMC_MM4_SDA

Q_RES_0402LF-40.2,1%,1/16W,CHIA  I513  R138
   1 SMB_BMC_MM4_R_SCL      A @SCM_LIB.SCM(SCH_1):SMB_BMC_MM4_R_SCL
   2 SMB_BMC_MM4_SCL      B @SCM_LIB.SCM(SCH_1):SMB_BMC_MM4_SCL


DRAWING: @SCM_LIB.SCM(SCH_1):PAGE13 

Q_RES_0402LF-0,5%,1/16W,EMPTY,A  I3  R154
   1 P1V8_AUX      A @SCM_LIB.SCM(SCH_1):P1V8_AUX
   2 P3V3_P2V5_P1V8_RVDD      B @SCM_LIB.SCM(SCH_1):P3V3_P2V5_P1V8_RVDD

Q_RES_0402LF-0,5%,1/16W,EMPTY,A  I4  R156
   1 P2V5_AUX      A @SCM_LIB.SCM(SCH_1):P2V5_AUX
   2 P3V3_P2V5_P1V8_RVDD      B @SCM_LIB.SCM(SCH_1):P3V3_P2V5_P1V8_RVDD

Q_RES_0402LF-0,5%,1/16W,CHIP,CA  I5  R155
   1 P3V3_AUX      A @SCM_LIB.SCM(SCH_1):P3V3_AUX
   2 P3V3_P2V5_P1V8_RVDD      B @SCM_LIB.SCM(SCH_1):P3V3_P2V5_P1V8_RVDD

Q_RES_0402LF-33.2,1%,1/16W,CHIA  I16  R158
   1 FM_DBP_CPU_PREQ_GF_R_N      A @SCM_LIB.SCM(SCH_1):FM_DBP_CPU_PREQ_GF_R_N
   2 FM_DBP_CPU_PREQ_GF_N      B @SCM_LIB.SCM(SCH_1):FM_DBP_CPU_PREQ_GF_N

Q_RES_0402LF-33.2,1%,1/16W,CHIA  I17  R159
   1 FM_JTAG_TCK_MUX_BMC_SEL      A @SCM_LIB.SCM(SCH_1):FM_JTAG_TCK_MUX_BMC_SEL
   2 FM_JTAG_TCK_MUX_BMC_SEL_R1      B @SCM_LIB.SCM(SCH_1):FM_JTAG_TCK_MUX_BMC_SEL_R1

Q_RES_0402LF-33.2,1%,1/16W,CHIA  I18  R157
   1 UART_BMC_1_TXD_R      A @SCM_LIB.SCM(SCH_1):UART_BMC_1_TXD_R
   2 UART_BMC_1_TXD      B @SCM_LIB.SCM(SCH_1):UART_BMC_1_TXD

Q_CAP_C0402-1UF,25V,10%,X6S,CHA  I29  C30
   1 P3V3_P2V5_P1V8_RVDD      A @SCM_LIB.SCM(SCH_1):P3V3_P2V5_P1V8_RVDD
   2    GND      B @SCM_LIB.SCM(SCH_1):GND

Q_CAP_0402-0.1UF,25V,10%,X7R,CA  I30  C31
   1 P3V3_P2V5_P1V8_RVDD      A @SCM_LIB.SCM(SCH_1):P3V3_P2V5_P1V8_RVDD
   2    GND      B @SCM_LIB.SCM(SCH_1):GND

Q_CAP_C0402-1UF,25V,10%,X6S,CHA  I31  C32
   1 P3V3_P2V5_P1V8_RVDD      A @SCM_LIB.SCM(SCH_1):P3V3_P2V5_P1V8_RVDD
   2    GND      B @SCM_LIB.SCM(SCH_1):GND

Q_CAP_0402-0.1UF,25V,10%,X7R,CA  I32  C33
   1 P3V3_P2V5_P1V8_RVDD      A @SCM_LIB.SCM(SCH_1):P3V3_P2V5_P1V8_RVDD
   2    GND      B @SCM_LIB.SCM(SCH_1):GND

Q_RES_0402LF-330,1%,1/16W,CHIPA  I33  R167
   1 P3V3_AUX      A @SCM_LIB.SCM(SCH_1):P3V3_AUX
   2 BMC_HEARTBEAT_R_N      B @SCM_LIB.SCM(SCH_1):BMC_HEARTBEAT_R_N

Q_LED_SMLF-LED_GREEN,19-213/GVA  I46  D8
   A BMC_HEARTBEAT_R_N      A @SCM_LIB.SCM(SCH_1):BMC_HEARTBEAT_R_N
   C BMC_HEARTBEAT_N      C @SCM_LIB.SCM(SCH_1):BMC_HEARTBEAT_N

Q_RES_0402LF-33.2,1%,1/16W,CHIA  I50  R166
   1 IRQ_BMC_CPU_NMI_R      A @SCM_LIB.SCM(SCH_1):IRQ_BMC_CPU_NMI_R
   2 IRQ_BMC_CPU_NMI      B @SCM_LIB.SCM(SCH_1):IRQ_BMC_CPU_NMI

Q_RES_0402LF-33.2,1%,1/16W,CHIA  I67  R170
   1 UART_BMC_5_TXD      A @SCM_LIB.SCM(SCH_1):UART_BMC_5_TXD
   2 UART_BMC_5_TXD_R      B @SCM_LIB.SCM(SCH_1):UART_BMC_5_TXD_R

Q_RES_0402LF-33.2,1%,1/16W,CHIA  I87  R177
   1 H_CPU1_PROCHOT_LVC1_N      A @SCM_LIB.SCM(SCH_1):H_CPU1_PROCHOT_LVC1_N
   2 H_CPU1_PROCHOT_LVC1_R_N      B @SCM_LIB.SCM(SCH_1):H_CPU1_PROCHOT_LVC1_R_N

Q_RES_0402LF-33.2,1%,1/16W,CHIA  I94  R178
   1 SPI_BMC_CLK_R      A @SCM_LIB.SCM(SCH_1):SPI_BMC_CLK_R
   2 SPI_BMC_BOOT_CLK      B @SCM_LIB.SCM(SCH_1):SPI_BMC_BOOT_CLK

Q_RES_0402LF-33.2,1%,1/16W,CHIA  I95  R179
   1 SPI_BMC_MOSI_IO0_R      A @SCM_LIB.SCM(SCH_1):SPI_BMC_MOSI_IO0_R
   2 SPI_BMC_BOOT_MOSI      B @SCM_LIB.SCM(SCH_1):SPI_BMC_BOOT_MOSI

Q_RES_0402LF-33.2,1%,1/16W,CHIA  I96  R180
   1 SPI_BMC_MISO_IO1_R      A @SCM_LIB.SCM(SCH_1):SPI_BMC_MISO_IO1_R
   2 SPI_BMC_BOOT_MISO      B @SCM_LIB.SCM(SCH_1):SPI_BMC_BOOT_MISO

Q_RES_0402LF-33.2,1%,1/16W,CHIA  I133  R37
   1 IRQ_SMI_ACTIVE_GF_N      A @SCM_LIB.SCM(SCH_1):IRQ_SMI_ACTIVE_GF_N
   2 IRQ_SMI_ACTIVE_BMC_N      B @SCM_LIB.SCM(SCH_1):IRQ_SMI_ACTIVE_BMC_N

Q_RES_0402LF-33.2,1%,1/16W,CHIA  I156  R237
   1 FM_DBP_BMC_PRDY_N      A @SCM_LIB.SCM(SCH_1):FM_DBP_BMC_PRDY_N
   2 FM_DBP_BMC_PRDY_R_N      B @SCM_LIB.SCM(SCH_1):FM_DBP_BMC_PRDY_R_N

Q_RES_0402LF-33.2,1%,1/16W,CHIA  I159  R160
   1 RST_RSMRST_N      A @SCM_LIB.SCM(SCH_1):RST_RSMRST_N
   2 RST_RSMRST_R_N      B @SCM_LIB.SCM(SCH_1):RST_RSMRST_R_N

Q_RES_0402LF-4.7K,1%,1/16W,CHIA  I184  R238
   1 P3V3_AUX      A @SCM_LIB.SCM(SCH_1):P3V3_AUX
   2 SPI_BMC_TPM_CS2_R_N      B @SCM_LIB.SCM(SCH_1):SPI_BMC_TPM_CS2_R_N

Q_RES_0402LF-4.7K,1%,1/16W,CHIA  I185  R239
   1 P3V3_AUX      A @SCM_LIB.SCM(SCH_1):P3V3_AUX
   2 PU_BMC_FWSPIABR_N      B @SCM_LIB.SCM(SCH_1):PU_BMC_FWSPIABR_N

Q_RES_0402LF-4.7K,1%,1/16W,CHIA  I186  R241
   1 P3V3_AUX      A @SCM_LIB.SCM(SCH_1):P3V3_AUX
   2 PU_SPI1ABR      B @SCM_LIB.SCM(SCH_1):PU_SPI1ABR

Q_RES_0402LF-4.7K,1%,1/16W,CHIA  I187  R240
   1 P3V3_AUX      A @SCM_LIB.SCM(SCH_1):P3V3_AUX
   2 PU_FWSPIWP_N      B @SCM_LIB.SCM(SCH_1):PU_FWSPIWP_N

Q_RES_0402LF-4.7K,1%,1/16W,CHIA  I188  R683
   1 P3V3_AUX      A @SCM_LIB.SCM(SCH_1):P3V3_AUX
   2 PU_SPI1WP_N      B @SCM_LIB.SCM(SCH_1):PU_SPI1WP_N

Q_RES_0402LF-33.2,1%,1/16W,CHIA  I198  R427
   1 UART_BMC_1_RXD_R      A @SCM_LIB.SCM(SCH_1):UART_BMC_1_RXD_R
   2 UART_BMC_1_RXD      B @SCM_LIB.SCM(SCH_1):UART_BMC_1_RXD

Q_RES_0402LF-4.7K,1%,1/16W,CHIA  I200  R38
   1 P3V3_AUX      A @SCM_LIB.SCM(SCH_1):P3V3_AUX
   2 FM_BMC_SUSACK_N      B @SCM_LIB.SCM(SCH_1):FM_BMC_SUSACK_N

Q_RES_0402LF-4.7K,1%,1/16W,CHIA  I204  R61
   1 P3V3_AUX      A @SCM_LIB.SCM(SCH_1):P3V3_AUX
   2 IRQ_BMC_PCH_NMI_N      B @SCM_LIB.SCM(SCH_1):IRQ_BMC_PCH_NMI_N

Q_RES_0402LF-33.2,1%,1/16W,CHIA  I208  R759
   1 UART_BMC_5_RXD      A @SCM_LIB.SCM(SCH_1):UART_BMC_5_RXD
   2 UART_BMC_5_RXD_R      B @SCM_LIB.SCM(SCH_1):UART_BMC_5_RXD_R

Q_RES_0402LF-4.7K,1%,1/16W,CHIA  I213  R774
   1 P3V3_AUX      A @SCM_LIB.SCM(SCH_1):P3V3_AUX
   2 FM_SLPS3_GF_N      B @SCM_LIB.SCM(SCH_1):FM_SLPS3_GF_N

Q_RES_0402LF-33.2,1%,1/16W,CHIA  I215  R799
   1 SPI_BMC_BIOS_CS0_N      A @SCM_LIB.SCM(SCH_1):SPI_BMC_BIOS_CS0_N
   2 SPI_BMC_BIOS_CS0_R1_N      B @SCM_LIB.SCM(SCH_1):SPI_BMC_BIOS_CS0_R1_N

Q_RES_0402LF-33.2,1%,1/16W,CHIA  I217  R801
   1 SPI_BMC_BOOT_CS0_R_N      A @SCM_LIB.SCM(SCH_1):SPI_BMC_BOOT_CS0_R_N
   2 SPI_BMC_BOOT_CS0_R1_N      B @SCM_LIB.SCM(SCH_1):SPI_BMC_BOOT_CS0_R1_N

Q_RES_0402LF-33.2,1%,1/16W,CHIA  I218  R802
   1 SPI_BMC_BOOT_CS1_R_N      A @SCM_LIB.SCM(SCH_1):SPI_BMC_BOOT_CS1_R_N
   2 SPI_BMC_BOOT_CS1_R1_N      B @SCM_LIB.SCM(SCH_1):SPI_BMC_BOOT_CS1_R1_N

Q_RES_0402LF-4.7K,1%,1/16W,EMPA  I220  R821
   1 P3V3_AUX      A @SCM_LIB.SCM(SCH_1):P3V3_AUX
   2 FM_BMC_ONCTL_R_N      B @SCM_LIB.SCM(SCH_1):FM_BMC_ONCTL_R_N

Q_RES_0402LF-33.2,1%,1/16W,CHIA  I223  R824
   1 FM_VIRTUAL_RESEAT      A @SCM_LIB.SCM(SCH_1):FM_VIRTUAL_RESEAT
   2 FM_VIRTUAL_RESEAT_BMC      B @SCM_LIB.SCM(SCH_1):FM_VIRTUAL_RESEAT_BMC

Q_RES_0402LF-33.2,1%,1/16W,CHIA  I225  R836
   1 PWRGD_PSU_AC_PWROK      A @SCM_LIB.SCM(SCH_1):PWRGD_PSU_AC_PWROK
   2 PWRGD_PSU_AC_PWROK_BMC      B @SCM_LIB.SCM(SCH_1):PWRGD_PSU_AC_PWROK_BMC

Q_RES_0402LF-33.2,1%,1/16W,CHIA  I227  R439
   1 FM_PECI_SEL_N      A @SCM_LIB.SCM(SCH_1):FM_PECI_SEL_N
   2 FM_PECI_SEL_R_N      B @SCM_LIB.SCM(SCH_1):FM_PECI_SEL_R_N

Q_RES_0402LF-33.2,1%,1/16W,EMPA  I239  R678
   1 SPI_BMC_CLK_R      A @SCM_LIB.SCM(SCH_1):SPI_BMC_CLK_R
   2 QSPI_2_PLD_CLK      B @SCM_LIB.SCM(SCH_1):QSPI_2_PLD_CLK

Q_RES_0402LF-33.2,1%,1/16W,EMPA  I245  R681
   1 SPI_BMC_IO2_R      A @SCM_LIB.SCM(SCH_1):SPI_BMC_IO2_R
   2 QSPI_2_PLD_IO2      B @SCM_LIB.SCM(SCH_1):QSPI_2_PLD_IO2

Q_RES_0402LF-33.2,1%,1/16W,EMPA  I246  R682
   1 SPI_BMC_IO3_R      A @SCM_LIB.SCM(SCH_1):SPI_BMC_IO3_R
   2 QSPI_2_PLD_IO3      B @SCM_LIB.SCM(SCH_1):QSPI_2_PLD_IO3

Q_RES_0402LF-33.2,1%,1/16W,EMPA  I247  R679
   1 SPI_BMC_MOSI_IO0_R      A @SCM_LIB.SCM(SCH_1):SPI_BMC_MOSI_IO0_R
   2 QSPI_2_PLD_IO0      B @SCM_LIB.SCM(SCH_1):QSPI_2_PLD_IO0

Q_RES_0402LF-33.2,1%,1/16W,EMPA  I248  R680
   1 SPI_BMC_MISO_IO1_R      A @SCM_LIB.SCM(SCH_1):SPI_BMC_MISO_IO1_R
   2 QSPI_2_PLD_IO1      B @SCM_LIB.SCM(SCH_1):QSPI_2_PLD_IO1

Q_RES_0402LF-33.2,1%,1/16W,CHIA  I266  R111
   1 FM_BMC_READY_R_PLD_N      A @SCM_LIB.SCM(SCH_1):FM_BMC_READY_R_PLD_N
   2 FM_BMC_READY_PLD_N      B @SCM_LIB.SCM(SCH_1):FM_BMC_READY_PLD_N

Q_RES_0402LF-4.7K,1%,1/16W,CHIA  I278  R55
   1 P3V3_AUX      A @SCM_LIB.SCM(SCH_1):P3V3_AUX
   2 FM_BMC_READY_R_PLD_N      B @SCM_LIB.SCM(SCH_1):FM_BMC_READY_R_PLD_N

Q_RES_0402LF-4.7K,1%,1/16W,CHIA  I279  R56
   1 P3V3_AUX      A @SCM_LIB.SCM(SCH_1):P3V3_AUX
   2 FM_BIOS_DEBUG_EN_R_N      B @SCM_LIB.SCM(SCH_1):FM_BIOS_DEBUG_EN_R_N

Q_RES_0402LF-33.2,1%,1/16W,CHIA  I286  R96
   1 BMC_EMMC_RST_R_N      A @SCM_LIB.SCM(SCH_1):BMC_EMMC_RST_R_N
   2 BMC_EMMC_RST_N      B @SCM_LIB.SCM(SCH_1):BMC_EMMC_RST_N

Q_RES_0402LF-33.2,1%,1/16W,CHIA  I295  R840
   1 PWRGD_SYS_PWROK      A @SCM_LIB.SCM(SCH_1):PWRGD_SYS_PWROK
   2 PWRGD_SYS_PWROK_BMC      B @SCM_LIB.SCM(SCH_1):PWRGD_SYS_PWROK_BMC

Q_RES_0402LF-4.7K,1%,1/16W,CHIA  I299  R446
   1 P3V3_AUX      A @SCM_LIB.SCM(SCH_1):P3V3_AUX
   2 FM_PECI_SEL_N      B @SCM_LIB.SCM(SCH_1):FM_PECI_SEL_N

Q_RES_0402LF-33.2,1%,1/16W,CHIA  I300  R443
   1 SMB_BMC_ALERT4_N      A @SCM_LIB.SCM(SCH_1):SMB_BMC_ALERT4_N
   2 SMB_BMC_ALERT4_R_N      B @SCM_LIB.SCM(SCH_1):SMB_BMC_ALERT4_R_N

Q_RES_0402LF-33.2,1%,1/16W,CHIA  I301  R442
   1 SMB_BMC_ALERT3_N      A @SCM_LIB.SCM(SCH_1):SMB_BMC_ALERT3_N
   2 SMB_BMC_ALERT3_R_N      B @SCM_LIB.SCM(SCH_1):SMB_BMC_ALERT3_R_N

Q_RES_0402LF-33.2,1%,1/16W,CHIA  I306  R444
   1 FM_ESPI_PLD_EN      A @SCM_LIB.SCM(SCH_1):FM_ESPI_PLD_EN
   2 FM_ESPI_PLD_R1_EN      B @SCM_LIB.SCM(SCH_1):FM_ESPI_PLD_R1_EN

Q_RES_0402LF-33.2,1%,1/16W,CHIA  I312  R460
   1 SPI_BMC_TPM_CS2_R_N      A @SCM_LIB.SCM(SCH_1):SPI_BMC_TPM_CS2_R_N
   2 SPI_BMC_TPM_CS2_R1_N      B @SCM_LIB.SCM(SCH_1):SPI_BMC_TPM_CS2_R1_N

Q_RES_0402LF-33.2,1%,1/16W,CHIA  I319  R469
   1 SPI_BMC_TPM_MISO_R1      A @SCM_LIB.SCM(SCH_1):SPI_BMC_TPM_MISO_R1
   2 SPI_BMC_TPM_MISO      B @SCM_LIB.SCM(SCH_1):SPI_BMC_TPM_MISO

Q_RES_0402LF-33.2,1%,1/16W,CHIA  I335  R494
   1 RST_BMC_SELF_HW_R1      A @SCM_LIB.SCM(SCH_1):RST_BMC_SELF_HW_R1
   2 RST_BMC_SELF_HW      B @SCM_LIB.SCM(SCH_1):RST_BMC_SELF_HW

Q_RES_0402LF-0,5%,1/16W,CHIP,CA  I337  R637
   1 RST_WDTRST_PLD_R1_N      A @SCM_LIB.SCM(SCH_1):RST_WDTRST_PLD_R1_N
   2 RST_WDTRST_PLD_N      B @SCM_LIB.SCM(SCH_1):RST_WDTRST_PLD_N

Q_RES_0402LF-4.7K,1%,1/16W,CHIA  I339  R452
   1 P3V3_AUX      A @SCM_LIB.SCM(SCH_1):P3V3_AUX
   2 RST_WDTRST_PLD_N      B @SCM_LIB.SCM(SCH_1):RST_WDTRST_PLD_N

Q_RES_0402LF-100K,1%,1/16W,CHIA  I340  R273
   1 PD_CLK_125M_PHY_BMC_RGMII      A @SCM_LIB.SCM(SCH_1):PD_CLK_125M_PHY_BMC_RGMII
   2    GND      B @SCM_LIB.SCM(SCH_1):GND

Q_RES_0402LF-33.2,1%,1/16W,CHIA  I344  R643
   1 PWRGD_DSW_PWROK      A @SCM_LIB.SCM(SCH_1):PWRGD_DSW_PWROK
   2 PWRGD_DSW_PWROK_R1      B @SCM_LIB.SCM(SCH_1):PWRGD_DSW_PWROK_R1

Q_RES_0402LF-33.2,1%,1/16W,CHIA  I349  R407
   1 FM_BMC_SUSACK_R1_N      A @SCM_LIB.SCM(SCH_1):FM_BMC_SUSACK_R1_N
   2 FM_BMC_SUSACK_N      B @SCM_LIB.SCM(SCH_1):FM_BMC_SUSACK_N

Q_RES_0402LF-0,5%,1/16W,CHIP,CA  I350  R722
   1 FM_SLPS3_GF_R1_N      A @SCM_LIB.SCM(SCH_1):FM_SLPS3_GF_R1_N
   2 FM_SLPS3_GF_N      B @SCM_LIB.SCM(SCH_1):FM_SLPS3_GF_N

Q_RES_0402LF-33.2,1%,1/16W,CHIA  I351  R826
   1 IRQ_PCH_SCI_WHEA_R_N      A @SCM_LIB.SCM(SCH_1):IRQ_PCH_SCI_WHEA_R_N
   2 IRQ_PCH_SCI_WHEA_N      B @SCM_LIB.SCM(SCH_1):IRQ_PCH_SCI_WHEA_N

Q_RES_0402LF-4.7K,1%,1/16W,CHIA  I353  R816
   1 P3V3_AUX      A @SCM_LIB.SCM(SCH_1):P3V3_AUX
   2 IRQ_PCH_SCI_WHEA_N      B @SCM_LIB.SCM(SCH_1):IRQ_PCH_SCI_WHEA_N

Q_RES_0402LF-4.7K,1%,1/16W,CHIA  I356  R805
   1 P3V3_AUX      A @SCM_LIB.SCM(SCH_1):P3V3_AUX
   2 BMC_HEARTBEAT_N      B @SCM_LIB.SCM(SCH_1):BMC_HEARTBEAT_N

Q_RES_0402LF-33.2,1%,1/16W,CHIA  I360  R309
   1 SPI_BMC_TPM_MOSI_R1      A @SCM_LIB.SCM(SCH_1):SPI_BMC_TPM_MOSI_R1
   2 SPI_BMC_TPM_MOSI      B @SCM_LIB.SCM(SCH_1):SPI_BMC_TPM_MOSI

AST2600A3GP-AST2600A3-GP,SMLF,A  I363  U5
AB14 SPI_BMC_BOOT_CS0_R1_N FWSPICS0# @SCM_LIB.SCM(SCH_1):SPI_BMC_BOOT_CS0_R1_N
 D14 H_CPU0_PROCHOT_LVC1_N GPIOM0||NCTS1 @SCM_LIB.SCM(SCH_1):H_CPU0_PROCHOT_LVC1_N
 B13 FM_VIRTUAL_RESEAT_BMC GPIOM1||NDCD1 @SCM_LIB.SCM(SCH_1):FM_VIRTUAL_RESEAT_BMC
 A12 PWRGD_PSU_AC_PWROK_BMC GPIOM2||NDSR1 @SCM_LIB.SCM(SCH_1):PWRGD_PSU_AC_PWROK_BMC
 E14 FM_PECI_SEL_R_N GPIOM3||NRI1 @SCM_LIB.SCM(SCH_1):FM_PECI_SEL_R_N
 B12 PWRGD_SYS_PWROK_BMC GPIOM4||NDTR1 @SCM_LIB.SCM(SCH_1):PWRGD_SYS_PWROK_BMC
 C12 FM_DBP_BMC_PRDY_R_N GPIOM5||NRTS1 @SCM_LIB.SCM(SCH_1):FM_DBP_BMC_PRDY_R_N
 C13 UART_BMC_1_TXD GPIOM6||TXD1 @SCM_LIB.SCM(SCH_1):UART_BMC_1_TXD
 D13 UART_BMC_1_RXD GPIOM7||RXD1 @SCM_LIB.SCM(SCH_1):UART_BMC_1_RXD
 P25 LED_POSTCODE_0 GPION0||NCTS2 @SCM_LIB.SCM(SCH_1):LED_POSTCODE_0
 N23 LED_POSTCODE_1 GPION1||NDCD2 @SCM_LIB.SCM(SCH_1):LED_POSTCODE_1
 N25 LED_POSTCODE_2 GPION2||NDSR2 @SCM_LIB.SCM(SCH_1):LED_POSTCODE_2
 N24 LED_POSTCODE_3 GPION3||NRI2 @SCM_LIB.SCM(SCH_1):LED_POSTCODE_3
 P26 LED_POSTCODE_4 GPION4||NDTR2 @SCM_LIB.SCM(SCH_1):LED_POSTCODE_4
 M23 LED_POSTCODE_5 GPION5||NRTS2 @SCM_LIB.SCM(SCH_1):LED_POSTCODE_5
 N26 LED_POSTCODE_6 GPION6||TXD2 @SCM_LIB.SCM(SCH_1):LED_POSTCODE_6
 M26 LED_POSTCODE_7 GPION7||RXD2 @SCM_LIB.SCM(SCH_1):LED_POSTCODE_7
 F15 FM_JTAG_TCK_MUX_BMC_SEL_R1 GPIOL5||RXD3 @SCM_LIB.SCM(SCH_1):FM_JTAG_TCK_MUX_BMC_SEL_R1
 C15 FM_DBP_CPU_PREQ_GF_N GPIOL4||TXD3 @SCM_LIB.SCM(SCH_1):FM_DBP_CPU_PREQ_GF_N
AA13 SPI_BMC_BOOT_CS1_R1_N FWSPICS1# @SCM_LIB.SCM(SCH_1):SPI_BMC_BOOT_CS1_R1_N
AC13 TP_BMC_SPICS2_N FWSPICS2# @SCM_LIB.SCM(SCH_1):TP_BMC_SPICS2_N
AB15 FM_SLPS3_GF_R1_N GPIOV0||SIOS3# @SCM_LIB.SCM(SCH_1):FM_SLPS3_GF_R1_N
AF14 RST_RSMRST_R_N GPIOV1||SIOS5# @SCM_LIB.SCM(SCH_1):RST_RSMRST_R_N
AD14 BMC_ID_BEEP_SEL_R1 GPIOV2||SIOPWREQ# @SCM_LIB.SCM(SCH_1):BMC_ID_BEEP_SEL_R1
AC15 FM_BMC_ONCTL_R_N GPIOV3||SIOONCTRL# @SCM_LIB.SCM(SCH_1):FM_BMC_ONCTL_R_N
AE15 BATTERY_DETECT GPIOV4||SIOPWRGD @SCM_LIB.SCM(SCH_1):BATTERY_DETECT
AE14 FM_BMC_READY_R_PLD_N GPIOV5||LPCPD# @SCM_LIB.SCM(SCH_1):FM_BMC_READY_R_PLD_N
AD15 FM_BMC_SUSACK_R1_N GPIOV6||LPCPME# @SCM_LIB.SCM(SCH_1):FM_BMC_SUSACK_R1_N
AF15 IRQ_TPM_SPI_N GPIOV7||LPCSMI# @SCM_LIB.SCM(SCH_1):IRQ_TPM_SPI_N
AF13 SPI_BMC_CLK_R FWSPICK @SCM_LIB.SCM(SCH_1):SPI_BMC_CLK_R
AC14 SPI_BMC_MOSI_IO0_R FWSPIMOSI @SCM_LIB.SCM(SCH_1):SPI_BMC_MOSI_IO0_R
AB13 SPI_BMC_MISO_IO1_R FWSPIMISO @SCM_LIB.SCM(SCH_1):SPI_BMC_MISO_IO1_R
AF12 SPI_BMC_IO3_R GPIOY5||FWSPIDQ3 @SCM_LIB.SCM(SCH_1):SPI_BMC_IO3_R
AE12 SPI_BMC_IO2_R GPIOY4||FWSPIDQ2 @SCM_LIB.SCM(SCH_1):SPI_BMC_IO2_R
AC12 PU_BMC_FWSPIABR_N_R GPIOY6||FWSPIABR @SCM_LIB.SCM(SCH_1):PU_BMC_FWSPIABR_N_R
AB12 PU_FWSPIWP_N_R GPIOY7||FWSPIWP# @SCM_LIB.SCM(SCH_1):PU_FWSPIWP_N_R
AB11 SPI_BMC_TPM_CLK_R1 GPIOZ3||SPI1CK @SCM_LIB.SCM(SCH_1):SPI_BMC_TPM_CLK_R1
AC11 SPI_BMC_TPM_MOSI_R1 GPIOZ4||SPI1MOSI @SCM_LIB.SCM(SCH_1):SPI_BMC_TPM_MOSI_R1
AA11 SPI_BMC_TPM_MISO_R1 GPIOZ5||SPI1MISO @SCM_LIB.SCM(SCH_1):SPI_BMC_TPM_MISO_R1
AD11 FM_DEBUG_PORT_PRSNT_R1_N GPIOZ6||SPI1DQ2||TXD13 @SCM_LIB.SCM(SCH_1):FM_DEBUG_PORT_PRSNT_R1_N
AF10 CLK_GEN2_BMC_RC_OE_N GPIOZ7||SPI1DQ3||RXD13 @SCM_LIB.SCM(SCH_1):CLK_GEN2_BMC_RC_OE_N
AD13 TP_BMC_SPICS0_N SPI1CS0# @SCM_LIB.SCM(SCH_1):TP_BMC_SPICS0_N
AC10 SPI_BMC_TPM_CS2_R1_N GPIOZ0||SPI1CS1# @SCM_LIB.SCM(SCH_1):SPI_BMC_TPM_CS2_R1_N
AD10 PU_SPI1ABR GPIOZ1||SPI1ABR @SCM_LIB.SCM(SCH_1):PU_SPI1ABR
AE10 PU_SPI1WP_N GPIOZ2||SPI1WP# @SCM_LIB.SCM(SCH_1):PU_SPI1WP_N
 AF8 SPI_BMC_BIOS_ROM_CLK GPIOX3||SPI2CK @SCM_LIB.SCM(SCH_1):SPI_BMC_BIOS_ROM_CLK
 AB9 SPI_BMC_BIOS_ROM_MOSI GPIOX4||SPI2MOSI @SCM_LIB.SCM(SCH_1):SPI_BMC_BIOS_ROM_MOSI
 AD9 SPI_BMC_BIOS_ROM_MISO GPIOX5||SPI2MISO @SCM_LIB.SCM(SCH_1):SPI_BMC_BIOS_ROM_MISO
 AF9 SPI_BMC_BIOS_ROM_IO2 GPIOX6||SPI2DQ2||TXD12 @SCM_LIB.SCM(SCH_1):SPI_BMC_BIOS_ROM_IO2
AB10 SPI_BMC_BIOS_ROM_IO3 GPIOX7||SPI2DQ3||RXD12 @SCM_LIB.SCM(SCH_1):SPI_BMC_BIOS_ROM_IO3
 AE8 SPI_BMC_BIOS_CS0_R1_N GPIOX0||SPI2CS0# @SCM_LIB.SCM(SCH_1):SPI_BMC_BIOS_CS0_R1_N
 AA9 PWRGD_DSW_PWROK_R1 GPIOX1||SPI2CS1# @SCM_LIB.SCM(SCH_1):PWRGD_DSW_PWROK_R1
 AC9 IRQ_SMI_ACTIVE_BMC_N GPIOX2||SPI2CS2# @SCM_LIB.SCM(SCH_1):IRQ_SMI_ACTIVE_BMC_N
 J26 FM_ME_BT_DONE GPIOB0||SALT1 @SCM_LIB.SCM(SCH_1):FM_ME_BT_DONE
 K23 VOL_SEN_ALERT_R GPIOB1||SALT2 @SCM_LIB.SCM(SCH_1):VOL_SEN_ALERT_R
 H26 SMB_BMC_ALERT3_R_N GPIOB2||SALT3 @SCM_LIB.SCM(SCH_1):SMB_BMC_ALERT3_R_N
 J25 SMB_BMC_ALERT4_R_N GPIOB3||SALT4 @SCM_LIB.SCM(SCH_1):SMB_BMC_ALERT4_R_N
 J23 FM_BMC_MUX_CS_SPI_SEL_0 GPIOB4||MDC2 @SCM_LIB.SCM(SCH_1):FM_BMC_MUX_CS_SPI_SEL_0
 G26 FM_ID_LED GPIOB5||MDIO2 @SCM_LIB.SCM(SCH_1):FM_ID_LED
 H25 FM_ESPI_PLD_R1_EN GPIOB6||TXD4 @SCM_LIB.SCM(SCH_1):FM_ESPI_PLD_R1_EN
 J24 IRQ_BMC_CPU_NMI GPIOB7||RXD4 @SCM_LIB.SCM(SCH_1):IRQ_BMC_CPU_NMI
AF11 RST_BMC_SELF_HW_R1 GPIOY0||SALT5||WDTRST1# @SCM_LIB.SCM(SCH_1):RST_BMC_SELF_HW_R1
AD12 RST_WDTRST_PLD_R1_N GPIOY1||SALT6||WDTRST2# @SCM_LIB.SCM(SCH_1):RST_WDTRST_PLD_R1_N
AE11 FM_FLASH_LATCH_N_R1 GPIOY2||SALT7||WDTRST3# @SCM_LIB.SCM(SCH_1):FM_FLASH_LATCH_N_R1
AA12 BMC_EMMC_RST_R_N GPIOY3||SALT8||WDTRST4# @SCM_LIB.SCM(SCH_1):BMC_EMMC_RST_R_N
  C8 UART_BMC_5_TXD   TXD5 @SCM_LIB.SCM(SCH_1):UART_BMC_5_TXD
  D8 UART_BMC_5_RXD   RXD5 @SCM_LIB.SCM(SCH_1):UART_BMC_5_RXD
 G23 FM_JTAG_SEL RGMII3RXCK||RMII3RCLKI||GPIOC6 @SCM_LIB.SCM(SCH_1):FM_JTAG_SEL
 G24 IRQ_SGPIO_BMC_N RGMII3RXCTL||GPIOC7 @SCM_LIB.SCM(SCH_1):IRQ_SGPIO_BMC_N
 F23 GPU_FPGA_RST_N RGMII3RXD0||RMII3RXD0||GPIOD0 @SCM_LIB.SCM(SCH_1):GPU_FPGA_RST_N
 F26 CLK_BUF1_GPU_FPGA_OE_R_N RGMII3RXD1||RMII3RXD1||GPIOD1 @SCM_LIB.SCM(SCH_1):CLK_BUF1_GPU_FPGA_OE_R_N
 F25 FM_BIC_DEBUG_SW_N_R RGMII3RXD2||RMII3CRSDV||GPIOD2 @SCM_LIB.SCM(SCH_1):FM_BIC_DEBUG_SW_N_R
 E26 FM_BMC_CRASHLOG_TRIG_R1_N RGMII3RXD3||RMII3RXER||GPIOD3 @SCM_LIB.SCM(SCH_1):FM_BMC_CRASHLOG_TRIG_R1_N
 C25 RMII_OCP_RCLKI_R_ISO RGMII4RXCK||RMII4RCLKI||NCTS4||GPIOE2 @SCM_LIB.SCM(SCH_1):RMII_OCP_RCLKI_R_ISO
 C26 FM_PLT_BMC_THERMTRIP_N_R RGMII4RXCTL||NDCD4||GPIOE3 @SCM_LIB.SCM(SCH_1):FM_PLT_BMC_THERMTRIP_N_R
 C24 RMII_RXD0 RGMII4RXD0||RMII4RXD0||NDSR4||GPIOE4 @SCM_LIB.SCM(SCH_1):RMII_RXD0
 B26 RMII_RXD1 RGMII4RXD1||RMII4RXD1||NRI4||GPIOE5 @SCM_LIB.SCM(SCH_1):RMII_RXD1
 B25 RMII_CSRDV RGMII4RXD2||RMII4CRSDV||NDTR4||GPIOE6 @SCM_LIB.SCM(SCH_1):RMII_CSRDV
 B24 RMII_RXER RGMII4RXD3||RMII4RXER||NRTS4||GPIOE7 @SCM_LIB.SCM(SCH_1):RMII_RXER
 F24 IRQ_SML0_ALERT_R_N RGMII4TXCK||RMII4RCLKO||NCTS3||GPIOD4 @SCM_LIB.SCM(SCH_1):IRQ_SML0_ALERT_R_N
 E23 RMII_TXEN_R RGMII4TXCTL||RMII4TXEN||NDCD3||GPIOD5 @SCM_LIB.SCM(SCH_1):RMII_TXEN_R
 E24 RMII_TXD0_R RGMII4TXD0||RMII4TXD0||NDSR3||GPIOD6 @SCM_LIB.SCM(SCH_1):RMII_TXD0_R
 E25 RMII_TXD1_R RGMII4TXD1||RMII4TXD1||NRI3||GPIOD7 @SCM_LIB.SCM(SCH_1):RMII_TXD1_R
 D26 PD_BIOS_MUX_EN_R_N RGMII4TXD2||NDTR3||GPIOE0 @SCM_LIB.SCM(SCH_1):PD_BIOS_MUX_EN_R_N
 D24 FM_BIOS_DEBUG_EN_R_N RGMII4TXD3||NRTS3||GPIOE1 @SCM_LIB.SCM(SCH_1):FM_BIOS_DEBUG_EN_R_N
 H24 RST_PLTRST_R_N RGMII3TXCK||RMII3RCLKO||GPIOC0 @SCM_LIB.SCM(SCH_1):RST_PLTRST_R_N
 J22 FM_CPU_RMCA_CATERR_LVT3_R_N RGMII3TXCTL||RMII3TXEN||GPIOC1 @SCM_LIB.SCM(SCH_1):FM_CPU_RMCA_CATERR_LVT3_R_N
 H22 FM_BMC_CPU_FBRK_OUT_N RGMII3TXD0||RMII3TXD0||GPIOC2 @SCM_LIB.SCM(SCH_1):FM_BMC_CPU_FBRK_OUT_N
 H23 RST_SGPIO_RESET_BMC_N RGMII3TXD1||RMII3TXD1||GPIOC3 @SCM_LIB.SCM(SCH_1):RST_SGPIO_RESET_BMC_N
 G22 RST_ROT_CPU_R1_N RGMII3TXD2||GPIOC4 @SCM_LIB.SCM(SCH_1):RST_ROT_CPU_R1_N
 F22 H_CPU_CATERR_LVC2_R2_N RGMII3TXD3||GPIOC5 @SCM_LIB.SCM(SCH_1):H_CPU_CATERR_LVC2_R2_N
 A10 PD_CLK_125M_PHY_BMC_RGMII RGMIICK @SCM_LIB.SCM(SCH_1):PD_CLK_125M_PHY_BMC_RGMII
 R23 IRQ_BMC_PCH_NMI_N GPIOS0||MDC1 @SCM_LIB.SCM(SCH_1):IRQ_BMC_PCH_NMI_N
 T25 BMC_MONITER GPIOS1||MDIO1 @SCM_LIB.SCM(SCH_1):BMC_MONITER
 P24 H_CPU1_PROCHOT_LVC1_N GPIOS5||RXD10 @SCM_LIB.SCM(SCH_1):H_CPU1_PROCHOT_LVC1_N
 P23 RST_PCA9548_SENSOR_R_N GPIOS6||TXD11 @SCM_LIB.SCM(SCH_1):RST_PCA9548_SENSOR_R_N
 T24 BMC_CPLD_GPIO_2_R1 GPIOS7||RXD11 @SCM_LIB.SCM(SCH_1):BMC_CPLD_GPIO_2_R1
 R26 FM_BMC_DEBUG_SW_N GPIOS4||TXD10 @SCM_LIB.SCM(SCH_1):FM_BMC_DEBUG_SW_N
 B16 FM_THROTTLE_N GPIOI6||SIOPBI# @SCM_LIB.SCM(SCH_1):FM_THROTTLE_N
 E16 FLASH_WP_STATUS_R1 GPIOI5||SIOPBO# @SCM_LIB.SCM(SCH_1):FLASH_WP_STATUS_R1
 A15 IRQ_PCH_SCI_WHEA_R_N GPIOI7||SIOSCI# @SCM_LIB.SCM(SCH_1):IRQ_PCH_SCI_WHEA_R_N

Q_RES_0402LF-33.2,1%,1/16W,CHIA  I365  R461
   1 BMC_ID_BEEP_SEL      A @SCM_LIB.SCM(SCH_1):BMC_ID_BEEP_SEL
   2 BMC_ID_BEEP_SEL_R1      B @SCM_LIB.SCM(SCH_1):BMC_ID_BEEP_SEL_R1

Q_RES_0402LF-33.2,1%,1/16W,CHIA  I373  R402
   1 PU_FWSPIWP_N      A @SCM_LIB.SCM(SCH_1):PU_FWSPIWP_N
   2 PU_FWSPIWP_N_R      B @SCM_LIB.SCM(SCH_1):PU_FWSPIWP_N_R

Q_RES_0402LF-33.2,1%,1/16W,CHIA  I374  R401
   1 PU_BMC_FWSPIABR_N      A @SCM_LIB.SCM(SCH_1):PU_BMC_FWSPIABR_N
   2 PU_BMC_FWSPIABR_N_R      B @SCM_LIB.SCM(SCH_1):PU_BMC_FWSPIABR_N_R

Q_RES_0402LF-33.2,1%,1/16W,CHIA  I381  R121
   1 FM_CPU_RMCA_CATERR_LVT3_R_N      A @SCM_LIB.SCM(SCH_1):FM_CPU_RMCA_CATERR_LVT3_R_N
   2 FM_CPU_MSMI_CATERR_LVT3_N      B @SCM_LIB.SCM(SCH_1):FM_CPU_MSMI_CATERR_LVT3_N

Q_RES_0402LF-33.2,1%,1/16W,CHIA  I382  R60
   1 RST_ROT_CPU_R1_N      A @SCM_LIB.SCM(SCH_1):RST_ROT_CPU_R1_N
   2 RST_ROT_CPU_N      B @SCM_LIB.SCM(SCH_1):RST_ROT_CPU_N

Q_RES_0402LF-33.2,1%,1/16W,CHIA  I383  R688
   1 RST_SGPIO_RESET_BMC_N      A @SCM_LIB.SCM(SCH_1):RST_SGPIO_RESET_BMC_N
   2 RST_SGPIO_RESET_N      B @SCM_LIB.SCM(SCH_1):RST_SGPIO_RESET_N

Q_RES_0402LF-33.2,1%,1/16W,CHIA  I384  R242
   1 FM_BMC_CPU_FBRK_OUT_N      A @SCM_LIB.SCM(SCH_1):FM_BMC_CPU_FBRK_OUT_N
   2 FM_BMC_CPU_FBRK_OUT_R_N      B @SCM_LIB.SCM(SCH_1):FM_BMC_CPU_FBRK_OUT_R_N

Q_RES_0402LF-33.2,1%,1/16W,EMPA  I398  R689
   1 IRQ_SGPIO_N      A @SCM_LIB.SCM(SCH_1):IRQ_SGPIO_N
   2 IRQ_SGPIO_BMC_N      B @SCM_LIB.SCM(SCH_1):IRQ_SGPIO_BMC_N

Q_RES_0402LF-33.2,1%,1/16W,CHIA  I399  R122
   1 FM_BIC_DEBUG_SW_N      A @SCM_LIB.SCM(SCH_1):FM_BIC_DEBUG_SW_N
   2 FM_BIC_DEBUG_SW_N_R      B @SCM_LIB.SCM(SCH_1):FM_BIC_DEBUG_SW_N_R

Q_RES_0402LF-33.2,1%,1/16W,CHIA  I400  R760
   1 FM_BMC_CRASHLOG_TRIG_N      A @SCM_LIB.SCM(SCH_1):FM_BMC_CRASHLOG_TRIG_N
   2 FM_BMC_CRASHLOG_TRIG_R1_N      B @SCM_LIB.SCM(SCH_1):FM_BMC_CRASHLOG_TRIG_R1_N

Q_RES_0402LF-33.2,1%,1/16W,CHIA  I402  R763
   1 FM_PCH_BMC_THERMTRIP_N      A @SCM_LIB.SCM(SCH_1):FM_PCH_BMC_THERMTRIP_N
   2 FM_PLT_BMC_THERMTRIP_N_R      B @SCM_LIB.SCM(SCH_1):FM_PLT_BMC_THERMTRIP_N_R

Q_RES_0402LF-33.2,1%,1/16W,CHIA  I407  R458
   1 FM_DEBUG_PORT_PRSNT_R1_N      A @SCM_LIB.SCM(SCH_1):FM_DEBUG_PORT_PRSNT_R1_N
   2 FM_DEBUG_PORT_PRSNT_N      B @SCM_LIB.SCM(SCH_1):FM_DEBUG_PORT_PRSNT_N

Q_RES_0402LF-33.2,1%,1/16W,CHIA  I419  R70
   1 RST_PCA9548_SENSOR_R_N      A @SCM_LIB.SCM(SCH_1):RST_PCA9548_SENSOR_R_N
   2 RST_PCA9548_SENSOR_N      B @SCM_LIB.SCM(SCH_1):RST_PCA9548_SENSOR_N

Q_RES_0402LF-33.2,1%,1/16W,CHIA  I421  R65
   1 BMC_CPLD_GPIO_2_R1      A @SCM_LIB.SCM(SCH_1):BMC_CPLD_GPIO_2_R1
   2 BMC_CPLD_GPIO_2      B @SCM_LIB.SCM(SCH_1):BMC_CPLD_GPIO_2

Q_RES_0402LF-33.2,1%,1/16W,CHIA  I427  R112
   1 FM_BIOS_DEBUG_EN_R_N      A @SCM_LIB.SCM(SCH_1):FM_BIOS_DEBUG_EN_R_N
   2 FM_BIOS_DEBUG_EN_N      B @SCM_LIB.SCM(SCH_1):FM_BIOS_DEBUG_EN_N

Q_RES_0402LF-33.2,1%,1/16W,CHIA  I430  R405
   1 PD_BIOS_MUX_EN_R_N      A @SCM_LIB.SCM(SCH_1):PD_BIOS_MUX_EN_R_N
   2 PD_BIOS_MUX_EN_N      B @SCM_LIB.SCM(SCH_1):PD_BIOS_MUX_EN_N

Q_RES_0402LF-33.2,1%,1/16W,CHIA  I431  R466
   1 FLASH_WP_STATUS_R1      A @SCM_LIB.SCM(SCH_1):FLASH_WP_STATUS_R1
   2 FLASH_WP_STATUS      B @SCM_LIB.SCM(SCH_1):FLASH_WP_STATUS

Q_RES_0402LF-33.2,1%,1/16W,CHIA  I432  R465
   1 FM_FLASH_LATCH_N_R1      A @SCM_LIB.SCM(SCH_1):FM_FLASH_LATCH_N_R1
   2 FM_FLASH_LATCH_N      B @SCM_LIB.SCM(SCH_1):FM_FLASH_LATCH_N

74LVC1G66GV-74LVC1G66GV,SMLF,IA  I435  U28
   1 RMII_OCP_RCLKI      Y @SCM_LIB.SCM(SCH_1):RMII_OCP_RCLKI
   2 RMII_OCP_RCLKI_ISO      Z @SCM_LIB.SCM(SCH_1):RMII_OCP_RCLKI_ISO
   3    GND    GND @SCM_LIB.SCM(SCH_1):GND
   4 PWRGD_P1V0_AUX_DELAY_R      E @SCM_LIB.SCM(SCH_1):PWRGD_P1V0_AUX_DELAY_R
   5 P3V3_LDO    VCC @SCM_LIB.SCM(SCH_1):P3V3_LDO

Q_CAP_0402-0.1UF,25V,10%,X7R,CA  I440  C180
   1 P3V3_LDO      A @SCM_LIB.SCM(SCH_1):P3V3_LDO
   2    GND      B @SCM_LIB.SCM(SCH_1):GND

Q_RES_0402LF-0,5%,1/16W,CHIP,CA  I447  R392
   1 RMII_OCP_RCLKI_ISO      A @SCM_LIB.SCM(SCH_1):RMII_OCP_RCLKI_ISO
   2 RMII_OCP_RCLKI_R_ISO      B @SCM_LIB.SCM(SCH_1):RMII_OCP_RCLKI_R_ISO

Q_RES_0402LF-0,5%,1/16W,CHIP,CA  I448  R395
   1 PWRGD_P1V0_AUX_DELAY_R      A @SCM_LIB.SCM(SCH_1):PWRGD_P1V0_AUX_DELAY_R
   2 PWRGD_P1V0_AUX_DELAY      B @SCM_LIB.SCM(SCH_1):PWRGD_P1V0_AUX_DELAY

Q_RES_0402LF-90.9,1%,1/16W,CHIA  I449  R468
   1 SPI_BMC_TPM_CLK_R1      A @SCM_LIB.SCM(SCH_1):SPI_BMC_TPM_CLK_R1
   2 SPI_BMC_TPM_CLK      B @SCM_LIB.SCM(SCH_1):SPI_BMC_TPM_CLK

Q_RES_0402LF-22,1%,1/16W,CHIP,A  I451  R171
   1 RMII_TXEN_R      A @SCM_LIB.SCM(SCH_1):RMII_TXEN_R
   2 RMII_TXEN      B @SCM_LIB.SCM(SCH_1):RMII_TXEN

Q_RES_0402LF-22,1%,1/16W,CHIP,A  I452  R172
   1 RMII_TXD0_R      A @SCM_LIB.SCM(SCH_1):RMII_TXD0_R
   2 RMII_TXD0      B @SCM_LIB.SCM(SCH_1):RMII_TXD0

Q_RES_0402LF-22,1%,1/16W,CHIP,A  I453  R173
   1 RMII_TXD1_R      A @SCM_LIB.SCM(SCH_1):RMII_TXD1_R
   2 RMII_TXD1      B @SCM_LIB.SCM(SCH_1):RMII_TXD1


DRAWING: @SCM_LIB.SCM(SCH_1):PAGE14 

AST2600A3GP-AST2600A3-GP,SMLF,A  I149  U5
  B3     NC RGMII1RXCK||RMII1RCLKI||GPIO18A6     NC
  A2     NC RGMII1RXCTL||GPIO18A7     NC
  B2     NC RGMII1RXD0||RMII1RXD0||GPIO18B0     NC
  B1     NC RGMII1RXD1||RMII1RXD1||GPIO18B1     NC
  C4     NC RGMII1RXD2||RMII1CRSDV||GPIO18B2     NC
  E5     NC RGMII1RXD3||RMII1RXER||GPIO18B3     NC
  C6 AC_PWR_BMC_BTN_R_N RGMII1TXCK||RMII1RCLKO||GPIO18A0 @SCM_LIB.SCM(SCH_1):AC_PWR_BMC_BTN_R_N
  D6     NC RGMII1TXCTL||RMII1TXEN||GPIO18A1     NC
  D5     NC RGMII1TXD0||RMII1TXD0||GPIO18A2     NC
  A3     NC RGMII1TXD1||RMII1TXD1||GPIO18A3     NC
  C5     NC RGMII1TXD2||GPIO18A4     NC
  E6     NC RGMII1TXD3||GPIO18A5     NC
  D2     NC RGMII2RXCK||RMII2RCLKI||GPIO18C2     NC
  E3     NC RGMII2RXCTL||GPIO18C3     NC
  D1     NC RGMII2RXD0||RMII2RXD0||GPIO18C4     NC
  F4     NC RGMII2RXD1||RMII2RXD1||GPIO18C5     NC
  E2     NC RGMII2RXD2||RMII2CRSDV||GPIO18C6     NC
  E1     NC RGMII2RXD3||RMII2RXER||GPIO18C7     NC
  D4     NC RGMII2TXCK||RMII2RCLKO||GPIO18B4     NC
  C2     NC RGMII2TXCTL||RMII2TXEN||GPIO18B5     NC
  C1     NC RGMII2TXD0||RMII2TXD0||GPIO18B6     NC
  D3 FM_BOARD_BMC_REV_ID0 RGMII2TXD1||RMII2TXD1||GPIO18B7 @SCM_LIB.SCM(SCH_1):FM_BOARD_BMC_REV_ID0
  E4 FM_BOARD_BMC_REV_ID1 RGMII2TXD2||GPIO18C0 @SCM_LIB.SCM(SCH_1):FM_BOARD_BMC_REV_ID1
  F5 FM_BOARD_BMC_REV_ID2 RGMII2TXD3||GPIO18C1 @SCM_LIB.SCM(SCH_1):FM_BOARD_BMC_REV_ID2
 AB4     NC GPIO18D0||EMMCCLK     NC
 AA4     NC GPIO18D1||EMMCCMD     NC
 AC4     NC GPIO18D2||EMMCDAT0     NC
 AA5     NC GPIO18D3||EMMCDAT1     NC
  Y5     NC GPIO18D4||EMMCDAT2     NC
 AB5     NC GPIO18D5||EMMCDAT3     NC
 AC5     NC GPIO18D6||EMMCCD#     NC
 AB6     NC GPIO18D7||EMMCWP#     NC
  Y1     NC GPIO18E0||EMMCDAT4||FWSPI18CS#||VBCS#     NC
  Y2     NC GPIO18E1||EMMCDAT5||FWSPI18CK||VBCK     NC
  Y3     NC GPIO18E2||EMMCDAT6||FWSPI18MOSI||VBMOSI     NC
  Y4     NC GPIO18E3||EMMCDAT7||FWSPI18MISO||VBMISO     NC
AF23 I3C1_SCL_R I3C1SCL @SCM_LIB.SCM(SCH_1):I3C1_SCL_R
AE24 I3C1_SDA_R I3C1SDA @SCM_LIB.SCM(SCH_1):I3C1_SDA_R
AF22 I3C2_SCL_R I3C2SCL @SCM_LIB.SCM(SCH_1):I3C2_SCL_R
AE22 I3C2_SDA_R I3C2SDA @SCM_LIB.SCM(SCH_1):I3C2_SDA_R
AF25 I3C3_SCL_R I3C3SCL||FSI1CLK @SCM_LIB.SCM(SCH_1):I3C3_SCL_R
AE26 I3C3_SDA_R I3C3SDA||FSI1DATA @SCM_LIB.SCM(SCH_1):I3C3_SDA_R
AE25 I3C4_SCL_R I3C4SCL||FSI2CLK @SCM_LIB.SCM(SCH_1):I3C4_SCL_R
AF24 I3C4_SDA_R I3C4SDA||FSI2DATA @SCM_LIB.SCM(SCH_1):I3C4_SDA_R

Q_RES_0402LF-1K,1%,1/16W,EMPTYB  I163  R684
   1 BMC_EMMC_WP_N      A @SCM_LIB.SCM(SCH_1):BMC_EMMC_WP_N
   2    GND      B @SCM_LIB.SCM(SCH_1):GND

Q_RES_0402LF-4.7K,1%,1/16W,EMPB  I164  R686
   1 P3V3_AUX      A @SCM_LIB.SCM(SCH_1):P3V3_AUX
   2 BMC_EMMC_WP_N      B @SCM_LIB.SCM(SCH_1):BMC_EMMC_WP_N

Q_RES_0402LF-1K,1%,1/16W,EMPTYB  I165  R685
   1 BMC_EMMC_CD_N      A @SCM_LIB.SCM(SCH_1):BMC_EMMC_CD_N
   2    GND      B @SCM_LIB.SCM(SCH_1):GND

Q_RES_0402LF-4.7K,1%,1/16W,EMPB  I166  R687
   1 P3V3_AUX      A @SCM_LIB.SCM(SCH_1):P3V3_AUX
   2 BMC_EMMC_CD_N      B @SCM_LIB.SCM(SCH_1):BMC_EMMC_CD_N

Q_RES_0402LF-1K,1%,1/16W,CHIP,A  I171  R194
   1 P1V2_P1V0_I3C_VDDL1      A @SCM_LIB.SCM(SCH_1):P1V2_P1V0_I3C_VDDL1
   2 I3C1_SPD_SCL      B @SCM_LIB.SCM(SCH_1):I3C1_SPD_SCL

Q_RES_0402LF-1K,1%,1/16W,CHIP,A  I172  R195
   1 P1V2_P1V0_I3C_VDDL1      A @SCM_LIB.SCM(SCH_1):P1V2_P1V0_I3C_VDDL1
   2 I3C1_SPD_SDA      B @SCM_LIB.SCM(SCH_1):I3C1_SPD_SDA

Q_RES_0402LF-1K,1%,1/16W,CHIP,A  I173  R190
   1 P1V2_P1V0_I3C_VDDL1      A @SCM_LIB.SCM(SCH_1):P1V2_P1V0_I3C_VDDL1
   2 I3C2_SPD_SCL      B @SCM_LIB.SCM(SCH_1):I3C2_SPD_SCL

Q_RES_0402LF-1K,1%,1/16W,CHIP,A  I174  R191
   1 P1V2_P1V0_I3C_VDDL1      A @SCM_LIB.SCM(SCH_1):P1V2_P1V0_I3C_VDDL1
   2 I3C2_SPD_SDA      B @SCM_LIB.SCM(SCH_1):I3C2_SPD_SDA

Q_RES_0402LF-1K,1%,1/16W,CHIP,A  I183  R188
   1 P1V2_P1V0_I3C_VDDL1      A @SCM_LIB.SCM(SCH_1):P1V2_P1V0_I3C_VDDL1
   2 I3C3_SPD_SCL      B @SCM_LIB.SCM(SCH_1):I3C3_SPD_SCL

Q_RES_0402LF-1K,1%,1/16W,CHIP,A  I188  R189
   1 P1V2_P1V0_I3C_VDDL1      A @SCM_LIB.SCM(SCH_1):P1V2_P1V0_I3C_VDDL1
   2 I3C3_SPD_SDA      B @SCM_LIB.SCM(SCH_1):I3C3_SPD_SDA

Q_RES_0402LF-1K,1%,1/16W,CHIP,A  I189  R196
   1 P1V2_P1V0_I3C_VDDL1      A @SCM_LIB.SCM(SCH_1):P1V2_P1V0_I3C_VDDL1
   2 I3C4_SPD_SCL      B @SCM_LIB.SCM(SCH_1):I3C4_SPD_SCL

Q_RES_0402LF-1K,1%,1/16W,CHIP,A  I190  R197
   1 P1V2_P1V0_I3C_VDDL1      A @SCM_LIB.SCM(SCH_1):P1V2_P1V0_I3C_VDDL1
   2 I3C4_SPD_SDA      B @SCM_LIB.SCM(SCH_1):I3C4_SPD_SDA

Q_RES_0402LF-4.7K,1%,1/16W,CHIA  I220  R856
   1 P1V8_AUX      A @SCM_LIB.SCM(SCH_1):P1V8_AUX
   2 FM_BOARD_BMC_REV_ID1      B @SCM_LIB.SCM(SCH_1):FM_BOARD_BMC_REV_ID1

Q_RES_0402LF-4.7K,1%,1/16W,EMPA  I221  R854
   1 P1V8_AUX      A @SCM_LIB.SCM(SCH_1):P1V8_AUX
   2 FM_BOARD_BMC_REV_ID2      B @SCM_LIB.SCM(SCH_1):FM_BOARD_BMC_REV_ID2

Q_RES_0402LF-4.7K,1%,1/16W,CHIA  I222  R858
   1 P1V8_AUX      A @SCM_LIB.SCM(SCH_1):P1V8_AUX
   2 FM_BOARD_BMC_REV_ID0      B @SCM_LIB.SCM(SCH_1):FM_BOARD_BMC_REV_ID0

Q_RES_0402LF-1K,1%,1/16W,CHIP,A  I223  R855
   1 FM_BOARD_BMC_REV_ID2      A @SCM_LIB.SCM(SCH_1):FM_BOARD_BMC_REV_ID2
   2    GND      B @SCM_LIB.SCM(SCH_1):GND

Q_RES_0402LF-1K,1%,1/16W,EMPTYA  I224  R857
   1 FM_BOARD_BMC_REV_ID1      A @SCM_LIB.SCM(SCH_1):FM_BOARD_BMC_REV_ID1
   2    GND      B @SCM_LIB.SCM(SCH_1):GND

Q_RES_0402LF-1K,1%,1/16W,EMPTYA  I225  R865
   1 FM_BOARD_BMC_REV_ID0      A @SCM_LIB.SCM(SCH_1):FM_BOARD_BMC_REV_ID0
   2    GND      B @SCM_LIB.SCM(SCH_1):GND

Q_RES_0402LF-33.2,1%,1/16W,CHIA  I229  R884
   1 AC_PWR_BMC_BTN_R_N      A @SCM_LIB.SCM(SCH_1):AC_PWR_BMC_BTN_R_N
   2 AC_PWR_BMC_BTN_N      B @SCM_LIB.SCM(SCH_1):AC_PWR_BMC_BTN_N

Q_RES_0402LF-4.7K,1%,1/16W,CHIA  I231  R885
   1 P1V8_AUX      A @SCM_LIB.SCM(SCH_1):P1V8_AUX
   2 AC_PWR_BMC_BTN_N      B @SCM_LIB.SCM(SCH_1):AC_PWR_BMC_BTN_N

Q_RES_0402LF-110,1%,1/16W,CHIPA  I232  R184
   1 I3C1_SPD_SCL      A @SCM_LIB.SCM(SCH_1):I3C1_SPD_SCL
   2 I3C1_SCL_R      B @SCM_LIB.SCM(SCH_1):I3C1_SCL_R

Q_RES_0402LF-110,1%,1/16W,CHIPA  I233  R186
   1 I3C2_SPD_SCL      A @SCM_LIB.SCM(SCH_1):I3C2_SPD_SCL
   2 I3C2_SCL_R      B @SCM_LIB.SCM(SCH_1):I3C2_SCL_R

Q_RES_0402LF-110,1%,1/16W,CHIPA  I234  R198
   1 I3C3_SCL_R      A @SCM_LIB.SCM(SCH_1):I3C3_SCL_R
   2 I3C3_SPD_SCL      B @SCM_LIB.SCM(SCH_1):I3C3_SPD_SCL

Q_RES_0402LF-110,1%,1/16W,CHIPA  I235  R200
   1 I3C4_SCL_R      A @SCM_LIB.SCM(SCH_1):I3C4_SCL_R
   2 I3C4_SPD_SCL      B @SCM_LIB.SCM(SCH_1):I3C4_SPD_SCL

Q_RES_0402LF-33.2,1%,1/16W,CHIA  I236  R185
   1 I3C1_SPD_SDA      A @SCM_LIB.SCM(SCH_1):I3C1_SPD_SDA
   2 I3C1_SDA_R      B @SCM_LIB.SCM(SCH_1):I3C1_SDA_R

Q_RES_0402LF-33.2,1%,1/16W,CHIA  I237  R187
   1 I3C2_SPD_SDA      A @SCM_LIB.SCM(SCH_1):I3C2_SPD_SDA
   2 I3C2_SDA_R      B @SCM_LIB.SCM(SCH_1):I3C2_SDA_R

Q_RES_0402LF-33.2,1%,1/16W,CHIA  I238  R199
   1 I3C3_SDA_R      A @SCM_LIB.SCM(SCH_1):I3C3_SDA_R
   2 I3C3_SPD_SDA      B @SCM_LIB.SCM(SCH_1):I3C3_SPD_SDA

Q_RES_0402LF-33.2,1%,1/16W,CHIA  I239  R201
   1 I3C4_SDA_R      A @SCM_LIB.SCM(SCH_1):I3C4_SDA_R
   2 I3C4_SPD_SDA      B @SCM_LIB.SCM(SCH_1):I3C4_SPD_SDA


DRAWING: @SCM_LIB.SCM(SCH_1):PAGE15 

Q_RES_0402LF-0,5%,1/16W,EMPTY,A  I2  R208
   1 P1V8_AUX      A @SCM_LIB.SCM(SCH_1):P1V8_AUX
   2 P3V3_P1V8_SD1VDD      B @SCM_LIB.SCM(SCH_1):P3V3_P1V8_SD1VDD

Q_RES_0402LF-0,5%,1/16W,CHIP,CA  I4  R207
   1 P3V3_AUX      A @SCM_LIB.SCM(SCH_1):P3V3_AUX
   2 P3V3_P1V8_SD1VDD      B @SCM_LIB.SCM(SCH_1):P3V3_P1V8_SD1VDD

Q_CAP_C0402-1UF,25V,10%,X6S,CHA  I14  C35
   1 P3V3_P1V8_SD1VDD      A @SCM_LIB.SCM(SCH_1):P3V3_P1V8_SD1VDD
   2    GND      B @SCM_LIB.SCM(SCH_1):GND

Q_CAP_0402-0.1UF,25V,10%,X7R,CA  I16  C36
   1 P3V3_P1V8_SD1VDD      A @SCM_LIB.SCM(SCH_1):P3V3_P1V8_SD1VDD
   2    GND      B @SCM_LIB.SCM(SCH_1):GND

Q_RES_0402LF-10K,1%,1/16W,EMPTA  I19  R209
   1 PECI_BMC      A @SCM_LIB.SCM(SCH_1):PECI_BMC
   2    GND      B @SCM_LIB.SCM(SCH_1):GND

Q_RES_0402LF-4.7K,1%,1/16W,CHIA  I21  R212
   1 P3V3_RGM      A @SCM_LIB.SCM(SCH_1):P3V3_RGM
   2 PU_25M_BMC_CLK_EN      B @SCM_LIB.SCM(SCH_1):PU_25M_BMC_CLK_EN

Q_CAP_0402-0.1UF,25V,10%,X7R,CA  I24  C37
   1 P3V3_RGM      A @SCM_LIB.SCM(SCH_1):P3V3_RGM
   2    GND      B @SCM_LIB.SCM(SCH_1):GND

Q_RES_0402LF-0,5%,1/16W,EMPTY,A  I32  R214
   1 P1V8_AUX      A @SCM_LIB.SCM(SCH_1):P1V8_AUX
   2 P3V3_P1V8_SD2VDD      B @SCM_LIB.SCM(SCH_1):P3V3_P1V8_SD2VDD

Q_RES_0402LF-0,5%,1/16W,CHIP,CA  I34  R213
   1 P3V3_AUX      A @SCM_LIB.SCM(SCH_1):P3V3_AUX
   2 P3V3_P1V8_SD2VDD      B @SCM_LIB.SCM(SCH_1):P3V3_P1V8_SD2VDD

Q_CAP_C0402-1UF,25V,10%,X6S,CHA  I36  C38
   1 P3V3_P1V8_SD2VDD      A @SCM_LIB.SCM(SCH_1):P3V3_P1V8_SD2VDD
   2    GND      B @SCM_LIB.SCM(SCH_1):GND

Q_CAP_0402-0.1UF,25V,10%,X7R,CA  I37  C39
   1 P3V3_P1V8_SD2VDD      A @SCM_LIB.SCM(SCH_1):P3V3_P1V8_SD2VDD
   2    GND      B @SCM_LIB.SCM(SCH_1):GND

OSC4_7X25000018-25MHZ,SMLF,MISA  I39  OSC1
   1 PU_25M_BMC_CLK_EN     OE @SCM_LIB.SCM(SCH_1):PU_25M_BMC_CLK_EN
   2    GND    GND @SCM_LIB.SCM(SCH_1):GND
   3 BMC_CLK_25M_R    OUT @SCM_LIB.SCM(SCH_1):BMC_CLK_25M_R
   4 P3V3_RGM    VDD @SCM_LIB.SCM(SCH_1):P3V3_RGM

Q_RES_0402LF-33.2,1%,1/16W,CHIA  I42  R215
   1 BMC_CLK_25M_R      A @SCM_LIB.SCM(SCH_1):BMC_CLK_25M_R
   2 BMC_CLK_25M      B @SCM_LIB.SCM(SCH_1):BMC_CLK_25M

Q_RES_0402LF-1K,1%,1/16W,CHIP,A  I47  R210
   1    GND      A @SCM_LIB.SCM(SCH_1):GND
   2 PD_SP_ENTEST      B @SCM_LIB.SCM(SCH_1):PD_SP_ENTEST

Q_RES_0402LF-10K,1%,1/16W,CHIPA  I51  R211
   1 P3V3_RGM      A @SCM_LIB.SCM(SCH_1):P3V3_RGM
   2 FM_BMC_SSPRST_N      B @SCM_LIB.SCM(SCH_1):FM_BMC_SSPRST_N

Q_INDUCTOR_SMLF-BLM18PG121SN1DA  I65  L3
   2 P1V8_BMC_USB2AV18      2 @SCM_LIB.SCM(SCH_1):P1V8_BMC_USB2AV18
   1 P1V8_AUX      1 @SCM_LIB.SCM(SCH_1):P1V8_AUX

Q_CAP_0402-0.1UF,25V,10%,X7R,CA  I68  C41
   1 P1V8_BMC_USB2AV18      A @SCM_LIB.SCM(SCH_1):P1V8_BMC_USB2AV18
   2    GND      B @SCM_LIB.SCM(SCH_1):GND

Q_INDUCTOR_SMLF-BLM18PG121SN1DA  I82  L4
   2 P3V3_BMC_USB2AV33      2 @SCM_LIB.SCM(SCH_1):P3V3_BMC_USB2AV33
   1 P3V3_AUX      1 @SCM_LIB.SCM(SCH_1):P3V3_AUX

Q_CAP_0402-0.1UF,25V,10%,X7R,CA  I89  C45
   1 P3V3_BMC_USB2AV33      A @SCM_LIB.SCM(SCH_1):P3V3_BMC_USB2AV33
   2    GND      B @SCM_LIB.SCM(SCH_1):GND

Q_RES_0402LF-0,5%,1/16W,CHIP,CA  I92  R217
   1 USB_HOST_BMC_A_R_DP      A @SCM_LIB.SCM(SCH_1):USB_HOST_BMC_A_R_DP
   2 USB_HOST_BMC_A_DP      B @SCM_LIB.SCM(SCH_1):USB_HOST_BMC_A_DP

Q_RES_0402LF-0,5%,1/16W,CHIP,CA  I93  R218
   1 USB_HOST_BMC_A_R_DN      A @SCM_LIB.SCM(SCH_1):USB_HOST_BMC_A_R_DN
   2 USB_HOST_BMC_A_DN      B @SCM_LIB.SCM(SCH_1):USB_HOST_BMC_A_DN

Q_CAP_C0603-22UF,6.3V,20%,X6S,A  I117  C42
   1 PVCCIO_PECI_BMC      A @SCM_LIB.SCM(SCH_1):PVCCIO_PECI_BMC
   2    GND      B @SCM_LIB.SCM(SCH_1):GND

Q_CAP_C0402-1UF,25V,10%,X6S,CHA  I119  C43
   1 PVCCIO_PECI_BMC      A @SCM_LIB.SCM(SCH_1):PVCCIO_PECI_BMC
   2    GND      B @SCM_LIB.SCM(SCH_1):GND

Q_RES_0402LF-0,5%,1/16W,CHIP,CA  I128  R566
   1 RST_BMC_RSTBTN_OUT_R_N      A @SCM_LIB.SCM(SCH_1):RST_BMC_RSTBTN_OUT_R_N
   2 RST_BMC_RSTBTN_OUT_N      B @SCM_LIB.SCM(SCH_1):RST_BMC_RSTBTN_OUT_N

Q_RES_0402LF-10,1%,1/16W,CHIP,A  I133  R21
   1 V_DACG_R      A @SCM_LIB.SCM(SCH_1):V_DACG_R
   2 V_DACG      B @SCM_LIB.SCM(SCH_1):V_DACG

Q_RES_0402LF-10,1%,1/16W,CHIP,A  I134  R24
   1 V_DACB_R      A @SCM_LIB.SCM(SCH_1):V_DACB_R
   2 V_DACB      B @SCM_LIB.SCM(SCH_1):V_DACB

Q_RES_0402LF-0,5%,1/16W,CHIP,CA  I140  R20
   1 V_VGAVS_R      A @SCM_LIB.SCM(SCH_1):V_VGAVS_R
   2 V_VGAVS      B @SCM_LIB.SCM(SCH_1):V_VGAVS

Q_RES_0402LF-0,5%,1/16W,CHIP,CA  I141  R19
   1 V_VGAHS_R      A @SCM_LIB.SCM(SCH_1):V_VGAHS_R
   2 V_VGAHS      B @SCM_LIB.SCM(SCH_1):V_VGAHS

Q_RES_0402LF-10,1%,1/16W,CHIP,A  I142  R26
   1 V_DACR_R      A @SCM_LIB.SCM(SCH_1):V_DACR_R
   2 V_DACR      B @SCM_LIB.SCM(SCH_1):V_DACR

Q_RES_0402LF-150,1%,1/16W,CHIPA  I149  R25
   1 V_DACR_R      A @SCM_LIB.SCM(SCH_1):V_DACR_R
   2    GND      B @SCM_LIB.SCM(SCH_1):GND

Q_RES_0402LF-150,1%,1/16W,CHIPA  I150  R23
   1 V_DACG_R      A @SCM_LIB.SCM(SCH_1):V_DACG_R
   2    GND      B @SCM_LIB.SCM(SCH_1):GND

Q_RES_0402LF-150,1%,1/16W,CHIPA  I151  R22
   1 V_DACB_R      A @SCM_LIB.SCM(SCH_1):V_DACB_R
   2    GND      B @SCM_LIB.SCM(SCH_1):GND

Q_RES_0402LF-4.7K,1%,1/16W,EMPA  I152  R623
   1 P3V3_RGM      A @SCM_LIB.SCM(SCH_1):P3V3_RGM
   2 RST_EXTRST_N      B @SCM_LIB.SCM(SCH_1):RST_EXTRST_N

Q_RES_0402LF-0,5%,1/16W,CHIP,CA  I168  R528
   1 USB_HOST_BMC_B_R_DN      A @SCM_LIB.SCM(SCH_1):USB_HOST_BMC_B_R_DN
   2 USB_HOST_BMC_B_DN      B @SCM_LIB.SCM(SCH_1):USB_HOST_BMC_B_DN

Q_RES_0402LF-0,5%,1/16W,CHIP,CA  I169  R527
   1 USB_HOST_BMC_B_R_DP      A @SCM_LIB.SCM(SCH_1):USB_HOST_BMC_B_R_DP
   2 USB_HOST_BMC_B_DP      B @SCM_LIB.SCM(SCH_1):USB_HOST_BMC_B_DP

Q_RES_0402LF-4.7K,1%,1/16W,CHIA  I174  R717
   1 P3V3_AUX      A @SCM_LIB.SCM(SCH_1):P3V3_AUX
   2 RST_BMC_RSTBTN_OUT_N      B @SCM_LIB.SCM(SCH_1):RST_BMC_RSTBTN_OUT_N

MOSFET_N_GSD-NX7002AK,SMLF,IC,A  I179  Q11
   G BATTERY_DETECT_R   GATE @SCM_LIB.SCM(SCH_1):BATTERY_DETECT_R
   S P3V_BAT_SENSOR SOURCE @SCM_LIB.SCM(SCH_1):P3V_BAT_SENSOR
   D P3V_BAT_R1  DRAIN @SCM_LIB.SCM(SCH_1):P3V_BAT_R1

Q_CAP_0402-100PF,50V,5%,NPO,CHA  I180  C275
   1 P3V_BAT_SENSOR      A @SCM_LIB.SCM(SCH_1):P3V_BAT_SENSOR
   2    GND      B @SCM_LIB.SCM(SCH_1):GND

Q_RES_0402LF-100K,1%,1/16W,CHIA  I181  R778
   1 P3V_BAT_SENSOR      A @SCM_LIB.SCM(SCH_1):P3V_BAT_SENSOR
   2    GND      B @SCM_LIB.SCM(SCH_1):GND

Q_RES_0402LF-1K,1%,1/16W,CHIP,A  I183  R775
   1 BATTERY_DETECT      A @SCM_LIB.SCM(SCH_1):BATTERY_DETECT
   2 BATTERY_DETECT_R      B @SCM_LIB.SCM(SCH_1):BATTERY_DETECT_R

Q_RES_0402LF-47K,1%,1/16W,CHIPA  I184  R776
   1 BATTERY_DETECT_R      A @SCM_LIB.SCM(SCH_1):BATTERY_DETECT_R
   2    GND      B @SCM_LIB.SCM(SCH_1):GND

Q_CAP_0402-0.1UF,25V,10%,X7R,CA  I201  C290
   1 P12V_SENSOR      A @SCM_LIB.SCM(SCH_1):P12V_SENSOR
   2    GND      B @SCM_LIB.SCM(SCH_1):GND

Q_RES_0402LF-15.8K,1%,1/16W,CHA  I202  R785
   1 P12V_AUX      A @SCM_LIB.SCM(SCH_1):P12V_AUX
   2 P12V_SENSOR      B @SCM_LIB.SCM(SCH_1):P12V_SENSOR

Q_RES_0402LF-2K,1%,1/16W,CHIP,A  I203  R786
   1 P12V_SENSOR      A @SCM_LIB.SCM(SCH_1):P12V_SENSOR
   2    GND      B @SCM_LIB.SCM(SCH_1):GND

Q_CAP_0402-0.1UF,25V,10%,X7R,CA  I207  C295
   1 P5V_SENSOR      A @SCM_LIB.SCM(SCH_1):P5V_SENSOR
   2    GND      B @SCM_LIB.SCM(SCH_1):GND

Q_RES_0402LF-2K,1%,1/16W,CHIP,A  I211  R788
   1 P5V_SENSOR      A @SCM_LIB.SCM(SCH_1):P5V_SENSOR
   2    GND      B @SCM_LIB.SCM(SCH_1):GND

Q_CAP_0402-0.1UF,25V,10%,X7R,CA  I215  C299
   1 P3V3_SENSOR      A @SCM_LIB.SCM(SCH_1):P3V3_SENSOR
   2    GND      B @SCM_LIB.SCM(SCH_1):GND

Q_RES_0402LF-2.87K,1%,1/16W,CHA  I219  R789
   1 P3V3_AUX      A @SCM_LIB.SCM(SCH_1):P3V3_AUX
   2 P3V3_SENSOR      B @SCM_LIB.SCM(SCH_1):P3V3_SENSOR

Q_RES_0402LF-2K,1%,1/16W,CHIP,A  I220  R790
   1 P3V3_SENSOR      A @SCM_LIB.SCM(SCH_1):P3V3_SENSOR
   2    GND      B @SCM_LIB.SCM(SCH_1):GND

Q_RES_0402LF-5.36K,1%,1/16W,CHA  I223  R787
   1 P5V_AUX      A @SCM_LIB.SCM(SCH_1):P5V_AUX
   2 P5V_SENSOR      B @SCM_LIB.SCM(SCH_1):P5V_SENSOR

Q_CAP_0402-0.1UF,25V,10%,X7R,CA  I235  C303
   1 P2V5_SENSOR      A @SCM_LIB.SCM(SCH_1):P2V5_SENSOR
   2    GND      B @SCM_LIB.SCM(SCH_1):GND

Q_RES_0402LF-2K,1%,1/16W,CHIP,A  I236  R792
   1 P2V5_SENSOR      A @SCM_LIB.SCM(SCH_1):P2V5_SENSOR
   2    GND      B @SCM_LIB.SCM(SCH_1):GND

Q_CAP_0402-0.1UF,25V,10%,X7R,CA  I240  C307
   1 P1V8_SENSOR      A @SCM_LIB.SCM(SCH_1):P1V8_SENSOR
   2    GND      B @SCM_LIB.SCM(SCH_1):GND

Q_RES_0402LF-2K,1%,1/16W,CHIP,A  I242  R794
   1 P1V8_SENSOR      A @SCM_LIB.SCM(SCH_1):P1V8_SENSOR
   2    GND      B @SCM_LIB.SCM(SCH_1):GND

Q_RES_0402LF-665,1%,1/16W,CHIPA  I244  R793
   1 P1V8_AUX      A @SCM_LIB.SCM(SCH_1):P1V8_AUX
   2 P1V8_SENSOR      B @SCM_LIB.SCM(SCH_1):P1V8_SENSOR

Q_RES_0402LF-1.69K,1%,1/16W,CHA  I245  R791
   1 P2V5_AUX      A @SCM_LIB.SCM(SCH_1):P2V5_AUX
   2 P2V5_SENSOR      B @SCM_LIB.SCM(SCH_1):P2V5_SENSOR

Q_CAP_0402-0.1UF,25V,10%,X7R,CA  I247  C309
   1 P1V2_SENSOR      A @SCM_LIB.SCM(SCH_1):P1V2_SENSOR
   2    GND      B @SCM_LIB.SCM(SCH_1):GND

Q_RES_0402LF-1K,1%,1/16W,CHIP,A  I252  R795
   1 P1V2_AUX      A @SCM_LIB.SCM(SCH_1):P1V2_AUX
   2 P1V2_SENSOR      B @SCM_LIB.SCM(SCH_1):P1V2_SENSOR

Q_RES_0402LF-1K,1%,1/16W,CHIP,A  I255  R796
   1 P1V0_AUX      A @SCM_LIB.SCM(SCH_1):P1V0_AUX
   2 P1V0_SENSOR      B @SCM_LIB.SCM(SCH_1):P1V0_SENSOR

Q_CAP_0402-0.1UF,25V,10%,X7R,CA  I256  C311
   1 P1V0_SENSOR      A @SCM_LIB.SCM(SCH_1):P1V0_SENSOR
   2    GND      B @SCM_LIB.SCM(SCH_1):GND

Q_CAP_0402-0.1UF,25V,10%,X7R,CA  I259  C314
   1 PGPPA_BMC_AUX_SENSOR      A @SCM_LIB.SCM(SCH_1):PGPPA_BMC_AUX_SENSOR
   2    GND      B @SCM_LIB.SCM(SCH_1):GND

Q_RES_0402LF-2.87K,1%,1/16W,CHA  I261  R797
   1 PGPPA_BMC_AUX      A @SCM_LIB.SCM(SCH_1):PGPPA_BMC_AUX
   2 PGPPA_BMC_AUX_SENSOR      B @SCM_LIB.SCM(SCH_1):PGPPA_BMC_AUX_SENSOR

Q_RES_0402LF-2K,1%,1/16W,CHIP,A  I262  R798
   1 PGPPA_BMC_AUX_SENSOR      A @SCM_LIB.SCM(SCH_1):PGPPA_BMC_AUX_SENSOR
   2    GND      B @SCM_LIB.SCM(SCH_1):GND

Q_RES_0402LF-200K,1%,1/16W,CHIA  I289  R777
   1 P3V_BAT_R      A @SCM_LIB.SCM(SCH_1):P3V_BAT_R
   2 P3V_BAT_R1      B @SCM_LIB.SCM(SCH_1):P3V_BAT_R1

Q_RES_0402LF-0,5%,1/16W,CHIP,CA  I318  R316
   1 BMC_PWR_LED      A @SCM_LIB.SCM(SCH_1):BMC_PWR_LED
   2 PWR_LED      B @SCM_LIB.SCM(SCH_1):PWR_LED

Q_RES_0402LF-33.2,1%,1/16W,CHIA  I320  R448
   1 SMB_BMC_ALERT9_N      A @SCM_LIB.SCM(SCH_1):SMB_BMC_ALERT9_N
   2 SMB_BMC_ALERT9_R_N      B @SCM_LIB.SCM(SCH_1):SMB_BMC_ALERT9_R_N

Q_RES_0402LF-33.2,1%,1/16W,CHIA  I321  R449
   1 SMB_BMC_ALERT10_N      A @SCM_LIB.SCM(SCH_1):SMB_BMC_ALERT10_N
   2 SMB_BMC_ALERT10_R_N      B @SCM_LIB.SCM(SCH_1):SMB_BMC_ALERT10_R_N

Q_RES_0402LF-33.2,1%,1/16W,CHIA  I326  R489
   1 FM_SOL_UART_CH_SEL      A @SCM_LIB.SCM(SCH_1):FM_SOL_UART_CH_SEL
   2 FM_SOL_UART_CH_SEL_R1      B @SCM_LIB.SCM(SCH_1):FM_SOL_UART_CH_SEL_R1

Q_RES_0402LF-33.2,1%,1/16W,CHIA  I330  R479
   1 FM_P12V_HSC_ENABLE      A @SCM_LIB.SCM(SCH_1):FM_P12V_HSC_ENABLE
   2 FM_P12V_HSC_ENABLE_R1      B @SCM_LIB.SCM(SCH_1):FM_P12V_HSC_ENABLE_R1

Q_RES_0402LF-33.2,1%,1/16W,CHIA  I345  R644
   1 FM_JTAG_BMC_MUX_SEL      A @SCM_LIB.SCM(SCH_1):FM_JTAG_BMC_MUX_SEL
   2 FM_JTAG_BMC_MUX_SEL_R1      B @SCM_LIB.SCM(SCH_1):FM_JTAG_BMC_MUX_SEL_R1

Q_RES_0402LF-4.7K,1%,1/16W,EMPA  I346  R491
   1 P3V3_RGM      A @SCM_LIB.SCM(SCH_1):P3V3_RGM
   2 RST_BMC_SRST_N      B @SCM_LIB.SCM(SCH_1):RST_BMC_SRST_N

AST2600A3GP-AST2600A3-GP,SMLF,A  I350  U5
AD21 V_DACB_R   DACB @SCM_LIB.SCM(SCH_1):V_DACB_R
AE21 V_DACG_R   DACG @SCM_LIB.SCM(SCH_1):V_DACG_R
AF21 V_DACR_R   DACR @SCM_LIB.SCM(SCH_1):V_DACR_R
 J10 P3V3_BMC_USB2AV33 USB2AV33 @SCM_LIB.SCM(SCH_1):P3V3_BMC_USB2AV33
  B4 USB_HOST_BMC_A_R_DN USB2A_DN @SCM_LIB.SCM(SCH_1):USB_HOST_BMC_A_R_DN
  A4 USB_HOST_BMC_A_R_DP USB2A_DP @SCM_LIB.SCM(SCH_1):USB_HOST_BMC_A_R_DP
  B6 USB_HOST_BMC_B_R_DN USB2B_DN @SCM_LIB.SCM(SCH_1):USB_HOST_BMC_B_R_DN
  A6 USB_HOST_BMC_B_R_DP USB2B_DP @SCM_LIB.SCM(SCH_1):USB_HOST_BMC_B_R_DP
AD20 P12V_SENSOR ADC0||GPIT0 @SCM_LIB.SCM(SCH_1):P12V_SENSOR
AC18 P5V_SENSOR ADC1||GPIT1 @SCM_LIB.SCM(SCH_1):P5V_SENSOR
AE19 P3V3_SENSOR ADC2||GPIT2 @SCM_LIB.SCM(SCH_1):P3V3_SENSOR
AD19 P2V5_SENSOR ADC3||GPIT3 @SCM_LIB.SCM(SCH_1):P2V5_SENSOR
AC19 P1V8_SENSOR ADC4||GPIT4 @SCM_LIB.SCM(SCH_1):P1V8_SENSOR
AB19 PGPPA_BMC_AUX_SENSOR ADC5||GPIT5 @SCM_LIB.SCM(SCH_1):PGPPA_BMC_AUX_SENSOR
AB18 P1V2_SENSOR ADC6||GPIT6 @SCM_LIB.SCM(SCH_1):P1V2_SENSOR
AE18 P3V_BAT_SENSOR ADC7||GPIT7 @SCM_LIB.SCM(SCH_1):P3V_BAT_SENSOR
AB16 SMB_BMC_ALERT9_R_N ADC8||GPIU0||SALT9 @SCM_LIB.SCM(SCH_1):SMB_BMC_ALERT9_R_N
AA17 SMB_BMC_ALERT10_R_N ADC9||GPIU1||SALT10 @SCM_LIB.SCM(SCH_1):SMB_BMC_ALERT10_R_N
AB17 P1V0_SENSOR ADC10||GPIU2||SALT11 @SCM_LIB.SCM(SCH_1):P1V0_SENSOR
AE16 SMB_BMC_ALERT12_N ADC11||GPIU3||SALT12 @SCM_LIB.SCM(SCH_1):SMB_BMC_ALERT12_N
AC16 BSM_PRSNT_R_N ADC12||GPIU4||SALT13 @SCM_LIB.SCM(SCH_1):BSM_PRSNT_R_N
AA16 FM_BMC_EN_DET_R ADC13||GPIU5||SALT14 @SCM_LIB.SCM(SCH_1):FM_BMC_EN_DET_R
AD16 FM_PCHHOT_R_N ADC14||GPIU6||SALT15 @SCM_LIB.SCM(SCH_1):FM_PCHHOT_R_N
AC17 SMB_BMC_ALERT16_N ADC15||GPIU7||SALT16 @SCM_LIB.SCM(SCH_1):SMB_BMC_ALERT16_N
 C10 PD_SP_ENTEST ENTEST @SCM_LIB.SCM(SCH_1):PD_SP_ENTEST
 E10 RST_BMC_SRST_N  SRST# @SCM_LIB.SCM(SCH_1):RST_BMC_SRST_N
 B10 RST_EXTRST_N EXTRST# @SCM_LIB.SCM(SCH_1):RST_EXTRST_N
 D10 BMC_CLK_25M  CLKIN @SCM_LIB.SCM(SCH_1):BMC_CLK_25M
  B7 RST_SPI_FLASH_N RSTIND# @SCM_LIB.SCM(SCH_1):RST_SPI_FLASH_N
 F11 JTAG_SCM_NTRST NTRST||MNTRST1 @SCM_LIB.SCM(SCH_1):JTAG_SCM_NTRST
  B9 JTAG_SCM_TCK TCK||MTCK1 @SCM_LIB.SCM(SCH_1):JTAG_SCM_TCK
  D9 JTAG_SCM_TDI TDI||MTDI1 @SCM_LIB.SCM(SCH_1):JTAG_SCM_TDI
  C9 JTAG_SCM_TDO TDO||MTDO1 @SCM_LIB.SCM(SCH_1):JTAG_SCM_TDO
  A9 JTAG_SCM_TMS TMS||MTMS1 @SCM_LIB.SCM(SCH_1):JTAG_SCM_TMS
 B14 V_VGAHS_R GPIOL6||VGAHS @SCM_LIB.SCM(SCH_1):V_VGAHS_R
 C14 V_VGAVS_R GPIOL7||VGAVS @SCM_LIB.SCM(SCH_1):V_VGAVS_R
  B8 V_BMC_DDC_SCL DDCCLK @SCM_LIB.SCM(SCH_1):V_BMC_DDC_SCL
  A8 V_BMC_DDC_SDA DDCDAT @SCM_LIB.SCM(SCH_1):V_BMC_DDC_SDA
AD26 FM_PMBUS_ALERT_EN GPIOO0||PWM0 @SCM_LIB.SCM(SCH_1):FM_PMBUS_ALERT_EN
AD22     NC GPIOO1||PWM1     NC
AD23 FM_PCIE_M2_SSD0_PRSNT_N GPIOO2||PWM2 @SCM_LIB.SCM(SCH_1):FM_PCIE_M2_SSD0_PRSNT_N
AD24 FM_JTAG_BMC_MUX_SEL_R1 GPIOO3||PWM3 @SCM_LIB.SCM(SCH_1):FM_JTAG_BMC_MUX_SEL_R1
AD25 FM_ADR_TRIGGER_N GPIOO4||PWM4 @SCM_LIB.SCM(SCH_1):FM_ADR_TRIGGER_N
AC22 FM_TPM_PRSNT_0_N GPIOO5||PWM5 @SCM_LIB.SCM(SCH_1):FM_TPM_PRSNT_0_N
AC24 FM_ADR_COMPLETE GPIOO6||PWM6 @SCM_LIB.SCM(SCH_1):FM_ADR_COMPLETE
AC23 FM_SPD_REMOTE_EN_R GPIOO7||PWM7 @SCM_LIB.SCM(SCH_1):FM_SPD_REMOTE_EN_R
AA25 IRQ_PCH_TPM_SPI_N GPIOQ0||TACH0 @SCM_LIB.SCM(SCH_1):IRQ_PCH_TPM_SPI_N
AB25 USB_OC0_REAR_R_N GPIOQ1||TACH1 @SCM_LIB.SCM(SCH_1):USB_OC0_REAR_R_N
 Y24 GPU_NVS_PWR_BRAKE_R_N GPIOQ2||TACH2 @SCM_LIB.SCM(SCH_1):GPU_NVS_PWR_BRAKE_R_N
AB26 GPU_WP_HW_CTRL_R_N GPIOQ3||TACH3 @SCM_LIB.SCM(SCH_1):GPU_WP_HW_CTRL_R_N
 Y26 FM_HDD_LED_N GPIOQ4||TACH4 @SCM_LIB.SCM(SCH_1):FM_HDD_LED_N
AC26 FM_P12V_HSC_ENABLE_R1 GPIOQ5||TACH5 @SCM_LIB.SCM(SCH_1):FM_P12V_HSC_ENABLE_R1
 Y25 FM_PCH_BEEP_LED GPIOQ6||TACH6 @SCM_LIB.SCM(SCH_1):FM_PCH_BEEP_LED
AA26 FM_SOL_UART_CH_SEL_R1 GPIOQ7||TACH7 @SCM_LIB.SCM(SCH_1):FM_SOL_UART_CH_SEL_R1
 V25 IRQ_OC_DETECT_N GPIOR0||TACH8 @SCM_LIB.SCM(SCH_1):IRQ_OC_DETECT_N
 U24 IRQ_UV_DETECT_N GPIOR1||TACH9 @SCM_LIB.SCM(SCH_1):IRQ_UV_DETECT_N
 V24 IRQ_OC_DETECT_EN_N GPIOR2||TACH10 @SCM_LIB.SCM(SCH_1):IRQ_OC_DETECT_EN_N
 V26 IRQ_CPU0_VRHOT_N GPIOR3||TACH11 @SCM_LIB.SCM(SCH_1):IRQ_CPU0_VRHOT_N
 U25 IRQ_CPU1_VRHOT_N GPIOR4||TACH12 @SCM_LIB.SCM(SCH_1):IRQ_CPU1_VRHOT_N
 T23 PWRGD_PCH_PWROK GPIOR5||TACH13 @SCM_LIB.SCM(SCH_1):PWRGD_PCH_PWROK
 W26 PWRGD_CPUPWRGD_LVC1 GPIOR6||TACH14 @SCM_LIB.SCM(SCH_1):PWRGD_CPUPWRGD_LVC1
 U26 FM_BIOS_POST_CMPLT_BMC_N GPIOR7||TACH15 @SCM_LIB.SCM(SCH_1):FM_BIOS_POST_CMPLT_BMC_N
AB22 FM_PWR_BTN GPIOP0||PWM8||THRUIN0 @SCM_LIB.SCM(SCH_1):FM_PWR_BTN
 W24 SYS_BMC_PWRBTN_R1_N GPIOP1||PWM9||THRUOUT0 @SCM_LIB.SCM(SCH_1):SYS_BMC_PWRBTN_R1_N
AA23 ID_RST_BTN_BMC_R_N GPIOP2||PWM10||THRUIN1 @SCM_LIB.SCM(SCH_1):ID_RST_BTN_BMC_R_N
AA24 RST_BMC_RSTBTN_OUT_R_N GPIOP3||PWM11||THRUOUT1 @SCM_LIB.SCM(SCH_1):RST_BMC_RSTBTN_OUT_R_N
 W23 BMC_PWR_LED GPIOP4||PWM12||THRUIN2 @SCM_LIB.SCM(SCH_1):BMC_PWR_LED
AB23 H_CPU0_MEMTRIP_LVC1_N GPIOP5||PWM13||THRUOUT2 @SCM_LIB.SCM(SCH_1):H_CPU0_MEMTRIP_LVC1_N
AB24 H_CPU1_MEMTRIP_LVC1_N GPIOP6||PWM14 @SCM_LIB.SCM(SCH_1):H_CPU1_MEMTRIP_LVC1_N
 Y23 BMC_HEARTBEAT_N GPIOP7||PWM15||HBLED# @SCM_LIB.SCM(SCH_1):BMC_HEARTBEAT_N
  D7 FM_BMC_SSPRST_N SSPRST# @SCM_LIB.SCM(SCH_1):FM_BMC_SSPRST_N
 K10 P1V8_BMC_USB2AV18 USB2AV18 @SCM_LIB.SCM(SCH_1):P1V8_BMC_USB2AV18
AA18 PVCCIO_PECI_BMC PECIVDD @SCM_LIB.SCM(SCH_1):PVCCIO_PECI_BMC
AF16 PECI_BMC_R   PECI @SCM_LIB.SCM(SCH_1):PECI_BMC_R
 C16 JTAG_1_BMC_TDO GPIOI4||MTDO2 @SCM_LIB.SCM(SCH_1):JTAG_1_BMC_TDO
 D16 JTAG_1_BMC_TMS_R GPIOI3||MTMS2||RXD13 @SCM_LIB.SCM(SCH_1):JTAG_1_BMC_TMS_R
 E17 JTAG_1_BMC_TCK_R GPIOI2||MTCK2||TXD13 @SCM_LIB.SCM(SCH_1):JTAG_1_BMC_TCK_R
 D17 JTAG_1_BMC_TRST_R GPIOI0||MNTRST2||TXD12 @SCM_LIB.SCM(SCH_1):JTAG_1_BMC_TRST_R
 A16 JTAG_1_BMC_TDI_R GPIOI1||MTDI2||RXD12 @SCM_LIB.SCM(SCH_1):JTAG_1_BMC_TDI_R
AB21 FM_INTRUDER_R_N CHASI# @SCM_LIB.SCM(SCH_1):FM_INTRUDER_R_N

Q_RES_0402LF-0,5%,1/16W,CHIP,CA  I351  R398
   1 JTAG_1_BMC_TDO      A @SCM_LIB.SCM(SCH_1):JTAG_1_BMC_TDO
   2 JTAG_1_BMC_TDO_R      B @SCM_LIB.SCM(SCH_1):JTAG_1_BMC_TDO_R

Q_RES_0402LF-49.9,1%,1/16W,EMPA  I353  R441
   1 USB_HOST_BMC_A_DN      A @SCM_LIB.SCM(SCH_1):USB_HOST_BMC_A_DN
   2    GND      B @SCM_LIB.SCM(SCH_1):GND

Q_RES_0402LF-49.9,1%,1/16W,EMPA  I354  R440
   1 USB_HOST_BMC_A_DP      A @SCM_LIB.SCM(SCH_1):USB_HOST_BMC_A_DP
   2    GND      B @SCM_LIB.SCM(SCH_1):GND

Q_RES_0402LF-0,5%,1/16W,CHIP,CA  I367  R804
   1 SYS_BMC_PWRBTN_R1_N      A @SCM_LIB.SCM(SCH_1):SYS_BMC_PWRBTN_R1_N
   2 SYS_BMC_PWRBTN_R_N      B @SCM_LIB.SCM(SCH_1):SYS_BMC_PWRBTN_R_N

Q_CAP_C0603-4.7UF,25V,10%,X6S,A  I368  C40
   1 P1V8_BMC_USB2AV18      A @SCM_LIB.SCM(SCH_1):P1V8_BMC_USB2AV18
   2    GND      B @SCM_LIB.SCM(SCH_1):GND

Q_CAP_C0603-4.7UF,25V,10%,X6S,A  I369  C44
   1 P3V3_BMC_USB2AV33      A @SCM_LIB.SCM(SCH_1):P3V3_BMC_USB2AV33
   2    GND      B @SCM_LIB.SCM(SCH_1):GND

Q_RES_0402LF-0,5%,1/16W,CHIP,CA  I387  R853
   1 FM_INTRUDER_R_N      A @SCM_LIB.SCM(SCH_1):FM_INTRUDER_R_N
   2 FM_INTRUDER_N      B @SCM_LIB.SCM(SCH_1):FM_INTRUDER_N

Q_RES_0402LF-49.9,1%,1/16W,CHIA  I389  R216
   1 PECI_BMC_R      A @SCM_LIB.SCM(SCH_1):PECI_BMC_R
   2 PECI_BMC      B @SCM_LIB.SCM(SCH_1):PECI_BMC

Q_RES_0402LF-4.7K,1%,1/16W,CHIA  I391  R462
   1 P3V3_AUX      A @SCM_LIB.SCM(SCH_1):P3V3_AUX
   2 SYS_BMC_PWRBTN_R1_N      B @SCM_LIB.SCM(SCH_1):SYS_BMC_PWRBTN_R1_N

74LVC1G08GW_SM-74LVC1G08GW,IC,A  I393  U15
   1 SYS_BMC_PWRBTN_R_N      B @SCM_LIB.SCM(SCH_1):SYS_BMC_PWRBTN_R_N
   2 PWR_BTN_BMC_N      A @SCM_LIB.SCM(SCH_1):PWR_BTN_BMC_N
   4 SYS_PWRBTN_N      Y @SCM_LIB.SCM(SCH_1):SYS_PWRBTN_N
   5 P3V3_AUX    VCC @SCM_LIB.SCM(SCH_1):P3V3_AUX
   3    GND    GND @SCM_LIB.SCM(SCH_1):GND

Q_CAP_0402-0.1UF,25V,10%,X7R,CA  I398  C26
   1 P3V3_AUX      A @SCM_LIB.SCM(SCH_1):P3V3_AUX
   2    GND      B @SCM_LIB.SCM(SCH_1):GND

Q_RES_0402LF-33.2,1%,1/16W,CHIA  I404  R585
   1 BMC_RSTIND_N      A @SCM_LIB.SCM(SCH_1):BMC_RSTIND_N
   2 RST_SPI_FLASH_N      B @SCM_LIB.SCM(SCH_1):RST_SPI_FLASH_N

Q_RES_0402LF-100,1%,1/16W,CHIPA  I405  R225
   1 FM_PWR_BTN      A @SCM_LIB.SCM(SCH_1):FM_PWR_BTN
   2 PWR_BTN_BMC_N      B @SCM_LIB.SCM(SCH_1):PWR_BTN_BMC_N

Q_RES_0402LF-100,1%,1/16W,CHIPA  I406  R565
   1 ID_RST_BTN_BMC_R_N      A @SCM_LIB.SCM(SCH_1):ID_RST_BTN_BMC_R_N
   2 ID_RST_BTN_BMC_N      B @SCM_LIB.SCM(SCH_1):ID_RST_BTN_BMC_N


DRAWING: @SCM_LIB.SCM(SCH_1):PAGE16 

Q_CAP_C0603-22UF,6.3V,20%,X6S,A  I23  C55
   1 P1V2_AUX      A @SCM_LIB.SCM(SCH_1):P1V2_AUX
   2    GND      B @SCM_LIB.SCM(SCH_1):GND

Q_INDUCTOR_SMLF-BLM18PG121SN1DA  I24  L10
   2 P1V8_STBY_PE_VCC18A      2 @SCM_LIB.SCM(SCH_1):P1V8_STBY_PE_VCC18A
   1 P1V8_AUX      1 @SCM_LIB.SCM(SCH_1):P1V8_AUX

Q_INDUCTOR_SMLF-BLM18PG121SN1DA  I29  L8
   2 P1V0_STBY_PLAVDD      2 @SCM_LIB.SCM(SCH_1):P1V0_STBY_PLAVDD
   1 P1V0_AUX      1 @SCM_LIB.SCM(SCH_1):P1V0_AUX

Q_CAP_C0402-1UF,25V,10%,X6S,CHA  I31  C52
   1 P1V0_STBY_PLAVDD      A @SCM_LIB.SCM(SCH_1):P1V0_STBY_PLAVDD
   2    GND      B @SCM_LIB.SCM(SCH_1):GND

Q_CAP_0402-0.1UF,25V,10%,X7R,CA  I32  C54
   1 P1V0_STBY_PLAVDD      A @SCM_LIB.SCM(SCH_1):P1V0_STBY_PLAVDD
   2    GND      B @SCM_LIB.SCM(SCH_1):GND

Q_CAP_C0402-1UF,25V,10%,X6S,CHA  I33  C56
   1 P1V0_STBY_PLAVDD      A @SCM_LIB.SCM(SCH_1):P1V0_STBY_PLAVDD
   2    GND      B @SCM_LIB.SCM(SCH_1):GND

Q_CAP_0402-2200PF,50V,10%,X7R,A  I46  C63
   1 P1V2_STBY_MVDD_CK      A @SCM_LIB.SCM(SCH_1):P1V2_STBY_MVDD_CK
   2    GND      B @SCM_LIB.SCM(SCH_1):GND

Q_INDUCTOR_SMLF-BLM18PG121SN1DA  I47  L11
   2 P1V2_STBY_MVDD_CK      2 @SCM_LIB.SCM(SCH_1):P1V2_STBY_MVDD_CK
   1 P1V2_AUX      1 @SCM_LIB.SCM(SCH_1):P1V2_AUX

Q_CAP_C0402-1UF,25V,10%,X6S,CHA  I48  C67
   1 P1V2_STBY_MVDD_CK      A @SCM_LIB.SCM(SCH_1):P1V2_STBY_MVDD_CK
   2    GND      B @SCM_LIB.SCM(SCH_1):GND

Q_CAP_0402-0.1UF,25V,10%,X7R,CA  I49  C71
   1 P1V2_STBY_MVDD_CK      A @SCM_LIB.SCM(SCH_1):P1V2_STBY_MVDD_CK
   2    GND      B @SCM_LIB.SCM(SCH_1):GND

Q_CAP_0402-0.1UF,25V,10%,X7R,CA  I51  C73
   1 P1V2_STBY_MVDD_CK      A @SCM_LIB.SCM(SCH_1):P1V2_STBY_MVDD_CK
   2    GND      B @SCM_LIB.SCM(SCH_1):GND

Q_CAP_C0402-1UF,25V,10%,X6S,CHA  I52  C58
   1 P1V2_AUX      A @SCM_LIB.SCM(SCH_1):P1V2_AUX
   2    GND      B @SCM_LIB.SCM(SCH_1):GND

Q_CAP_C0402-1UF,25V,10%,X6S,CHA  I53  C62
   1 P1V2_AUX      A @SCM_LIB.SCM(SCH_1):P1V2_AUX
   2    GND      B @SCM_LIB.SCM(SCH_1):GND

Q_CAP_0402-0.1UF,25V,10%,X7R,CA  I54  C66
   1 P1V2_AUX      A @SCM_LIB.SCM(SCH_1):P1V2_AUX
   2    GND      B @SCM_LIB.SCM(SCH_1):GND

Q_CAP_C0402-1UF,25V,10%,X6S,CHA  I55  C61
   1 P1V8_STBY_PE_VCC18A      A @SCM_LIB.SCM(SCH_1):P1V8_STBY_PE_VCC18A
   2    GND      B @SCM_LIB.SCM(SCH_1):GND

Q_CAP_0402-0.1UF,25V,10%,X7R,CA  I57  C70
   1 P1V2_AUX      A @SCM_LIB.SCM(SCH_1):P1V2_AUX
   2    GND      B @SCM_LIB.SCM(SCH_1):GND

Q_CAP_0402-0.1UF,25V,10%,X7R,CA  I58  C72
   1 P1V2_AUX      A @SCM_LIB.SCM(SCH_1):P1V2_AUX
   2    GND      B @SCM_LIB.SCM(SCH_1):GND

Q_CAP_0402-0.1UF,25V,10%,X7R,CA  I59  C69
   1 P1V8_STBY_PE_VCC18A      A @SCM_LIB.SCM(SCH_1):P1V8_STBY_PE_VCC18A
   2    GND      B @SCM_LIB.SCM(SCH_1):GND

Q_CAP_0402-0.1UF,25V,10%,X7R,CA  I66  C74
   1 P1V2_AUX      A @SCM_LIB.SCM(SCH_1):P1V2_AUX
   2    GND      B @SCM_LIB.SCM(SCH_1):GND

Q_CAP_0402-0.1UF,25V,10%,X7R,CA  I79  C59
   1 P1V0_STBY_PLAVDD      A @SCM_LIB.SCM(SCH_1):P1V0_STBY_PLAVDD
   2    GND      B @SCM_LIB.SCM(SCH_1):GND

Q_CAP_C0402-1UF,25V,10%,X6S,CHA  I81  C64
   1 P1V0_STBY_PLAVDD      A @SCM_LIB.SCM(SCH_1):P1V0_STBY_PLAVDD
   2    GND      B @SCM_LIB.SCM(SCH_1):GND

Q_CAP_0402-0.1UF,25V,10%,X7R,CA  I82  C68
   1 P1V0_STBY_PLAVDD      A @SCM_LIB.SCM(SCH_1):P1V0_STBY_PLAVDD
   2    GND      B @SCM_LIB.SCM(SCH_1):GND

Q_RES_0402LF-49.9K,1%,1/16W,CHA  I86  R234
   1    GND      A @SCM_LIB.SCM(SCH_1):GND
   2 A_BMC_ADCREXT1      B @SCM_LIB.SCM(SCH_1):A_BMC_ADCREXT1

Q_RES_0402LF-49.9K,1%,1/16W,CHA  I87  R233
   1    GND      A @SCM_LIB.SCM(SCH_1):GND
   2 A_BMC_ADCREXT0      B @SCM_LIB.SCM(SCH_1):A_BMC_ADCREXT0

Q_CAP_C0402-1UF,25V,10%,X6S,CHA  I93  C75
   1 A_BMC_ADCAV33      A @SCM_LIB.SCM(SCH_1):A_BMC_ADCAV33
   2    GND      B @SCM_LIB.SCM(SCH_1):GND

Q_INDUCTOR_SMLF-BLM18PG121SN1DA  I99  L12
   2 A_BMC_ADCAV33      2 @SCM_LIB.SCM(SCH_1):A_BMC_ADCAV33
   1 P3V3_AUX      1 @SCM_LIB.SCM(SCH_1):P3V3_AUX

Q_CAP_0402-0.1UF,25V,10%,X7R,CA  I100  C77
   1 A_BMC_ADCAV33      A @SCM_LIB.SCM(SCH_1):A_BMC_ADCAV33
   2    GND      B @SCM_LIB.SCM(SCH_1):GND

Q_CAP_0402-0.1UF,25V,10%,X7R,CA  I106  C83
   1 P3V3_RTC_AUX      A @SCM_LIB.SCM(SCH_1):P3V3_RTC_AUX
   2    GND      B @SCM_LIB.SCM(SCH_1):GND

Q_CAP_0402-0.1UF,25V,10%,X7R,CA  I118  C89
   1 P1V8_AUX      A @SCM_LIB.SCM(SCH_1):P1V8_AUX
   2    GND      B @SCM_LIB.SCM(SCH_1):GND

Q_CAP_0402-0.1UF,25V,10%,X7R,CA  I119  C95
   1 P1V8_AUX      A @SCM_LIB.SCM(SCH_1):P1V8_AUX
   2    GND      B @SCM_LIB.SCM(SCH_1):GND

Q_CAP_0402-0.1UF,25V,10%,X7R,CA  I120  C85
   1 P3V3_RGM      A @SCM_LIB.SCM(SCH_1):P3V3_RGM
   2    GND      B @SCM_LIB.SCM(SCH_1):GND

Q_CAP_0402-0.1UF,25V,10%,X7R,CA  I123  C88
   1 P3V3_AUX      A @SCM_LIB.SCM(SCH_1):P3V3_AUX
   2    GND      B @SCM_LIB.SCM(SCH_1):GND

Q_CAP_0402-0.1UF,25V,10%,X7R,CA  I124  C94
   1 P3V3_AUX      A @SCM_LIB.SCM(SCH_1):P3V3_AUX
   2    GND      B @SCM_LIB.SCM(SCH_1):GND

Q_CAP_0402-0.1UF,25V,10%,X7R,CA  I126  C102
   1 P1V8_AUX      A @SCM_LIB.SCM(SCH_1):P1V8_AUX
   2    GND      B @SCM_LIB.SCM(SCH_1):GND

Q_CAP_C0402-1UF,25V,10%,X6S,CHA  I127  C106
   1 P1V8_AUX      A @SCM_LIB.SCM(SCH_1):P1V8_AUX
   2    GND      B @SCM_LIB.SCM(SCH_1):GND

Q_CAP_C0402-1UF,25V,10%,X6S,CHA  I128  C111
   1 P1V8_AUX      A @SCM_LIB.SCM(SCH_1):P1V8_AUX
   2    GND      B @SCM_LIB.SCM(SCH_1):GND

Q_CAP_C0402-1UF,25V,10%,X6S,CHA  I129  C116
   1 P1V8_AUX      A @SCM_LIB.SCM(SCH_1):P1V8_AUX
   2    GND      B @SCM_LIB.SCM(SCH_1):GND

Q_CAP_C0603-22UF,6.3V,20%,X6S,A  I131  C121
   1 P1V8_AUX      A @SCM_LIB.SCM(SCH_1):P1V8_AUX
   2    GND      B @SCM_LIB.SCM(SCH_1):GND

Q_CAP_0402-0.1UF,25V,10%,X7R,CA  I132  C101
   1 P3V3_AUX      A @SCM_LIB.SCM(SCH_1):P3V3_AUX
   2    GND      B @SCM_LIB.SCM(SCH_1):GND

Q_CAP_C0402-1UF,25V,10%,X6S,CHA  I133  C110
   1 P3V3_AUX      A @SCM_LIB.SCM(SCH_1):P3V3_AUX
   2    GND      B @SCM_LIB.SCM(SCH_1):GND

Q_CAP_C0402-1UF,25V,10%,X6S,CHA  I135  C115
   1 P3V3_AUX      A @SCM_LIB.SCM(SCH_1):P3V3_AUX
   2    GND      B @SCM_LIB.SCM(SCH_1):GND

Q_CAP_C0603-22UF,6.3V,20%,X6S,A  I143  C126
   1 P1V8_AUX      A @SCM_LIB.SCM(SCH_1):P1V8_AUX
   2    GND      B @SCM_LIB.SCM(SCH_1):GND

Q_CAP_0402-0.1UF,25V,10%,X7R,CA  I147  C87
   1 P1V8_AUX      A @SCM_LIB.SCM(SCH_1):P1V8_AUX
   2    GND      B @SCM_LIB.SCM(SCH_1):GND

Q_CAP_0402-0.1UF,25V,10%,X7R,CA  I148  C93
   1 P1V8_AUX      A @SCM_LIB.SCM(SCH_1):P1V8_AUX
   2    GND      B @SCM_LIB.SCM(SCH_1):GND

Q_CAP_0402-0.1UF,25V,10%,X7R,CA  I149  C86
   1 P1V0_AUX      A @SCM_LIB.SCM(SCH_1):P1V0_AUX
   2    GND      B @SCM_LIB.SCM(SCH_1):GND

Q_CAP_0402-0.1UF,25V,10%,X7R,CA  I150  C92
   1 P1V0_AUX      A @SCM_LIB.SCM(SCH_1):P1V0_AUX
   2    GND      B @SCM_LIB.SCM(SCH_1):GND

Q_CAP_0402-0.1UF,25V,10%,X7R,CA  I151  C91
   1 P1V2_AUX      A @SCM_LIB.SCM(SCH_1):P1V2_AUX
   2    GND      B @SCM_LIB.SCM(SCH_1):GND

Q_CAP_0402-0.1UF,25V,10%,X7R,CA  I152  C100
   1 P1V8_AUX      A @SCM_LIB.SCM(SCH_1):P1V8_AUX
   2    GND      B @SCM_LIB.SCM(SCH_1):GND

Q_CAP_0402-0.1UF,25V,10%,X7R,CA  I153  C105
   1 P1V8_AUX      A @SCM_LIB.SCM(SCH_1):P1V8_AUX
   2    GND      B @SCM_LIB.SCM(SCH_1):GND

Q_CAP_0402-0.1UF,25V,10%,X7R,CA  I154  C99
   1 P1V0_AUX      A @SCM_LIB.SCM(SCH_1):P1V0_AUX
   2    GND      B @SCM_LIB.SCM(SCH_1):GND

Q_CAP_C0402-1UF,25V,10%,X6S,CHA  I155  C104
   1 P1V0_AUX      A @SCM_LIB.SCM(SCH_1):P1V0_AUX
   2    GND      B @SCM_LIB.SCM(SCH_1):GND

Q_CAP_0402-0.1UF,25V,10%,X7R,CA  I156  C109
   1 P1V8_AUX      A @SCM_LIB.SCM(SCH_1):P1V8_AUX
   2    GND      B @SCM_LIB.SCM(SCH_1):GND

Q_CAP_C0402-1UF,25V,10%,X6S,CHA  I157  C108
   1 P1V0_AUX      A @SCM_LIB.SCM(SCH_1):P1V0_AUX
   2    GND      B @SCM_LIB.SCM(SCH_1):GND

Q_CAP_C0402-1UF,25V,10%,X6S,CHA  I158  C114
   1 P1V8_AUX      A @SCM_LIB.SCM(SCH_1):P1V8_AUX
   2    GND      B @SCM_LIB.SCM(SCH_1):GND

Q_CAP_C0402-1UF,25V,10%,X6S,CHA  I159  C119
   1 P1V8_AUX      A @SCM_LIB.SCM(SCH_1):P1V8_AUX
   2    GND      B @SCM_LIB.SCM(SCH_1):GND

Q_CAP_C0603-22UF,6.3V,20%,X6S,A  I162  C118
   1 P1V0_AUX      A @SCM_LIB.SCM(SCH_1):P1V0_AUX
   2    GND      B @SCM_LIB.SCM(SCH_1):GND

Q_CAP_0402-0.1UF,25V,10%,X7R,CA  I163  C98
   1 P1V2_AUX      A @SCM_LIB.SCM(SCH_1):P1V2_AUX
   2    GND      B @SCM_LIB.SCM(SCH_1):GND

Q_CAP_0402-0.1UF,25V,10%,X7R,CA  I164  C103
   1 P1V2_AUX      A @SCM_LIB.SCM(SCH_1):P1V2_AUX
   2    GND      B @SCM_LIB.SCM(SCH_1):GND

Q_CAP_0402-0.1UF,25V,10%,X7R,CA  I165  C107
   1 P1V2_AUX      A @SCM_LIB.SCM(SCH_1):P1V2_AUX
   2    GND      B @SCM_LIB.SCM(SCH_1):GND

Q_CAP_0402-0.1UF,25V,10%,X7R,CA  I166  C112
   1 P1V2_AUX      A @SCM_LIB.SCM(SCH_1):P1V2_AUX
   2    GND      B @SCM_LIB.SCM(SCH_1):GND

Q_CAP_C0402-1UF,25V,10%,X6S,CHA  I167  C117
   1 P1V2_AUX      A @SCM_LIB.SCM(SCH_1):P1V2_AUX
   2    GND      B @SCM_LIB.SCM(SCH_1):GND

Q_CAP_C0402-1UF,25V,10%,X6S,CHA  I168  C122
   1 P1V2_AUX      A @SCM_LIB.SCM(SCH_1):P1V2_AUX
   2    GND      B @SCM_LIB.SCM(SCH_1):GND

Q_CAP_C0603-22UF,6.3V,20%,X6S,A  I169  C124
   1 P1V8_AUX      A @SCM_LIB.SCM(SCH_1):P1V8_AUX
   2    GND      B @SCM_LIB.SCM(SCH_1):GND

Q_CAP_C0603-22UF,6.3V,20%,X6S,A  I171  C123
   1 P1V0_AUX      A @SCM_LIB.SCM(SCH_1):P1V0_AUX
   2    GND      B @SCM_LIB.SCM(SCH_1):GND

Q_CAP_C0402-1UF,25V,10%,X6S,CHA  I173  C127
   1 P1V2_AUX      A @SCM_LIB.SCM(SCH_1):P1V2_AUX
   2    GND      B @SCM_LIB.SCM(SCH_1):GND

Q_CAP_C0402-1UF,25V,10%,X6S,CHA  I174  C129
   1 P1V2_AUX      A @SCM_LIB.SCM(SCH_1):P1V2_AUX
   2    GND      B @SCM_LIB.SCM(SCH_1):GND

Q_CAP_0402-0.1UF,25V,10%,X7R,CA  I179  C84
   1 P1V2_AUX      A @SCM_LIB.SCM(SCH_1):P1V2_AUX
   2    GND      B @SCM_LIB.SCM(SCH_1):GND

Q_CAP_0402-0.1UF,25V,10%,X7R,CA  I180  C82
   1 P1V2_AUX      A @SCM_LIB.SCM(SCH_1):P1V2_AUX
   2    GND      B @SCM_LIB.SCM(SCH_1):GND

Q_CAP_0402-0.1UF,25V,10%,X7R,CA  I183  C76
   1 P1V2_AUX      A @SCM_LIB.SCM(SCH_1):P1V2_AUX
   2    GND      B @SCM_LIB.SCM(SCH_1):GND

Q_RES_0402LF-2.74K,1%,1/16W,CHA  I187  R235
   1    GND      A @SCM_LIB.SCM(SCH_1):GND
   2 A_BMC_DACREST      B @SCM_LIB.SCM(SCH_1):A_BMC_DACREST

AST2600A3GP-AST2600A3-GP,SMLF,A  I188  U5
AF20 A_BMC_ADCREXT0 ADCREXT0 @SCM_LIB.SCM(SCH_1):A_BMC_ADCREXT0
AB20 A_BMC_ADCVREFN0 ADCVREFN0 @SCM_LIB.SCM(SCH_1):A_BMC_ADCVREFN0
AC20 A_BMC_ADCVREFP0 ADCVREFP0 @SCM_LIB.SCM(SCH_1):A_BMC_ADCVREFP0
 Y21 A_BMC_ADCAV33 ADCAV33_Y21 @SCM_LIB.SCM(SCH_1):A_BMC_ADCAV33
 V21 P3V3_STBY_DACAV33 DACAV33_V21 @SCM_LIB.SCM(SCH_1):P3V3_STBY_DACAV33
AC21 A_BMC_DACREST DACRSET @SCM_LIB.SCM(SCH_1):A_BMC_DACREST
  E7 P1V0_STBY_PLAVDD PLLAVDD_E7 @SCM_LIB.SCM(SCH_1):P1V0_STBY_PLAVDD
 H14 P3V3_STBY_PLLAHVDD PLLAHVDD @SCM_LIB.SCM(SCH_1):P3V3_STBY_PLLAHVDD
AD17 A_BMC_ADCVREFP1 ADCVREFP1 @SCM_LIB.SCM(SCH_1):A_BMC_ADCVREFP1
AD18 A_BMC_ADCVREFN1 ADCVREFN1 @SCM_LIB.SCM(SCH_1):A_BMC_ADCVREFN1
AF18 A_BMC_ADCREXT1 ADCREXT1 @SCM_LIB.SCM(SCH_1):A_BMC_ADCREXT1
  L9 P1V0_AUX IV10D_L9 @SCM_LIB.SCM(SCH_1):P1V0_AUX
 L10 P1V0_AUX IV10D_L10 @SCM_LIB.SCM(SCH_1):P1V0_AUX
  M8 P1V0_AUX IV10D_M8 @SCM_LIB.SCM(SCH_1):P1V0_AUX
  N5 P1V8_STBY_AVDDPLL AVDDPLL @SCM_LIB.SCM(SCH_1):P1V8_STBY_AVDDPLL
  G6 P1V2_AUX MVDD_G6 @SCM_LIB.SCM(SCH_1):P1V2_AUX
  F7 P1V0_STBY_PLAVDD PLLAVDD_F7 @SCM_LIB.SCM(SCH_1):P1V0_STBY_PLAVDD
 W21 P3V3_STBY_DACAV33 DACAV33_W21 @SCM_LIB.SCM(SCH_1):P3V3_STBY_DACAV33
  E9 P1V0_STBY_PLAVDD PLLDVDD_E9 @SCM_LIB.SCM(SCH_1):P1V0_STBY_PLAVDD
  F9 P1V0_STBY_PLAVDD PLLDVDD_F9 @SCM_LIB.SCM(SCH_1):P1V0_STBY_PLAVDD
  T9 P1V0_STBY_PE_VCC10A RC_VCC10A @SCM_LIB.SCM(SCH_1):P1V0_STBY_PE_VCC10A
  V9 P1V8_STBY_PE_VCC18A RC_VCC18A @SCM_LIB.SCM(SCH_1):P1V8_STBY_PE_VCC18A
 T10 P1V0_STBY_RC_VCC10A PE_VCC10A @SCM_LIB.SCM(SCH_1):P1V0_STBY_RC_VCC10A
 V10 P1V8_STBY_RC_VCC18A PE_VCC18A @SCM_LIB.SCM(SCH_1):P1V8_STBY_RC_VCC18A
  V8 P1V8_STBY_DP_VCC18A DP_VCC18A @SCM_LIB.SCM(SCH_1):P1V8_STBY_DP_VCC18A
  T8 P1V0_STBY_DP_VCC10A DP_VCC10A @SCM_LIB.SCM(SCH_1):P1V0_STBY_DP_VCC10A
  H6 P1V2_AUX MVDD_H6 @SCM_LIB.SCM(SCH_1):P1V2_AUX
  J6 P1V2_AUX MVDD_J6 @SCM_LIB.SCM(SCH_1):P1V2_AUX
  K6 P1V2_AUX MVDD_K6 @SCM_LIB.SCM(SCH_1):P1V2_AUX
  L6 P1V2_AUX MVDD_L6 @SCM_LIB.SCM(SCH_1):P1V2_AUX
  P6 P1V2_AUX MVDD_P6 @SCM_LIB.SCM(SCH_1):P1V2_AUX
  R6 P1V2_AUX MVDD_R6 @SCM_LIB.SCM(SCH_1):P1V2_AUX
  T6 P1V2_AUX MVDD_T6 @SCM_LIB.SCM(SCH_1):P1V2_AUX
  M6 P1V2_STBY_MVDD_CK MVDD_CK @SCM_LIB.SCM(SCH_1):P1V2_STBY_MVDD_CK
 K16 P1V2_AUX IV12D_K16 @SCM_LIB.SCM(SCH_1):P1V2_AUX
 K17 P1V2_AUX IV12D_K17 @SCM_LIB.SCM(SCH_1):P1V2_AUX
 K18 P1V2_AUX IV12D_K18 @SCM_LIB.SCM(SCH_1):P1V2_AUX
 K19 P1V2_AUX IV12D_K19 @SCM_LIB.SCM(SCH_1):P1V2_AUX
 L14 P1V2_AUX IV12D_L14 @SCM_LIB.SCM(SCH_1):P1V2_AUX
 M14 P1V2_AUX IV12D_M14 @SCM_LIB.SCM(SCH_1):P1V2_AUX
 N14 P1V2_AUX IV12D_N14 @SCM_LIB.SCM(SCH_1):P1V2_AUX
 P14 P1V2_AUX IV12D_P14 @SCM_LIB.SCM(SCH_1):P1V2_AUX
 R14 P1V2_AUX IV12D_R14 @SCM_LIB.SCM(SCH_1):P1V2_AUX
 T14 P1V2_AUX IV12D_T14 @SCM_LIB.SCM(SCH_1):P1V2_AUX
 L21 P1V2_AUX IV12D_L21 @SCM_LIB.SCM(SCH_1):P1V2_AUX
 M21 P1V2_AUX IV12D_M21 @SCM_LIB.SCM(SCH_1):P1V2_AUX
 N21 P1V2_AUX IV12D_N21 @SCM_LIB.SCM(SCH_1):P1V2_AUX
 P21 P1V2_AUX IV12D_P21 @SCM_LIB.SCM(SCH_1):P1V2_AUX
 R21 P1V2_AUX IV12D_R21 @SCM_LIB.SCM(SCH_1):P1V2_AUX
 T21 P1V2_AUX IV12D_T21 @SCM_LIB.SCM(SCH_1):P1V2_AUX
 U15 P1V2_AUX IV12D_U15 @SCM_LIB.SCM(SCH_1):P1V2_AUX
 U16 P1V2_AUX IV12D_U16 @SCM_LIB.SCM(SCH_1):P1V2_AUX
 U17 P1V2_AUX IV12D_U17 @SCM_LIB.SCM(SCH_1):P1V2_AUX
 U18 P1V2_AUX IV12D_U18 @SCM_LIB.SCM(SCH_1):P1V2_AUX
 L22 P3V3_P2V5_P1V8_RVDD RVDD_L22 @SCM_LIB.SCM(SCH_1):P3V3_P2V5_P1V8_RVDD
 M22 P3V3_P2V5_P1V8_RVDD RVDD_M22 @SCM_LIB.SCM(SCH_1):P3V3_P2V5_P1V8_RVDD
 J21 P3V3_P2V5_P1V8_RVDD RVDD_J21 @SCM_LIB.SCM(SCH_1):P3V3_P2V5_P1V8_RVDD
 K21 P3V3_P2V5_P1V8_RVDD RVDD_K21 @SCM_LIB.SCM(SCH_1):P3V3_P2V5_P1V8_RVDD
 G21 P3V3_P1V8_SD1VDD SD1VDD_G21 @SCM_LIB.SCM(SCH_1):P3V3_P1V8_SD1VDD
 H18 P3V3_P1V8_SD2VDD SD2VDD_H18 @SCM_LIB.SCM(SCH_1):P3V3_P1V8_SD2VDD
 W15 PGPPA_BMC_AUX  LPVDD @SCM_LIB.SCM(SCH_1):PGPPA_BMC_AUX
 F19 P3V3_P1V8_I2C_I3C I3CVDDH_F19 @SCM_LIB.SCM(SCH_1):P3V3_P1V8_I2C_I3C
  N8 P1V0_AUX IV10D_N8 @SCM_LIB.SCM(SCH_1):P1V0_AUX
  P8 P1V0_AUX IV10D_P8 @SCM_LIB.SCM(SCH_1):P1V0_AUX
 M11 P1V0_AUX IV10D_M11 @SCM_LIB.SCM(SCH_1):P1V0_AUX
 N11 P1V0_AUX IV10D_N11 @SCM_LIB.SCM(SCH_1):P1V0_AUX
 P11 P1V0_AUX IV10D_P11 @SCM_LIB.SCM(SCH_1):P1V0_AUX
  R9 P1V0_AUX IV10D_R9 @SCM_LIB.SCM(SCH_1):P1V0_AUX
  U6 P1V8_AUX PV18D_U6 @SCM_LIB.SCM(SCH_1):P1V8_AUX
  V6 P1V8_AUX PV18D_V6 @SCM_LIB.SCM(SCH_1):P1V8_AUX
  H8 P1V8_AUX PV18D_H8 @SCM_LIB.SCM(SCH_1):P1V8_AUX
  J8 P1V8_AUX PV18D_J8 @SCM_LIB.SCM(SCH_1):P1V8_AUX
 H12 P1V8_AUX PV18D_RGM_H12 @SCM_LIB.SCM(SCH_1):P1V8_AUX
 H16 P3V3_AUX PV33D_H16 @SCM_LIB.SCM(SCH_1):P3V3_AUX
 H17 P3V3_AUX PV33D_H17 @SCM_LIB.SCM(SCH_1):P3V3_AUX
 W16 P3V3_AUX PV33D_W16 @SCM_LIB.SCM(SCH_1):P3V3_AUX
 W17 P3V3_AUX PV33D_W17 @SCM_LIB.SCM(SCH_1):P3V3_AUX
 W18 P3V3_AUX PV33D_W18 @SCM_LIB.SCM(SCH_1):P3V3_AUX
 W19 P3V3_AUX PV33D_W19 @SCM_LIB.SCM(SCH_1):P3V3_AUX
 N22 P3V3_AUX PV33D_N22 @SCM_LIB.SCM(SCH_1):P3V3_AUX
 P22 P3V3_AUX PV33D_P22 @SCM_LIB.SCM(SCH_1):P3V3_AUX
 R22 P3V3_AUX PV33D_R22 @SCM_LIB.SCM(SCH_1):P3V3_AUX
 T22 P3V3_AUX PV33D_T22 @SCM_LIB.SCM(SCH_1):P3V3_AUX
 V23 P3V3_RTC_AUX BATVDD @SCM_LIB.SCM(SCH_1):P3V3_RTC_AUX
 L13 P1V8_AUX PV18D_SLI_L13 @SCM_LIB.SCM(SCH_1):P1V8_AUX
 M13 P1V8_AUX PV18D_SLI_M13 @SCM_LIB.SCM(SCH_1):P1V8_AUX
 N13 P1V8_AUX PV18D_SLI_N13 @SCM_LIB.SCM(SCH_1):P1V8_AUX
 P13 P1V8_AUX PV18D_SLI_P13 @SCM_LIB.SCM(SCH_1):P1V8_AUX
 R13 P1V8_AUX PV18D_SLI_R13 @SCM_LIB.SCM(SCH_1):P1V8_AUX
 T13 P1V8_AUX PV18D_SLI_T13 @SCM_LIB.SCM(SCH_1):P1V8_AUX
 U13 P1V8_AUX PV18D_SLI_U13 @SCM_LIB.SCM(SCH_1):P1V8_AUX
 V13 P1V8_AUX PV18D_SLI_V13 @SCM_LIB.SCM(SCH_1):P1V8_AUX
 W13 P1V8_AUX PV18D_SLI_W13 @SCM_LIB.SCM(SCH_1):P1V8_AUX
 W14 P1V8_AUX PV18D_SLI_W14 @SCM_LIB.SCM(SCH_1):P1V8_AUX
AA21 A_BMC_ADCAV33 ADCAV33_AA21 @SCM_LIB.SCM(SCH_1):A_BMC_ADCAV33
 J12 P1V8_AUX PV18D_RGM_J12 @SCM_LIB.SCM(SCH_1):P1V8_AUX
 R10 P1V0_AUX IV10D_R10 @SCM_LIB.SCM(SCH_1):P1V0_AUX
AF19 ADCVREFEXT0 ADCVREFEXT0 @SCM_LIB.SCM(SCH_1):ADCVREFEXT0
AF17 ADCVREFEXT1 ADCVREFEXT1 @SCM_LIB.SCM(SCH_1):ADCVREFEXT1
 N12 P1V8_AUX PV18D_N12 @SCM_LIB.SCM(SCH_1):P1V8_AUX
 P12 P1V8_AUX PV18D_P12 @SCM_LIB.SCM(SCH_1):P1V8_AUX
 R12 P1V8_AUX PV18D_R12 @SCM_LIB.SCM(SCH_1):P1V8_AUX
 H21 P3V3_P1V8_SD1VDD SD1VDD_H21 @SCM_LIB.SCM(SCH_1):P3V3_P1V8_SD1VDD
 H19 P3V3_P1V8_SD2VDD SD2VDD_H19 @SCM_LIB.SCM(SCH_1):P3V3_P1V8_SD2VDD
 F20 P3V3_P1V8_I2C_I3C I3CVDDH_F20 @SCM_LIB.SCM(SCH_1):P3V3_P1V8_I2C_I3C
 H15 P3V3_AUX PV33D_H15 @SCM_LIB.SCM(SCH_1):P3V3_AUX
  J9 P1V0_STBY_PLAVDD DPLLAVDD @SCM_LIB.SCM(SCH_1):P1V0_STBY_PLAVDD
 V22 P1V2_P1V0_I3C_VDDL1 I3CVDDL1 @SCM_LIB.SCM(SCH_1):P1V2_P1V0_I3C_VDDL1
 U21 P1V2_P1V0_I3C_VDDL2 I3CVDDL2 @SCM_LIB.SCM(SCH_1):P1V2_P1V0_I3C_VDDL2
 K11 P3V3_RGM PV33D_RGM_K11 @SCM_LIB.SCM(SCH_1):P3V3_RGM
 K12 P3V3_RGM PV33D_RGM_K12 @SCM_LIB.SCM(SCH_1):P3V3_RGM

Q_CAP_C0603-22UF,6.3V,20%,X6S,A  I189  C113
   1 P1V0_AUX      A @SCM_LIB.SCM(SCH_1):P1V0_AUX
   2    GND      B @SCM_LIB.SCM(SCH_1):GND

Q_CAP_C0603-22UF,6.3V,20%,X6S,A  I190  C120
   1 P3V3_AUX      A @SCM_LIB.SCM(SCH_1):P3V3_AUX
   2    GND      B @SCM_LIB.SCM(SCH_1):GND

Q_CAP_C0603-22UF,6.3V,20%,X6S,A  I191  C125
   1 P3V3_AUX      A @SCM_LIB.SCM(SCH_1):P3V3_AUX
   2    GND      B @SCM_LIB.SCM(SCH_1):GND

Q_CAP_C0603-22UF,6.3V,20%,X6S,A  I192  C131
   1 P1V2_AUX      A @SCM_LIB.SCM(SCH_1):P1V2_AUX
   2    GND      B @SCM_LIB.SCM(SCH_1):GND

Q_CAP_C0603-22UF,6.3V,20%,X6S,A  I193  C132
   1 P1V2_AUX      A @SCM_LIB.SCM(SCH_1):P1V2_AUX
   2    GND      B @SCM_LIB.SCM(SCH_1):GND


DRAWING: @SCM_LIB.SCM(SCH_1):PAGE17 

Q_RES_0402LF-0,5%,1/16W,CHIP,CA  I92  R281
   1 P1V0_AUX      A @SCM_LIB.SCM(SCH_1):P1V0_AUX
   2 P1V2_P1V0_I3C_VDDL2      B @SCM_LIB.SCM(SCH_1):P1V2_P1V0_I3C_VDDL2

Q_RES_0402LF-0,5%,1/16W,EMPTY,A  I94  R280
   1 P1V2_AUX      A @SCM_LIB.SCM(SCH_1):P1V2_AUX
   2 P1V2_P1V0_I3C_VDDL2      B @SCM_LIB.SCM(SCH_1):P1V2_P1V0_I3C_VDDL2

Q_RES_0402LF-0,5%,1/16W,CHIP,CA  I95  R279
   1 P1V0_AUX      A @SCM_LIB.SCM(SCH_1):P1V0_AUX
   2 P1V2_P1V0_I3C_VDDL1      B @SCM_LIB.SCM(SCH_1):P1V2_P1V0_I3C_VDDL1

Q_CAP_0402-0.1UF,25V,10%,X7R,CA  I97  C140
   1 P1V2_P1V0_I3C_VDDL2      A @SCM_LIB.SCM(SCH_1):P1V2_P1V0_I3C_VDDL2
   2    GND      B @SCM_LIB.SCM(SCH_1):GND

Q_CAP_0402-0.1UF,25V,10%,X7R,CA  I98  C139
   1 P1V2_P1V0_I3C_VDDL1      A @SCM_LIB.SCM(SCH_1):P1V2_P1V0_I3C_VDDL1
   2    GND      B @SCM_LIB.SCM(SCH_1):GND

Q_RES_0402LF-0,5%,1/16W,EMPTY,A  I101  R278
   1 P1V2_AUX      A @SCM_LIB.SCM(SCH_1):P1V2_AUX
   2 P1V2_P1V0_I3C_VDDL1      B @SCM_LIB.SCM(SCH_1):P1V2_P1V0_I3C_VDDL1

Q_CAP_C0402-0.01UF,50V,10%,X7RA  I104  C133
   1    GND      A @SCM_LIB.SCM(SCH_1):GND
   2 A_BMC_ADCVREFN1      B @SCM_LIB.SCM(SCH_1):A_BMC_ADCVREFN1

Q_CAP_C0402-0.01UF,50V,10%,X7RA  I106  C134
   1    GND      A @SCM_LIB.SCM(SCH_1):GND
   2 A_BMC_ADCVREFN0      B @SCM_LIB.SCM(SCH_1):A_BMC_ADCVREFN0

Q_CAP_C0402-0.01UF,50V,10%,X7RA  I107  C135
   1    GND      A @SCM_LIB.SCM(SCH_1):GND
   2 A_BMC_ADCVREFP1      B @SCM_LIB.SCM(SCH_1):A_BMC_ADCVREFP1

Q_CAP_C0402-0.01UF,50V,10%,X7RA  I108  C137
   1 A_BMC_ADCVREFN1      A @SCM_LIB.SCM(SCH_1):A_BMC_ADCVREFN1
   2 A_BMC_ADCVREFP1      B @SCM_LIB.SCM(SCH_1):A_BMC_ADCVREFP1

Q_CAP_C0402-0.01UF,50V,10%,X7RA  I109  C138
   1 A_BMC_ADCVREFN0      A @SCM_LIB.SCM(SCH_1):A_BMC_ADCVREFN0
   2 A_BMC_ADCVREFP0      B @SCM_LIB.SCM(SCH_1):A_BMC_ADCVREFP0

Q_CAP_C0402-0.01UF,50V,10%,X7RA  I110  C136
   1    GND      A @SCM_LIB.SCM(SCH_1):GND
   2 A_BMC_ADCVREFP0      B @SCM_LIB.SCM(SCH_1):A_BMC_ADCVREFP0

Q_CAP_0402-0.1UF,25V,10%,X7R,CA  I118  C49
   1 P1V8_STBY_AVDDPLL      A @SCM_LIB.SCM(SCH_1):P1V8_STBY_AVDDPLL
   2    GND      B @SCM_LIB.SCM(SCH_1):GND

Q_INDUCTOR_SMLF-BLM18PG121SN1DA  I120  L5
   2 P1V8_STBY_AVDDPLL      2 @SCM_LIB.SCM(SCH_1):P1V8_STBY_AVDDPLL
   1 P1V8_AUX      1 @SCM_LIB.SCM(SCH_1):P1V8_AUX

Q_CAP_C0402-1UF,25V,10%,X6S,CHA  I122  C46
   1 P1V8_STBY_AVDDPLL      A @SCM_LIB.SCM(SCH_1):P1V8_STBY_AVDDPLL
   2    GND      B @SCM_LIB.SCM(SCH_1):GND

Q_INDUCTOR_SMLF-BLM18PG121SN1DA  I124  L6
   2 P1V0_STBY_RC_VCC10A      2 @SCM_LIB.SCM(SCH_1):P1V0_STBY_RC_VCC10A
   1 P1V0_AUX      1 @SCM_LIB.SCM(SCH_1):P1V0_AUX

Q_CAP_0402-0.1UF,25V,10%,X7R,CA  I126  C50
   1 P1V0_STBY_RC_VCC10A      A @SCM_LIB.SCM(SCH_1):P1V0_STBY_RC_VCC10A
   2    GND      B @SCM_LIB.SCM(SCH_1):GND

Q_CAP_C0402-1UF,25V,10%,X6S,CHA  I128  C47
   1 P1V0_STBY_RC_VCC10A      A @SCM_LIB.SCM(SCH_1):P1V0_STBY_RC_VCC10A
   2    GND      B @SCM_LIB.SCM(SCH_1):GND

Q_RES_0402LF-0,5%,1/16W,CHIP,CA  I131  R231
   1 P3V3_AUX      A @SCM_LIB.SCM(SCH_1):P3V3_AUX
   2 P3V3_P1V8_I2C_I3C      B @SCM_LIB.SCM(SCH_1):P3V3_P1V8_I2C_I3C

Q_CAP_0402-0.1UF,25V,10%,X7R,CA  I133  C57
   1 P3V3_P1V8_I2C_I3C      A @SCM_LIB.SCM(SCH_1):P3V3_P1V8_I2C_I3C
   2    GND      B @SCM_LIB.SCM(SCH_1):GND

Q_CAP_C0402-1UF,25V,10%,X6S,CHA  I135  C53
   1 P3V3_P1V8_I2C_I3C      A @SCM_LIB.SCM(SCH_1):P3V3_P1V8_I2C_I3C
   2    GND      B @SCM_LIB.SCM(SCH_1):GND

Q_RES_0402LF-0,5%,1/16W,EMPTY,A  I136  R232
   1 P1V8_AUX      A @SCM_LIB.SCM(SCH_1):P1V8_AUX
   2 P3V3_P1V8_I2C_I3C      B @SCM_LIB.SCM(SCH_1):P3V3_P1V8_I2C_I3C

Q_CAP_0402-0.1UF,25V,10%,X7R,CA  I139  C65
   1 P3V3_STBY_PLLAHVDD      A @SCM_LIB.SCM(SCH_1):P3V3_STBY_PLLAHVDD
   2    GND      B @SCM_LIB.SCM(SCH_1):GND

Q_CAP_C0402-1UF,25V,10%,X6S,CHA  I141  C60
   1 P3V3_STBY_PLLAHVDD      A @SCM_LIB.SCM(SCH_1):P3V3_STBY_PLLAHVDD
   2    GND      B @SCM_LIB.SCM(SCH_1):GND

Q_INDUCTOR_SMLF-BLM18PG121SN1DB  I142  L9
   2 P3V3_STBY_PLLAHVDD      2 @SCM_LIB.SCM(SCH_1):P3V3_STBY_PLLAHVDD
   1 P3V3_AUX      1 @SCM_LIB.SCM(SCH_1):P3V3_AUX

Q_CAP_0402-0.1UF,25V,10%,X7R,CA  I145  C51
   1 P3V3_STBY_DACAV33      A @SCM_LIB.SCM(SCH_1):P3V3_STBY_DACAV33
   2    GND      B @SCM_LIB.SCM(SCH_1):GND

Q_INDUCTOR_SMLF-BLM18PG121SN1DA  I146  L7
   2 P3V3_STBY_DACAV33      2 @SCM_LIB.SCM(SCH_1):P3V3_STBY_DACAV33
   1 P3V3_AUX      1 @SCM_LIB.SCM(SCH_1):P3V3_AUX

Q_CAP_C0402-1UF,25V,10%,X6S,CHA  I148  C48
   1 P3V3_STBY_DACAV33      A @SCM_LIB.SCM(SCH_1):P3V3_STBY_DACAV33
   2    GND      B @SCM_LIB.SCM(SCH_1):GND

Q_CAP_0402-0.1UF,25V,10%,X7R,CA  I151  C81
   1 P1V8_STBY_RC_VCC18A      A @SCM_LIB.SCM(SCH_1):P1V8_STBY_RC_VCC18A
   2    GND      B @SCM_LIB.SCM(SCH_1):GND

Q_CAP_C0402-1UF,25V,10%,X6S,CHA  I153  C80
   1 P1V8_STBY_RC_VCC18A      A @SCM_LIB.SCM(SCH_1):P1V8_STBY_RC_VCC18A
   2    GND      B @SCM_LIB.SCM(SCH_1):GND

Q_INDUCTOR_SMLF-BLM18PG121SN1DA  I154  L14
   2 P1V8_STBY_RC_VCC18A      2 @SCM_LIB.SCM(SCH_1):P1V8_STBY_RC_VCC18A
   1 P1V8_AUX      1 @SCM_LIB.SCM(SCH_1):P1V8_AUX

Q_CAP_0402-0.1UF,25V,10%,X7R,CA  I157  C79
   1 P1V0_STBY_PE_VCC10A      A @SCM_LIB.SCM(SCH_1):P1V0_STBY_PE_VCC10A
   2    GND      B @SCM_LIB.SCM(SCH_1):GND

Q_INDUCTOR_SMLF-BLM18PG121SN1DA  I158  L13
   2 P1V0_STBY_PE_VCC10A      2 @SCM_LIB.SCM(SCH_1):P1V0_STBY_PE_VCC10A
   1 P1V0_AUX      1 @SCM_LIB.SCM(SCH_1):P1V0_AUX

Q_CAP_C0402-1UF,25V,10%,X6S,CHA  I160  C78
   1 P1V0_STBY_PE_VCC10A      A @SCM_LIB.SCM(SCH_1):P1V0_STBY_PE_VCC10A
   2    GND      B @SCM_LIB.SCM(SCH_1):GND

Q_CAP_0402-0.1UF,25V,10%,X7R,CA  I163  C130
   1 P1V8_STBY_DP_VCC18A      A @SCM_LIB.SCM(SCH_1):P1V8_STBY_DP_VCC18A
   2    GND      B @SCM_LIB.SCM(SCH_1):GND

Q_CAP_C0402-1UF,25V,10%,X6S,CHA  I165  C128
   1 P1V8_STBY_DP_VCC18A      A @SCM_LIB.SCM(SCH_1):P1V8_STBY_DP_VCC18A
   2    GND      B @SCM_LIB.SCM(SCH_1):GND

Q_INDUCTOR_SMLF-BLM18PG121SN1DA  I166  L16
   2 P1V8_STBY_DP_VCC18A      2 @SCM_LIB.SCM(SCH_1):P1V8_STBY_DP_VCC18A
   1 P1V8_AUX      1 @SCM_LIB.SCM(SCH_1):P1V8_AUX

Q_CAP_0402-0.1UF,25V,10%,X7R,CA  I169  C97
   1 P1V0_STBY_DP_VCC10A      A @SCM_LIB.SCM(SCH_1):P1V0_STBY_DP_VCC10A
   2    GND      B @SCM_LIB.SCM(SCH_1):GND

Q_INDUCTOR_SMLF-BLM18PG121SN1DA  I170  L15
   2 P1V0_STBY_DP_VCC10A      2 @SCM_LIB.SCM(SCH_1):P1V0_STBY_DP_VCC10A
   1 P1V0_AUX      1 @SCM_LIB.SCM(SCH_1):P1V0_AUX

Q_CAP_C0402-1UF,25V,10%,X6S,CHA  I173  C90
   1 P1V0_STBY_DP_VCC10A      A @SCM_LIB.SCM(SCH_1):P1V0_STBY_DP_VCC10A
   2    GND      B @SCM_LIB.SCM(SCH_1):GND

Q_INDUCTOR_SMLF-BLM18EG121SN1DA  I176  L17
   2 PGPPA_BMC_AUX      2 @SCM_LIB.SCM(SCH_1):PGPPA_BMC_AUX
   1 PGPPA_BMC_AUX_L      1 @SCM_LIB.SCM(SCH_1):PGPPA_BMC_AUX_L

Q_CAP_0402-0.1UF,25V,10%,X7R,CA  I178  C96
   1 PGPPA_BMC_AUX      A @SCM_LIB.SCM(SCH_1):PGPPA_BMC_AUX
   2    GND      B @SCM_LIB.SCM(SCH_1):GND

Q_CAP_C0402-10UF,6.3V,20%,X6S,A  I180  C224
   1 PGPPA_BMC_AUX      A @SCM_LIB.SCM(SCH_1):PGPPA_BMC_AUX
   2    GND      B @SCM_LIB.SCM(SCH_1):GND

MOSFET_N_GSD-DMG6968U-7,SMLF,IA  I227  Q10
   G LPC_ESPI_SEL_R   GATE @SCM_LIB.SCM(SCH_1):LPC_ESPI_SEL_R
   S    GND SOURCE @SCM_LIB.SCM(SCH_1):GND
   D LPC_ESPI_SEL_N  DRAIN @SCM_LIB.SCM(SCH_1):LPC_ESPI_SEL_N

Q_RES_0402LF-33.2,1%,1/16W,CHIA  I228  R713
   1 LPC_ESPI_SEL_R      A @SCM_LIB.SCM(SCH_1):LPC_ESPI_SEL_R
   2 LPC_ESPI_SEL      B @SCM_LIB.SCM(SCH_1):LPC_ESPI_SEL

Q_RES_0402LF-10K,1%,1/16W,CHIPA  I230  R716
   1 P5V_AUX      A @SCM_LIB.SCM(SCH_1):P5V_AUX
   2 LPC_ESPI_SEL_N      B @SCM_LIB.SCM(SCH_1):LPC_ESPI_SEL_N

Q_CAP_0402-1UF,16V,10%,EMPTY,TA  I234  C273
   1 LPC_ESPI_SEL_R      A @SCM_LIB.SCM(SCH_1):LPC_ESPI_SEL_R
   2    GND      B @SCM_LIB.SCM(SCH_1):GND

Q_CAP_0402-1UF,16V,10%,EMPTY,TA  I239  C270
   1 LPC_ESPI_SEL_N      A @SCM_LIB.SCM(SCH_1):LPC_ESPI_SEL_N
   2    GND      B @SCM_LIB.SCM(SCH_1):GND

Q_CAP_0402-0.1UF,25V,10%,X7R,CA  I250  C284
   1 ADCVREFEXT0      A @SCM_LIB.SCM(SCH_1):ADCVREFEXT0
   2    GND      B @SCM_LIB.SCM(SCH_1):GND

Q_CAP_C0402-1UF,25V,10%,X6S,CHA  I252  C282
   1 ADCVREFEXT0      A @SCM_LIB.SCM(SCH_1):ADCVREFEXT0
   2    GND      B @SCM_LIB.SCM(SCH_1):GND

Q_CAP_C0402-1UF,25V,10%,X6S,CHA  I253  C277
   1 ADCVREFEXT1      A @SCM_LIB.SCM(SCH_1):ADCVREFEXT1
   2    GND      B @SCM_LIB.SCM(SCH_1):GND

Q_CAP_0402-0.1UF,25V,10%,X7R,CA  I255  C279
   1 ADCVREFEXT1      A @SCM_LIB.SCM(SCH_1):ADCVREFEXT1
   2    GND      B @SCM_LIB.SCM(SCH_1):GND

Q_RES_0402LF-0,5%,1/16W,EMPTY,A  I256  R780
   1 P2V5_AUX      A @SCM_LIB.SCM(SCH_1):P2V5_AUX
   2 ADCVREFEXT0      B @SCM_LIB.SCM(SCH_1):ADCVREFEXT0

Q_RES_0402LF-0,5%,1/16W,CHIP,CA  I259  R779
   1 P2V5_AUX      A @SCM_LIB.SCM(SCH_1):P2V5_AUX
   2 ADCVREFEXT1      B @SCM_LIB.SCM(SCH_1):ADCVREFEXT1

Q_RES_0402LF-0,5%,1/16W,CHIP,CA  I260  R783
   1 P1V8_AUX      A @SCM_LIB.SCM(SCH_1):P1V8_AUX
   2 ADCVREFEXT0      B @SCM_LIB.SCM(SCH_1):ADCVREFEXT0

Q_RES_0402LF-0,5%,1/16W,EMPTY,A  I263  R781
   1 P1V8_AUX      A @SCM_LIB.SCM(SCH_1):P1V8_AUX
   2 ADCVREFEXT1      B @SCM_LIB.SCM(SCH_1):ADCVREFEXT1

Q_RES_0402LF-0,5%,1/16W,EMPTY,A  I264  R782
   1 P1V2_AUX      A @SCM_LIB.SCM(SCH_1):P1V2_AUX
   2 ADCVREFEXT1      B @SCM_LIB.SCM(SCH_1):ADCVREFEXT1

Q_RES_0402LF-0,5%,1/16W,EMPTY,A  I267  R784
   1 P1V2_AUX      A @SCM_LIB.SCM(SCH_1):P1V2_AUX
   2 ADCVREFEXT0      B @SCM_LIB.SCM(SCH_1):ADCVREFEXT0

Q_INDUCTOR_SMLF-BLM18PG121SN1DA  I272  L2
   2 P3V3_STBY_PLLAHVDD      2 @SCM_LIB.SCM(SCH_1):P3V3_STBY_PLLAHVDD
   1 P1V2_AUX      1 @SCM_LIB.SCM(SCH_1):P1V2_AUX

MOSFET_NCH_4D1S-NTGS4141NT1G,SA  I274  Q5
   1 PGPPA_BMC_AUX_L      1 @SCM_LIB.SCM(SCH_1):PGPPA_BMC_AUX_L
   6 PGPPA_BMC_AUX_L      6 @SCM_LIB.SCM(SCH_1):PGPPA_BMC_AUX_L
   3 LPC_ESPI_SEL_N      3 @SCM_LIB.SCM(SCH_1):LPC_ESPI_SEL_N
   2 PGPPA_BMC_AUX_L      2 @SCM_LIB.SCM(SCH_1):PGPPA_BMC_AUX_L
   4 P1V8_AUX      4 @SCM_LIB.SCM(SCH_1):P1V8_AUX
   5 PGPPA_BMC_AUX_L      5 @SCM_LIB.SCM(SCH_1):PGPPA_BMC_AUX_L

Q_RES_0603LF-0,5%,1/10W,EMPTY,A  I278  R645
   1 P1V8_AUX      A @SCM_LIB.SCM(SCH_1):P1V8_AUX
   2 PGPPA_BMC_AUX_L      B @SCM_LIB.SCM(SCH_1):PGPPA_BMC_AUX_L

Q_RES_0603LF-0,5%,1/10W,EMPTY,A  I279  R646
   1 PGPPA_BMC_AUX_L      A @SCM_LIB.SCM(SCH_1):PGPPA_BMC_AUX_L
   2 P3V3_AUX      B @SCM_LIB.SCM(SCH_1):P3V3_AUX

Q_RES_0402LF-150K,1%,1/16W,EMPA  I284  R493
   1 LPC_ESPI_SEL_N      A @SCM_LIB.SCM(SCH_1):LPC_ESPI_SEL_N
   2    GND      B @SCM_LIB.SCM(SCH_1):GND

AST2600A3GP-AST2600A3-GP,SMLF,A  I286  U5
  A1    GND GND_A1 @SCM_LIB.SCM(SCH_1):GND
  A5    GND GND_A5 @SCM_LIB.SCM(SCH_1):GND
 A26    GND GND_A26 @SCM_LIB.SCM(SCH_1):GND
  B5    GND GND_B5 @SCM_LIB.SCM(SCH_1):GND
 B11    GND GND_B11 @SCM_LIB.SCM(SCH_1):GND
 B15    GND GND_B15 @SCM_LIB.SCM(SCH_1):GND
 B19    GND GND_B19 @SCM_LIB.SCM(SCH_1):GND
 B23    GND GND_B23 @SCM_LIB.SCM(SCH_1):GND
  C3    GND GND_C3 @SCM_LIB.SCM(SCH_1):GND
 D25    GND GND_D25 @SCM_LIB.SCM(SCH_1):GND
  E8    GND GND_E8 @SCM_LIB.SCM(SCH_1):GND
  F6    GND GND_F6 @SCM_LIB.SCM(SCH_1):GND
  F8    GND GND_F8 @SCM_LIB.SCM(SCH_1):GND
 F10    GND GND_F10 @SCM_LIB.SCM(SCH_1):GND
 F12    GND GND_F12 @SCM_LIB.SCM(SCH_1):GND
 F14    GND GND_F14 @SCM_LIB.SCM(SCH_1):GND
 F16    GND GND_F16 @SCM_LIB.SCM(SCH_1):GND
 F17    GND GND_F17 @SCM_LIB.SCM(SCH_1):GND
 F18    GND GND_F18 @SCM_LIB.SCM(SCH_1):GND
 F21    GND GND_F21 @SCM_LIB.SCM(SCH_1):GND
  G2    GND GND_G2 @SCM_LIB.SCM(SCH_1):GND
 G25    GND GND_G25 @SCM_LIB.SCM(SCH_1):GND
  H4    GND GND_H4 @SCM_LIB.SCM(SCH_1):GND
  H9    GND GND_H9 @SCM_LIB.SCM(SCH_1):GND
 H10    GND GND_H10 @SCM_LIB.SCM(SCH_1):GND
 H11    GND GND_H11 @SCM_LIB.SCM(SCH_1):GND
 H13    GND GND_H13 @SCM_LIB.SCM(SCH_1):GND
  J2    GND GND_J2 @SCM_LIB.SCM(SCH_1):GND
 J11    GND GND_J11 @SCM_LIB.SCM(SCH_1):GND
 J13    GND GND_J13 @SCM_LIB.SCM(SCH_1):GND
 J14    GND GND_J14 @SCM_LIB.SCM(SCH_1):GND
 J15    GND GND_J15 @SCM_LIB.SCM(SCH_1):GND
 J16    GND GND_J16 @SCM_LIB.SCM(SCH_1):GND
 J17    GND GND_J17 @SCM_LIB.SCM(SCH_1):GND
 J18    GND GND_J18 @SCM_LIB.SCM(SCH_1):GND
 J19    GND GND_J19 @SCM_LIB.SCM(SCH_1):GND
  K4    GND GND_K4 @SCM_LIB.SCM(SCH_1):GND
  K8    GND GND_K8 @SCM_LIB.SCM(SCH_1):GND
  K9    GND GND_K9 @SCM_LIB.SCM(SCH_1):GND
 K13    GND GND_K13 @SCM_LIB.SCM(SCH_1):GND
 K14    GND GND_K14 @SCM_LIB.SCM(SCH_1):GND
 K15    GND GND_K15 @SCM_LIB.SCM(SCH_1):GND
 K22    GND GND_K22 @SCM_LIB.SCM(SCH_1):GND
  L2    GND GND_L2 @SCM_LIB.SCM(SCH_1):GND
  L8    GND GND_L8 @SCM_LIB.SCM(SCH_1):GND
 L11    GND GND_L11 @SCM_LIB.SCM(SCH_1):GND
 L12    GND GND_L12 @SCM_LIB.SCM(SCH_1):GND
 L15    GND GND_L15 @SCM_LIB.SCM(SCH_1):GND
 L16    GND GND_L16 @SCM_LIB.SCM(SCH_1):GND
 L17    GND GND_L17 @SCM_LIB.SCM(SCH_1):GND
  R2    GND GND_R2 @SCM_LIB.SCM(SCH_1):GND
  R8    GND GND_R8 @SCM_LIB.SCM(SCH_1):GND
 R11    GND GND_R11 @SCM_LIB.SCM(SCH_1):GND
 R15    GND GND_R15 @SCM_LIB.SCM(SCH_1):GND
 R16    GND GND_R16 @SCM_LIB.SCM(SCH_1):GND
 R17    GND GND_R17 @SCM_LIB.SCM(SCH_1):GND
 R18    GND GND_R18 @SCM_LIB.SCM(SCH_1):GND
 R19    GND GND_R19 @SCM_LIB.SCM(SCH_1):GND
 R25    GND GND_R25 @SCM_LIB.SCM(SCH_1):GND
  T4    GND GND_T4 @SCM_LIB.SCM(SCH_1):GND
 T11    GND GND_T11 @SCM_LIB.SCM(SCH_1):GND
 T12    GND GND_T12 @SCM_LIB.SCM(SCH_1):GND
 T15    GND GND_T15 @SCM_LIB.SCM(SCH_1):GND
 T16    GND GND_T16 @SCM_LIB.SCM(SCH_1):GND
 T17    GND GND_T17 @SCM_LIB.SCM(SCH_1):GND
 T18    GND GND_T18 @SCM_LIB.SCM(SCH_1):GND
 T19    GND GND_T19 @SCM_LIB.SCM(SCH_1):GND
  U2    GND GND_U2 @SCM_LIB.SCM(SCH_1):GND
  U8    GND GND_U8 @SCM_LIB.SCM(SCH_1):GND
  U9    GND GND_U9 @SCM_LIB.SCM(SCH_1):GND
 U10    GND GND_U10 @SCM_LIB.SCM(SCH_1):GND
 U11    GND GND_U11 @SCM_LIB.SCM(SCH_1):GND
 U12    GND GND_U12 @SCM_LIB.SCM(SCH_1):GND
 U14    GND GND_U14 @SCM_LIB.SCM(SCH_1):GND
 U19    GND GND_U19 @SCM_LIB.SCM(SCH_1):GND
 U22    GND GND_U22 @SCM_LIB.SCM(SCH_1):GND
  V5    GND GND_V5 @SCM_LIB.SCM(SCH_1):GND
 V11    GND GND_V11 @SCM_LIB.SCM(SCH_1):GND
 V12    GND GND_V12 @SCM_LIB.SCM(SCH_1):GND
 V14    GND GND_V14 @SCM_LIB.SCM(SCH_1):GND
 V15    GND GND_V15 @SCM_LIB.SCM(SCH_1):GND
 V16    GND GND_V16 @SCM_LIB.SCM(SCH_1):GND
 V17    GND GND_V17 @SCM_LIB.SCM(SCH_1):GND
 V18    GND GND_V18 @SCM_LIB.SCM(SCH_1):GND
 V19    GND GND_V19 @SCM_LIB.SCM(SCH_1):GND
  W5    GND GND_W5 @SCM_LIB.SCM(SCH_1):GND
  W6    GND GND_W6 @SCM_LIB.SCM(SCH_1):GND
  W8    GND GND_W8 @SCM_LIB.SCM(SCH_1):GND
  W9    GND GND_W9 @SCM_LIB.SCM(SCH_1):GND
 W10    GND GND_W10 @SCM_LIB.SCM(SCH_1):GND
 W11    GND GND_W11 @SCM_LIB.SCM(SCH_1):GND
 W12    GND GND_W12 @SCM_LIB.SCM(SCH_1):GND
 L18    GND GND_L18 @SCM_LIB.SCM(SCH_1):GND
 L19    GND GND_L19 @SCM_LIB.SCM(SCH_1):GND
 L25    GND GND_L25 @SCM_LIB.SCM(SCH_1):GND
  M4    GND GND_M4 @SCM_LIB.SCM(SCH_1):GND
  M9    GND GND_M9 @SCM_LIB.SCM(SCH_1):GND
 M10    GND GND_M10 @SCM_LIB.SCM(SCH_1):GND
 M12    GND GND_M12 @SCM_LIB.SCM(SCH_1):GND
 M15    GND GND_M15 @SCM_LIB.SCM(SCH_1):GND
 M16    GND GND_M16 @SCM_LIB.SCM(SCH_1):GND
 M17    GND GND_M17 @SCM_LIB.SCM(SCH_1):GND
 W22    GND GND_W22 @SCM_LIB.SCM(SCH_1):GND
 W25    GND GND_W25 @SCM_LIB.SCM(SCH_1):GND
  Y6    GND GND_Y6 @SCM_LIB.SCM(SCH_1):GND
 Y22    GND GND_Y22 @SCM_LIB.SCM(SCH_1):GND
 AA1    GND GND_AA1 @SCM_LIB.SCM(SCH_1):GND
 AA3    GND GND_AA3 @SCM_LIB.SCM(SCH_1):GND
 AA8    GND GND_AA8 @SCM_LIB.SCM(SCH_1):GND
 AA7    GND GND_AA7 @SCM_LIB.SCM(SCH_1):GND
 AA6    GND GND_AA6 @SCM_LIB.SCM(SCH_1):GND
 M18    GND GND_M18 @SCM_LIB.SCM(SCH_1):GND
 M19    GND GND_M19 @SCM_LIB.SCM(SCH_1):GND
  N2    GND GND_N2 @SCM_LIB.SCM(SCH_1):GND
  N6    GND GND_N6 @SCM_LIB.SCM(SCH_1):GND
  N9    GND GND_N9 @SCM_LIB.SCM(SCH_1):GND
 N10    GND GND_N10 @SCM_LIB.SCM(SCH_1):GND
 N15    GND GND_N15 @SCM_LIB.SCM(SCH_1):GND
 N16    GND GND_N16 @SCM_LIB.SCM(SCH_1):GND
 N17    GND GND_N17 @SCM_LIB.SCM(SCH_1):GND
 N18    GND GND_N18 @SCM_LIB.SCM(SCH_1):GND
 N19    GND GND_N19 @SCM_LIB.SCM(SCH_1):GND
AA10    GND GND_AA10 @SCM_LIB.SCM(SCH_1):GND
AA14    GND GND_AA14 @SCM_LIB.SCM(SCH_1):GND
AA15    GND GND_AA15 @SCM_LIB.SCM(SCH_1):GND
AA19    GND GND_AA19 @SCM_LIB.SCM(SCH_1):GND
AA22    GND GND_AA22 @SCM_LIB.SCM(SCH_1):GND
 AC2    GND GND_AC2 @SCM_LIB.SCM(SCH_1):GND
 AC6    GND GND_AC6 @SCM_LIB.SCM(SCH_1):GND
AC25    GND GND_AC25 @SCM_LIB.SCM(SCH_1):GND
 AD1    GND GND_AD1 @SCM_LIB.SCM(SCH_1):GND
 AD4    GND GND_AD4 @SCM_LIB.SCM(SCH_1):GND
 AE3    GND GND_AE3 @SCM_LIB.SCM(SCH_1):GND
 AE6    GND GND_AE6 @SCM_LIB.SCM(SCH_1):GND
 AE9    GND GND_AE9 @SCM_LIB.SCM(SCH_1):GND
AE13    GND GND_AE13 @SCM_LIB.SCM(SCH_1):GND
AE17    GND GND_AE17 @SCM_LIB.SCM(SCH_1):GND
AE20    GND GND_AE20 @SCM_LIB.SCM(SCH_1):GND
AE23    GND GND_AE23 @SCM_LIB.SCM(SCH_1):GND
 AF1    GND GND_AF1 @SCM_LIB.SCM(SCH_1):GND
 AF4    GND GND_AF4 @SCM_LIB.SCM(SCH_1):GND
AF26    GND GND_AF26 @SCM_LIB.SCM(SCH_1):GND
  P4    GND GND_P4 @SCM_LIB.SCM(SCH_1):GND
  P9    GND GND_P9 @SCM_LIB.SCM(SCH_1):GND
 P10    GND GND_P10 @SCM_LIB.SCM(SCH_1):GND
 P15    GND GND_P15 @SCM_LIB.SCM(SCH_1):GND
 P16    GND GND_P16 @SCM_LIB.SCM(SCH_1):GND
 P17    GND GND_P17 @SCM_LIB.SCM(SCH_1):GND
 P18    GND GND_P18 @SCM_LIB.SCM(SCH_1):GND
 P19    GND GND_P19 @SCM_LIB.SCM(SCH_1):GND
AA20    GND GND_AA20 @SCM_LIB.SCM(SCH_1):GND
 U23    GND GND_U23 @SCM_LIB.SCM(SCH_1):GND

MOSFET_PCH_GDS-NTR1P02LT1G,SMLA  I289  Q4
   D PGPPA_BMC_AUX_L      D @SCM_LIB.SCM(SCH_1):PGPPA_BMC_AUX_L
   G LPC_ESPI_SEL_N      G @SCM_LIB.SCM(SCH_1):LPC_ESPI_SEL_N
   S P3V3_AUX      S @SCM_LIB.SCM(SCH_1):P3V3_AUX


DRAWING: @SCM_LIB.SCM(SCH_1):PAGE20 

Q_CAP_C0603-4.7UF,25V,10%,X6S,A  I4  C1
   1 P1V2_AUX      A @SCM_LIB.SCM(SCH_1):P1V2_AUX
   2    GND      B @SCM_LIB.SCM(SCH_1):GND

Q_CAP_C0402-1UF,25V,10%,X6S,CHA  I5  C2
   1 P1V2_AUX      A @SCM_LIB.SCM(SCH_1):P1V2_AUX
   2    GND      B @SCM_LIB.SCM(SCH_1):GND

Q_CAP_C0402-1UF,25V,10%,X6S,CHA  I6  C3
   1 P1V2_AUX      A @SCM_LIB.SCM(SCH_1):P1V2_AUX
   2    GND      B @SCM_LIB.SCM(SCH_1):GND

Q_CAP_C0402-1UF,25V,10%,X6S,CHA  I7  C4
   1 P1V2_AUX      A @SCM_LIB.SCM(SCH_1):P1V2_AUX
   2    GND      B @SCM_LIB.SCM(SCH_1):GND

Q_RES_0402LF-0,5%,1/16W,CHIP,CA  I13  R2
   1 M_BMC_DDR4_BG1      A @SCM_LIB.SCM(SCH_1):M_BMC_DDR4_BG1
   2    GND      B @SCM_LIB.SCM(SCH_1):GND

Q_RES_0402LF-0,5%,1/16W,EMPTY,A  I14  R1
   1 M_BMC_DDR4_BG1      A @SCM_LIB.SCM(SCH_1):M_BMC_DDR4_BG1
   2 M_BMC_DDR4_MBG1      B @SCM_LIB.SCM(SCH_1):M_BMC_DDR4_MBG1

Q_RES_0402LF-0,5%,1/16W,CHIP,CA  I17  R3
   1 M_BMC_DDR4_ZQU      A @SCM_LIB.SCM(SCH_1):M_BMC_DDR4_ZQU
   2    GND      B @SCM_LIB.SCM(SCH_1):GND

Q_CAP_0402-0.1UF,25V,10%,X7R,CA  I19  C6
   1 P2V5_AUX      A @SCM_LIB.SCM(SCH_1):P2V5_AUX
   2    GND      B @SCM_LIB.SCM(SCH_1):GND

Q_CAP_0402-0.1UF,25V,10%,X7R,CA  I21  C8
   1 P2V5_AUX      A @SCM_LIB.SCM(SCH_1):P2V5_AUX
   2    GND      B @SCM_LIB.SCM(SCH_1):GND

Q_CAP_C0402-1UF,25V,10%,X6S,CHA  I23  C5
   1 P1V2_AUX      A @SCM_LIB.SCM(SCH_1):P1V2_AUX
   2    GND      B @SCM_LIB.SCM(SCH_1):GND

Q_CAP_0402-0.1UF,25V,10%,X7R,CA  I24  C7
   1 P1V2_AUX      A @SCM_LIB.SCM(SCH_1):P1V2_AUX
   2    GND      B @SCM_LIB.SCM(SCH_1):GND

Q_CAP_0402-100PF,50V,5%,NPO,CHA  I25  C9
   1 P1V2_AUX      A @SCM_LIB.SCM(SCH_1):P1V2_AUX
   2    GND      B @SCM_LIB.SCM(SCH_1):GND

Q_RES_0402LF-1K,1%,1/16W,CHIP,A  I27  R325
   1 P0V6_DDR_VREF_AUX      A @SCM_LIB.SCM(SCH_1):P0V6_DDR_VREF_AUX
   2    GND      B @SCM_LIB.SCM(SCH_1):GND

Q_RES_0402LF-1K,1%,1/16W,CHIP,A  I28  R324
   1 P1V2_AUX      A @SCM_LIB.SCM(SCH_1):P1V2_AUX
   2 P0V6_DDR_VREF_AUX      B @SCM_LIB.SCM(SCH_1):P0V6_DDR_VREF_AUX

Q_CAP_0402-0.1UF,25V,10%,X7R,CA  I32  C168
   1 P0V6_DDR_VREF_AUX      A @SCM_LIB.SCM(SCH_1):P0V6_DDR_VREF_AUX
   2    GND      B @SCM_LIB.SCM(SCH_1):GND

Q_CAP_C0402-0.01UF,50V,10%,X7RA  I33  C170
   1 P0V6_DDR_VREF_AUX      A @SCM_LIB.SCM(SCH_1):P0V6_DDR_VREF_AUX
   2    GND      B @SCM_LIB.SCM(SCH_1):GND

Q_CAP_C0402-0.01UF,50V,10%,EMPA  I34  C169
   1 P1V2_AUX      A @SCM_LIB.SCM(SCH_1):P1V2_AUX
   2 P0V6_DDR_VREF_AUX      B @SCM_LIB.SCM(SCH_1):P0V6_DDR_VREF_AUX

Q_CAP_0402-0.1UF,25V,10%,X7R,CA  I85  C10
   1 P0V6_DDR_VREF_AUX      A @SCM_LIB.SCM(SCH_1):P0V6_DDR_VREF_AUX
   2    GND      B @SCM_LIB.SCM(SCH_1):GND

Q_RES_0402LF-60.4,1%,1/16W,CHIA  I89  R8
   1 M_BMC_DDR4_MCLK_DP      A @SCM_LIB.SCM(SCH_1):M_BMC_DDR4_MCLK_DP
   2 M_BMC_DDR4_MCLK_C      B @SCM_LIB.SCM(SCH_1):M_BMC_DDR4_MCLK_C

Q_RES_0402LF-60.4,1%,1/16W,CHIA  I90  R7
   1 M_BMC_DDR4_MCLK_DN      A @SCM_LIB.SCM(SCH_1):M_BMC_DDR4_MCLK_DN
   2 M_BMC_DDR4_MCLK_C      B @SCM_LIB.SCM(SCH_1):M_BMC_DDR4_MCLK_C

Q_CAP_0402-0.22UF,16V,10%,X7R,A  I106  C12
   1 M_BMC_DDR4_MCLK_C      A @SCM_LIB.SCM(SCH_1):M_BMC_DDR4_MCLK_C
   2    GND      B @SCM_LIB.SCM(SCH_1):GND

Q_CAP_0402-0.22UF,16V,10%,EMPTA  I107  C229
   1 M_BMC_DDR4_MCLK_C      A @SCM_LIB.SCM(SCH_1):M_BMC_DDR4_MCLK_C
   2 P1V2_AUX      B @SCM_LIB.SCM(SCH_1):P1V2_AUX

Q_RES_0402LF-4.7K,1%,1/16W,CHIA  I111  R9
   1 M_BMC_DDR4_ALERT_N      A @SCM_LIB.SCM(SCH_1):M_BMC_DDR4_ALERT_N
   2 P1V2_AUX      B @SCM_LIB.SCM(SCH_1):P1V2_AUX

Q_CAP_C0402-10UF,6.3V,20%,X6S,A  I113  C16
   1 P1V2_AUX      A @SCM_LIB.SCM(SCH_1):P1V2_AUX
   2    GND      B @SCM_LIB.SCM(SCH_1):GND

Q_RES_0402LF-120,1%,1/16W,EMPTA  I114  R350
   1    GND      A @SCM_LIB.SCM(SCH_1):GND
   2 M_BMC_DDR4_MBG1      B @SCM_LIB.SCM(SCH_1):M_BMC_DDR4_MBG1

Q_RES_0402LF-120,1%,1/16W,EMPTA  I115  R375
   1 M_BMC_DDR4_MBG1      A @SCM_LIB.SCM(SCH_1):M_BMC_DDR4_MBG1
   2 P1V2_AUX      B @SCM_LIB.SCM(SCH_1):P1V2_AUX

Q_RES_0402LF-120,1%,1/16W,CHIPA  I116  R349
   1    GND      A @SCM_LIB.SCM(SCH_1):GND
   2 M_BMC_DDR4_MCKE      B @SCM_LIB.SCM(SCH_1):M_BMC_DDR4_MCKE

Q_RES_0402LF-120,1%,1/16W,CHIPA  I117  R347
   1    GND      A @SCM_LIB.SCM(SCH_1):GND
   2 M_BMC_DDR4_MBA1      B @SCM_LIB.SCM(SCH_1):M_BMC_DDR4_MBA1

Q_RES_0402LF-120,1%,1/16W,CHIPA  I118  R348
   1    GND      A @SCM_LIB.SCM(SCH_1):GND
   2 M_BMC_DDR4_MODT      B @SCM_LIB.SCM(SCH_1):M_BMC_DDR4_MODT

Q_RES_0402LF-120,1%,1/16W,CHIPA  I119  R345
   1    GND      A @SCM_LIB.SCM(SCH_1):GND
   2 M_BMC_DDR4_MBG0      B @SCM_LIB.SCM(SCH_1):M_BMC_DDR4_MBG0

Q_RES_0402LF-120,1%,1/16W,CHIPA  I120  R346
   1    GND      A @SCM_LIB.SCM(SCH_1):GND
   2 M_BMC_DDR4_MBA0      B @SCM_LIB.SCM(SCH_1):M_BMC_DDR4_MBA0

Q_RES_0402LF-120,1%,1/16W,CHIPA  I121  R344
   1    GND      A @SCM_LIB.SCM(SCH_1):GND
   2 M_BMC_DDR4_MACT_N      B @SCM_LIB.SCM(SCH_1):M_BMC_DDR4_MACT_N

Q_RES_0402LF-120,1%,1/16W,CHIPA  I122  R342
   1    GND      A @SCM_LIB.SCM(SCH_1):GND
   2 M_BMC_DDR4_MRAS_N      B @SCM_LIB.SCM(SCH_1):M_BMC_DDR4_MRAS_N

Q_RES_0402LF-120,1%,1/16W,CHIPA  I123  R343
   1    GND      A @SCM_LIB.SCM(SCH_1):GND
   2 M_BMC_DDR4_MCS_N      B @SCM_LIB.SCM(SCH_1):M_BMC_DDR4_MCS_N

Q_RES_0402LF-120,1%,1/16W,CHIPA  I124  R340
   1    GND      A @SCM_LIB.SCM(SCH_1):GND
   2 M_BMC_DDR4_MWE_N      B @SCM_LIB.SCM(SCH_1):M_BMC_DDR4_MWE_N

Q_RES_0402LF-120,1%,1/16W,CHIPA  I125  R341
   1    GND      A @SCM_LIB.SCM(SCH_1):GND
   2 M_BMC_DDR4_MCAS_N      B @SCM_LIB.SCM(SCH_1):M_BMC_DDR4_MCAS_N

Q_RES_0402LF-120,1%,1/16W,CHIPA  I127  R374
   1 M_BMC_DDR4_MCKE      A @SCM_LIB.SCM(SCH_1):M_BMC_DDR4_MCKE
   2 P1V2_AUX      B @SCM_LIB.SCM(SCH_1):P1V2_AUX

Q_RES_0402LF-120,1%,1/16W,CHIPA  I128  R373
   1 M_BMC_DDR4_MODT      A @SCM_LIB.SCM(SCH_1):M_BMC_DDR4_MODT
   2 P1V2_AUX      B @SCM_LIB.SCM(SCH_1):P1V2_AUX

Q_RES_0402LF-120,1%,1/16W,CHIPA  I129  R372
   1 M_BMC_DDR4_MBA1      A @SCM_LIB.SCM(SCH_1):M_BMC_DDR4_MBA1
   2 P1V2_AUX      B @SCM_LIB.SCM(SCH_1):P1V2_AUX

Q_RES_0402LF-120,1%,1/16W,CHIPA  I130  R371
   1 M_BMC_DDR4_MBA0      A @SCM_LIB.SCM(SCH_1):M_BMC_DDR4_MBA0
   2 P1V2_AUX      B @SCM_LIB.SCM(SCH_1):P1V2_AUX

Q_RES_0402LF-120,1%,1/16W,CHIPA  I131  R370
   1 M_BMC_DDR4_MBG0      A @SCM_LIB.SCM(SCH_1):M_BMC_DDR4_MBG0
   2 P1V2_AUX      B @SCM_LIB.SCM(SCH_1):P1V2_AUX

Q_RES_0402LF-120,1%,1/16W,CHIPA  I132  R369
   1 M_BMC_DDR4_MACT_N      A @SCM_LIB.SCM(SCH_1):M_BMC_DDR4_MACT_N
   2 P1V2_AUX      B @SCM_LIB.SCM(SCH_1):P1V2_AUX

Q_CAP_C0402-10UF,6.3V,20%,X6S,A  I134  C15
   1 P1V2_AUX      A @SCM_LIB.SCM(SCH_1):P1V2_AUX
   2    GND      B @SCM_LIB.SCM(SCH_1):GND

Q_RES_0402LF-120,1%,1/16W,CHIPA  I135  R368
   1 M_BMC_DDR4_MCS_N      A @SCM_LIB.SCM(SCH_1):M_BMC_DDR4_MCS_N
   2 P1V2_AUX      B @SCM_LIB.SCM(SCH_1):P1V2_AUX

Q_RES_0402LF-120,1%,1/16W,CHIPA  I136  R367
   1 M_BMC_DDR4_MRAS_N      A @SCM_LIB.SCM(SCH_1):M_BMC_DDR4_MRAS_N
   2 P1V2_AUX      B @SCM_LIB.SCM(SCH_1):P1V2_AUX

Q_RES_0402LF-120,1%,1/16W,CHIPA  I137  R366
   1 M_BMC_DDR4_MCAS_N      A @SCM_LIB.SCM(SCH_1):M_BMC_DDR4_MCAS_N
   2 P1V2_AUX      B @SCM_LIB.SCM(SCH_1):P1V2_AUX

Q_RES_0402LF-120,1%,1/16W,CHIPA  I138  R365
   1 M_BMC_DDR4_MWE_N      A @SCM_LIB.SCM(SCH_1):M_BMC_DDR4_MWE_N
   2 P1V2_AUX      B @SCM_LIB.SCM(SCH_1):P1V2_AUX

Q_RES_0402LF-1K,1%,1/16W,CHIP,A  I141  R4
   1 PD_M_BMC_DDR4_PAR      A @SCM_LIB.SCM(SCH_1):PD_M_BMC_DDR4_PAR
   2    GND      B @SCM_LIB.SCM(SCH_1):GND

Q_RES_0402LF-1K,1%,1/16W,CHIP,A  I142  R5
   1 PD_M_BMC_DDR4_TEN      A @SCM_LIB.SCM(SCH_1):PD_M_BMC_DDR4_TEN
   2    GND      B @SCM_LIB.SCM(SCH_1):GND

Q_RES_0402LF-240,1%,1/16W,CHIPA  I143  R6
   1 PD_M_BMC_DDR4_ZQ      A @SCM_LIB.SCM(SCH_1):PD_M_BMC_DDR4_ZQ
   2    GND      B @SCM_LIB.SCM(SCH_1):GND

Q_RES_0402LF-120,1%,1/16W,CHIPA  I159  R339
   1    GND      A @SCM_LIB.SCM(SCH_1):GND
   2 M_BMC_DDR4_MA<13>      B @SCM_LIB.SCM(SCH_1):M_BMC_DDR4_MA(13)

Q_RES_0402LF-120,1%,1/16W,CHIPA  I160  R338
   1    GND      A @SCM_LIB.SCM(SCH_1):GND
   2 M_BMC_DDR4_MA<12>      B @SCM_LIB.SCM(SCH_1):M_BMC_DDR4_MA(12)

Q_RES_0402LF-120,1%,1/16W,CHIPA  I161  R337
   1    GND      A @SCM_LIB.SCM(SCH_1):GND
   2 M_BMC_DDR4_MA<11>      B @SCM_LIB.SCM(SCH_1):M_BMC_DDR4_MA(11)

Q_RES_0402LF-120,1%,1/16W,CHIPA  I162  R336
   1    GND      A @SCM_LIB.SCM(SCH_1):GND
   2 M_BMC_DDR4_MA<10>      B @SCM_LIB.SCM(SCH_1):M_BMC_DDR4_MA(10)

Q_RES_0402LF-120,1%,1/16W,CHIPA  I163  R335
   1    GND      A @SCM_LIB.SCM(SCH_1):GND
   2 M_BMC_DDR4_MA<9>      B @SCM_LIB.SCM(SCH_1):M_BMC_DDR4_MA(9)

Q_RES_0402LF-120,1%,1/16W,CHIPA  I164  R334
   1    GND      A @SCM_LIB.SCM(SCH_1):GND
   2 M_BMC_DDR4_MA<8>      B @SCM_LIB.SCM(SCH_1):M_BMC_DDR4_MA(8)

Q_RES_0402LF-120,1%,1/16W,CHIPA  I165  R364
   1 M_BMC_DDR4_MA<13>      A @SCM_LIB.SCM(SCH_1):M_BMC_DDR4_MA(13)
   2 P1V2_AUX      B @SCM_LIB.SCM(SCH_1):P1V2_AUX

Q_RES_0402LF-120,1%,1/16W,CHIPA  I166  R363
   1 M_BMC_DDR4_MA<12>      A @SCM_LIB.SCM(SCH_1):M_BMC_DDR4_MA(12)
   2 P1V2_AUX      B @SCM_LIB.SCM(SCH_1):P1V2_AUX

Q_RES_0402LF-120,1%,1/16W,CHIPA  I167  R361
   1 M_BMC_DDR4_MA<10>      A @SCM_LIB.SCM(SCH_1):M_BMC_DDR4_MA(10)
   2 P1V2_AUX      B @SCM_LIB.SCM(SCH_1):P1V2_AUX

Q_RES_0402LF-120,1%,1/16W,CHIPA  I168  R362
   1 M_BMC_DDR4_MA<11>      A @SCM_LIB.SCM(SCH_1):M_BMC_DDR4_MA(11)
   2 P1V2_AUX      B @SCM_LIB.SCM(SCH_1):P1V2_AUX

Q_RES_0402LF-120,1%,1/16W,CHIPA  I169  R360
   1 M_BMC_DDR4_MA<9>      A @SCM_LIB.SCM(SCH_1):M_BMC_DDR4_MA(9)
   2 P1V2_AUX      B @SCM_LIB.SCM(SCH_1):P1V2_AUX

Q_RES_0402LF-120,1%,1/16W,CHIPA  I170  R359
   1 M_BMC_DDR4_MA<8>      A @SCM_LIB.SCM(SCH_1):M_BMC_DDR4_MA(8)
   2 P1V2_AUX      B @SCM_LIB.SCM(SCH_1):P1V2_AUX

Q_RES_0402LF-120,1%,1/16W,CHIPA  I171  R332
   1    GND      A @SCM_LIB.SCM(SCH_1):GND
   2 M_BMC_DDR4_MA<6>      B @SCM_LIB.SCM(SCH_1):M_BMC_DDR4_MA(6)

Q_RES_0402LF-120,1%,1/16W,CHIPA  I172  R333
   1    GND      A @SCM_LIB.SCM(SCH_1):GND
   2 M_BMC_DDR4_MA<7>      B @SCM_LIB.SCM(SCH_1):M_BMC_DDR4_MA(7)

Q_RES_0402LF-120,1%,1/16W,CHIPA  I173  R331
   1    GND      A @SCM_LIB.SCM(SCH_1):GND
   2 M_BMC_DDR4_MA<5>      B @SCM_LIB.SCM(SCH_1):M_BMC_DDR4_MA(5)

Q_RES_0402LF-120,1%,1/16W,CHIPA  I174  R330
   1    GND      A @SCM_LIB.SCM(SCH_1):GND
   2 M_BMC_DDR4_MA<4>      B @SCM_LIB.SCM(SCH_1):M_BMC_DDR4_MA(4)

Q_RES_0402LF-120,1%,1/16W,CHIPA  I175  R329
   1    GND      A @SCM_LIB.SCM(SCH_1):GND
   2 M_BMC_DDR4_MA<3>      B @SCM_LIB.SCM(SCH_1):M_BMC_DDR4_MA(3)

Q_RES_0402LF-120,1%,1/16W,CHIPA  I176  R328
   1    GND      A @SCM_LIB.SCM(SCH_1):GND
   2 M_BMC_DDR4_MA<2>      B @SCM_LIB.SCM(SCH_1):M_BMC_DDR4_MA(2)

Q_RES_0402LF-120,1%,1/16W,CHIPA  I177  R327
   1    GND      A @SCM_LIB.SCM(SCH_1):GND
   2 M_BMC_DDR4_MA<1>      B @SCM_LIB.SCM(SCH_1):M_BMC_DDR4_MA(1)

Q_RES_0402LF-120,1%,1/16W,CHIPA  I178  R358
   1 M_BMC_DDR4_MA<7>      A @SCM_LIB.SCM(SCH_1):M_BMC_DDR4_MA(7)
   2 P1V2_AUX      B @SCM_LIB.SCM(SCH_1):P1V2_AUX

Q_RES_0402LF-120,1%,1/16W,CHIPA  I179  R357
   1 M_BMC_DDR4_MA<6>      A @SCM_LIB.SCM(SCH_1):M_BMC_DDR4_MA(6)
   2 P1V2_AUX      B @SCM_LIB.SCM(SCH_1):P1V2_AUX

Q_RES_0402LF-120,1%,1/16W,CHIPA  I180  R356
   1 M_BMC_DDR4_MA<5>      A @SCM_LIB.SCM(SCH_1):M_BMC_DDR4_MA(5)
   2 P1V2_AUX      B @SCM_LIB.SCM(SCH_1):P1V2_AUX

Q_RES_0402LF-120,1%,1/16W,CHIPA  I181  R354
   1 M_BMC_DDR4_MA<3>      A @SCM_LIB.SCM(SCH_1):M_BMC_DDR4_MA(3)
   2 P1V2_AUX      B @SCM_LIB.SCM(SCH_1):P1V2_AUX

Q_RES_0402LF-120,1%,1/16W,CHIPA  I182  R355
   1 M_BMC_DDR4_MA<4>      A @SCM_LIB.SCM(SCH_1):M_BMC_DDR4_MA(4)
   2 P1V2_AUX      B @SCM_LIB.SCM(SCH_1):P1V2_AUX

Q_RES_0402LF-120,1%,1/16W,CHIPA  I183  R353
   1 M_BMC_DDR4_MA<2>      A @SCM_LIB.SCM(SCH_1):M_BMC_DDR4_MA(2)
   2 P1V2_AUX      B @SCM_LIB.SCM(SCH_1):P1V2_AUX

Q_RES_0402LF-120,1%,1/16W,CHIPA  I184  R352
   1 M_BMC_DDR4_MA<1>      A @SCM_LIB.SCM(SCH_1):M_BMC_DDR4_MA(1)
   2 P1V2_AUX      B @SCM_LIB.SCM(SCH_1):P1V2_AUX

Q_CAP_0402-0.1UF,25V,10%,X7R,CA  I186  C13
   1 P1V2_AUX      A @SCM_LIB.SCM(SCH_1):P1V2_AUX
   2    GND      B @SCM_LIB.SCM(SCH_1):GND

Q_CAP_0402-0.1UF,25V,10%,X7R,CA  I187  C14
   1 P1V2_AUX      A @SCM_LIB.SCM(SCH_1):P1V2_AUX
   2    GND      B @SCM_LIB.SCM(SCH_1):GND

Q_CAP_0402-0.1UF,25V,10%,X7R,CA  I190  C17
   1 P1V2_AUX      A @SCM_LIB.SCM(SCH_1):P1V2_AUX
   2    GND      B @SCM_LIB.SCM(SCH_1):GND

Q_CAP_0402-0.1UF,25V,10%,X7R,CA  I192  C18
   1 P1V2_AUX      A @SCM_LIB.SCM(SCH_1):P1V2_AUX
   2    GND      B @SCM_LIB.SCM(SCH_1):GND

Q_RES_0402LF-120,1%,1/16W,CHIPA  I193  R326
   1    GND      A @SCM_LIB.SCM(SCH_1):GND
   2 M_BMC_DDR4_MA<0>      B @SCM_LIB.SCM(SCH_1):M_BMC_DDR4_MA(0)

Q_RES_0402LF-120,1%,1/16W,CHIPA  I194  R351
   1 M_BMC_DDR4_MA<0>      A @SCM_LIB.SCM(SCH_1):M_BMC_DDR4_MA(0)
   2 P1V2_AUX      B @SCM_LIB.SCM(SCH_1):P1V2_AUX

K4A8G165WCBCTD-K4A8G165WC-BCTDA  I196  U1
  P3 M_BMC_DDR4_MA<0>     A0 @SCM_LIB.SCM(SCH_1):M_BMC_DDR4_MA(0)
  P7 M_BMC_DDR4_MA<1>     A1 @SCM_LIB.SCM(SCH_1):M_BMC_DDR4_MA(1)
  M3 M_BMC_DDR4_MA<10> A10||AP @SCM_LIB.SCM(SCH_1):M_BMC_DDR4_MA(10)
  T2 M_BMC_DDR4_MA<11>    A11 @SCM_LIB.SCM(SCH_1):M_BMC_DDR4_MA(11)
  M7 M_BMC_DDR4_MA<12> A12||BC_N @SCM_LIB.SCM(SCH_1):M_BMC_DDR4_MA(12)
  T8 M_BMC_DDR4_MA<13>    A13 @SCM_LIB.SCM(SCH_1):M_BMC_DDR4_MA(13)
  R3 M_BMC_DDR4_MA<2>     A2 @SCM_LIB.SCM(SCH_1):M_BMC_DDR4_MA(2)
  N7 M_BMC_DDR4_MA<3>     A3 @SCM_LIB.SCM(SCH_1):M_BMC_DDR4_MA(3)
  N3 M_BMC_DDR4_MA<4>     A4 @SCM_LIB.SCM(SCH_1):M_BMC_DDR4_MA(4)
  P8 M_BMC_DDR4_MA<5>     A5 @SCM_LIB.SCM(SCH_1):M_BMC_DDR4_MA(5)
  P2 M_BMC_DDR4_MA<6>     A6 @SCM_LIB.SCM(SCH_1):M_BMC_DDR4_MA(6)
  R8 M_BMC_DDR4_MA<7>     A7 @SCM_LIB.SCM(SCH_1):M_BMC_DDR4_MA(7)
  R2 M_BMC_DDR4_MA<8>     A8 @SCM_LIB.SCM(SCH_1):M_BMC_DDR4_MA(8)
  R7 M_BMC_DDR4_MA<9>     A9 @SCM_LIB.SCM(SCH_1):M_BMC_DDR4_MA(9)
  L3 M_BMC_DDR4_MACT_N  ACT_N @SCM_LIB.SCM(SCH_1):M_BMC_DDR4_MACT_N
  P9 M_BMC_DDR4_ALERT_N ALERT_N @SCM_LIB.SCM(SCH_1):M_BMC_DDR4_ALERT_N
  N2 M_BMC_DDR4_MBA0    BA0 @SCM_LIB.SCM(SCH_1):M_BMC_DDR4_MBA0
  N8 M_BMC_DDR4_MBA1    BA1 @SCM_LIB.SCM(SCH_1):M_BMC_DDR4_MBA1
  M2 M_BMC_DDR4_MBG0    BG0 @SCM_LIB.SCM(SCH_1):M_BMC_DDR4_MBG0
  M8 M_BMC_DDR4_MCAS_N CAS_N||A15 @SCM_LIB.SCM(SCH_1):M_BMC_DDR4_MCAS_N
  L7 M_BMC_DDR4_MCS_N   CS_N @SCM_LIB.SCM(SCH_1):M_BMC_DDR4_MCS_N
  K2 M_BMC_DDR4_MCKE    CKE @SCM_LIB.SCM(SCH_1):M_BMC_DDR4_MCKE
  T7    GND    NC1 @SCM_LIB.SCM(SCH_1):GND
  K3 M_BMC_DDR4_MODT    ODT @SCM_LIB.SCM(SCH_1):M_BMC_DDR4_MODT
  L8 M_BMC_DDR4_MRAS_N  RAS_N @SCM_LIB.SCM(SCH_1):M_BMC_DDR4_MRAS_N
  B3 P1V2_AUX   VDD0 @SCM_LIB.SCM(SCH_1):P1V2_AUX
  B9 P1V2_AUX   VDD1 @SCM_LIB.SCM(SCH_1):P1V2_AUX
  D1 P1V2_AUX   VDD2 @SCM_LIB.SCM(SCH_1):P1V2_AUX
  G7 P1V2_AUX   VDD3 @SCM_LIB.SCM(SCH_1):P1V2_AUX
  J1 P1V2_AUX   VDD4 @SCM_LIB.SCM(SCH_1):P1V2_AUX
  J9 P1V2_AUX   VDD5 @SCM_LIB.SCM(SCH_1):P1V2_AUX
  L1 P1V2_AUX   VDD6 @SCM_LIB.SCM(SCH_1):P1V2_AUX
  L9 P1V2_AUX   VDD7 @SCM_LIB.SCM(SCH_1):P1V2_AUX
  R1 P1V2_AUX   VDD8 @SCM_LIB.SCM(SCH_1):P1V2_AUX
  T9 P1V2_AUX   VDD9 @SCM_LIB.SCM(SCH_1):P1V2_AUX
  A1 P1V2_AUX  VDDQ0 @SCM_LIB.SCM(SCH_1):P1V2_AUX
  A9 P1V2_AUX  VDDQ1 @SCM_LIB.SCM(SCH_1):P1V2_AUX
  C1 P1V2_AUX  VDDQ2 @SCM_LIB.SCM(SCH_1):P1V2_AUX
  D9 P1V2_AUX  VDDQ3 @SCM_LIB.SCM(SCH_1):P1V2_AUX
  F2 P1V2_AUX  VDDQ4 @SCM_LIB.SCM(SCH_1):P1V2_AUX
  F8 P1V2_AUX  VDDQ5 @SCM_LIB.SCM(SCH_1):P1V2_AUX
  G1 P1V2_AUX  VDDQ6 @SCM_LIB.SCM(SCH_1):P1V2_AUX
  G9 P1V2_AUX  VDDQ7 @SCM_LIB.SCM(SCH_1):P1V2_AUX
  J2 P1V2_AUX  VDDQ8 @SCM_LIB.SCM(SCH_1):P1V2_AUX
  J8 P1V2_AUX  VDDQ9 @SCM_LIB.SCM(SCH_1):P1V2_AUX
  B1 P2V5_AUX   VPP0 @SCM_LIB.SCM(SCH_1):P2V5_AUX
  R9 P2V5_AUX   VPP1 @SCM_LIB.SCM(SCH_1):P2V5_AUX
  L2 M_BMC_DDR4_MWE_N WE_N||A14 @SCM_LIB.SCM(SCH_1):M_BMC_DDR4_MWE_N
  F9 PD_M_BMC_DDR4_ZQ     ZQ @SCM_LIB.SCM(SCH_1):PD_M_BMC_DDR4_ZQ
  G2 M_BMC_DDR4_DQ<0>   DQL0 @SCM_LIB.SCM(SCH_1):M_BMC_DDR4_DQ(0)
  F7 M_BMC_DDR4_DQ<1>   DQL1 @SCM_LIB.SCM(SCH_1):M_BMC_DDR4_DQ(1)
  H3 M_BMC_DDR4_DQ<2>   DQL2 @SCM_LIB.SCM(SCH_1):M_BMC_DDR4_DQ(2)
  H7 M_BMC_DDR4_DQ<3>   DQL3 @SCM_LIB.SCM(SCH_1):M_BMC_DDR4_DQ(3)
  H2 M_BMC_DDR4_DQ<4>   DQL4 @SCM_LIB.SCM(SCH_1):M_BMC_DDR4_DQ(4)
  H8 M_BMC_DDR4_DQ<5>   DQL5 @SCM_LIB.SCM(SCH_1):M_BMC_DDR4_DQ(5)
  J3 M_BMC_DDR4_DQ<6>   DQL6 @SCM_LIB.SCM(SCH_1):M_BMC_DDR4_DQ(6)
  J7 M_BMC_DDR4_DQ<7>   DQL7 @SCM_LIB.SCM(SCH_1):M_BMC_DDR4_DQ(7)
  A3 M_BMC_DDR4_DQ<8>   DQU0 @SCM_LIB.SCM(SCH_1):M_BMC_DDR4_DQ(8)
  B8 M_BMC_DDR4_DQ<9>   DQU1 @SCM_LIB.SCM(SCH_1):M_BMC_DDR4_DQ(9)
  C3 M_BMC_DDR4_DQ<10>   DQU2 @SCM_LIB.SCM(SCH_1):M_BMC_DDR4_DQ(10)
  C7 M_BMC_DDR4_DQ<11>   DQU3 @SCM_LIB.SCM(SCH_1):M_BMC_DDR4_DQ(11)
  C2 M_BMC_DDR4_DQ<12>   DQU4 @SCM_LIB.SCM(SCH_1):M_BMC_DDR4_DQ(12)
  C8 M_BMC_DDR4_DQ<13>   DQU5 @SCM_LIB.SCM(SCH_1):M_BMC_DDR4_DQ(13)
  D3 M_BMC_DDR4_DQ<14>   DQU6 @SCM_LIB.SCM(SCH_1):M_BMC_DDR4_DQ(14)
  D7 M_BMC_DDR4_DQ<15>   DQU7 @SCM_LIB.SCM(SCH_1):M_BMC_DDR4_DQ(15)
  K7 M_BMC_DDR4_MCLK_DP   CK_T @SCM_LIB.SCM(SCH_1):M_BMC_DDR4_MCLK_DP
  K8 M_BMC_DDR4_MCLK_DN   CK_C @SCM_LIB.SCM(SCH_1):M_BMC_DDR4_MCLK_DN
  B7 M_BMC_DDR4_DQS1_P DQSU_T @SCM_LIB.SCM(SCH_1):M_BMC_DDR4_DQS1_P
  A7 M_BMC_DDR4_DQS1_N DQSU_C @SCM_LIB.SCM(SCH_1):M_BMC_DDR4_DQS1_N
  G3 M_BMC_DDR4_DQS0_P DQSL_T @SCM_LIB.SCM(SCH_1):M_BMC_DDR4_DQS0_P
  F3 M_BMC_DDR4_DQS0_N DQSL_C @SCM_LIB.SCM(SCH_1):M_BMC_DDR4_DQS0_N
  N9 PD_M_BMC_DDR4_TEN    TEN @SCM_LIB.SCM(SCH_1):PD_M_BMC_DDR4_TEN
  T3 PD_M_BMC_DDR4_PAR    PAR @SCM_LIB.SCM(SCH_1):PD_M_BMC_DDR4_PAR
  M1 P0V6_DDR_VREF_AUX VREFCA @SCM_LIB.SCM(SCH_1):P0V6_DDR_VREF_AUX
  B2    GND   VSS0 @SCM_LIB.SCM(SCH_1):GND
  E1    GND   VSS1 @SCM_LIB.SCM(SCH_1):GND
  E9 M_BMC_DDR4_ZQU   VSS2 @SCM_LIB.SCM(SCH_1):M_BMC_DDR4_ZQU
  G8    GND   VSS3 @SCM_LIB.SCM(SCH_1):GND
  K1    GND   VSS4 @SCM_LIB.SCM(SCH_1):GND
  K9    GND   VSS5 @SCM_LIB.SCM(SCH_1):GND
  M9 M_BMC_DDR4_BG1   VSS6 @SCM_LIB.SCM(SCH_1):M_BMC_DDR4_BG1
  N1    GND   VSS7 @SCM_LIB.SCM(SCH_1):GND
  T1    GND   VSS8 @SCM_LIB.SCM(SCH_1):GND
  A2    GND  VSSQ0 @SCM_LIB.SCM(SCH_1):GND
  A8    GND  VSSQ1 @SCM_LIB.SCM(SCH_1):GND
  C9    GND  VSSQ2 @SCM_LIB.SCM(SCH_1):GND
  D2    GND  VSSQ3 @SCM_LIB.SCM(SCH_1):GND
  D8    GND  VSSQ4 @SCM_LIB.SCM(SCH_1):GND
  E3    GND  VSSQ5 @SCM_LIB.SCM(SCH_1):GND
  E8    GND  VSSQ6 @SCM_LIB.SCM(SCH_1):GND
  F1    GND  VSSQ7 @SCM_LIB.SCM(SCH_1):GND
  H1    GND  VSSQ8 @SCM_LIB.SCM(SCH_1):GND
  H9    GND  VSSQ9 @SCM_LIB.SCM(SCH_1):GND
  E7 M_BMC_DDR4_MDM0 DML_N||DBIL_N @SCM_LIB.SCM(SCH_1):M_BMC_DDR4_MDM0
  E2 M_BMC_DDR4_MDM1 DMU_N||DBIU_N @SCM_LIB.SCM(SCH_1):M_BMC_DDR4_MDM1
  P1 M_BMC_DDR4_RST_N RESET_N @SCM_LIB.SCM(SCH_1):M_BMC_DDR4_RST_N

Q_CAP_0402-0.1UF,25V,10%,X7R,CA  I197  C225
   1 P1V2_AUX      A @SCM_LIB.SCM(SCH_1):P1V2_AUX
   2    GND      B @SCM_LIB.SCM(SCH_1):GND

Q_CAP_0402-0.1UF,25V,10%,X7R,CA  I198  C222
   1 P1V2_AUX      A @SCM_LIB.SCM(SCH_1):P1V2_AUX
   2    GND      B @SCM_LIB.SCM(SCH_1):GND

Q_CAP_0402-0.1UF,25V,10%,X7R,CA  I199  C221
   1 P1V2_AUX      A @SCM_LIB.SCM(SCH_1):P1V2_AUX
   2    GND      B @SCM_LIB.SCM(SCH_1):GND


DRAWING: @SCM_LIB.SCM(SCH_1):PAGE21 

Q_CAP_0402-0.1UF,25V,10%,EMPTYA  I21  C228
   1 P3V3_AUX      A @SCM_LIB.SCM(SCH_1):P3V3_AUX
   2    GND      B @SCM_LIB.SCM(SCH_1):GND

Q_RES_0402LF-33.2,1%,1/16W,EMPA  I33  R654
   1 EMMC_CLK_R      A @SCM_LIB.SCM(SCH_1):EMMC_CLK_R
   2 BMC_EMMC_CLK      B @SCM_LIB.SCM(SCH_1):BMC_EMMC_CLK

Q_RES_0402LF-33.2,1%,1/16W,EMPA  I35  R48
   1 EMMC_CMD_R      A @SCM_LIB.SCM(SCH_1):EMMC_CMD_R
   2 BMC_EMMC_CMD      B @SCM_LIB.SCM(SCH_1):BMC_EMMC_CMD

Q_RES_0402LF-33.2,1%,1/16W,EMPA  I42  R649
   1 EMMC_DT0_R      A @SCM_LIB.SCM(SCH_1):EMMC_DT0_R
   2 BMC_EMMC_DT0      B @SCM_LIB.SCM(SCH_1):BMC_EMMC_DT0

Q_RES_0402LF-33.2,1%,1/16W,EMPA  I43  R648
   1 EMMC_DT1_R      A @SCM_LIB.SCM(SCH_1):EMMC_DT1_R
   2 BMC_EMMC_DT1      B @SCM_LIB.SCM(SCH_1):BMC_EMMC_DT1

Q_RES_0402LF-33.2,1%,1/16W,EMPA  I45  R647
   1 EMMC_DT2_R      A @SCM_LIB.SCM(SCH_1):EMMC_DT2_R
   2 BMC_EMMC_DT2      B @SCM_LIB.SCM(SCH_1):BMC_EMMC_DT2

Q_RES_0402LF-33.2,1%,1/16W,EMPA  I46  R532
   1 EMMC_DT3_R      A @SCM_LIB.SCM(SCH_1):EMMC_DT3_R
   2 BMC_EMMC_DT3      B @SCM_LIB.SCM(SCH_1):BMC_EMMC_DT3

Q_RES_0402LF-10K,1%,1/16W,EMPTB  I58  R662
   1 P3V3_AUX      A @SCM_LIB.SCM(SCH_1):P3V3_AUX
   2 EMMC_DT7_R      B @SCM_LIB.SCM(SCH_1):EMMC_DT7_R

Q_RES_0402LF-10K,1%,1/16W,EMPTB  I59  R663
   1 P3V3_AUX      A @SCM_LIB.SCM(SCH_1):P3V3_AUX
   2 EMMC_CMD_R      B @SCM_LIB.SCM(SCH_1):EMMC_CMD_R

Q_RES_0402LF-10K,1%,1/16W,EMPTB  I60  R661
   1 P3V3_AUX      A @SCM_LIB.SCM(SCH_1):P3V3_AUX
   2 EMMC_DT6_R      B @SCM_LIB.SCM(SCH_1):EMMC_DT6_R

Q_RES_0402LF-10K,1%,1/16W,EMPTB  I61  R660
   1 P3V3_AUX      A @SCM_LIB.SCM(SCH_1):P3V3_AUX
   2 EMMC_DT5_R      B @SCM_LIB.SCM(SCH_1):EMMC_DT5_R

Q_RES_0402LF-10K,1%,1/16W,EMPTB  I62  R658
   1 P3V3_AUX      A @SCM_LIB.SCM(SCH_1):P3V3_AUX
   2 EMMC_DT3_R      B @SCM_LIB.SCM(SCH_1):EMMC_DT3_R

Q_RES_0402LF-10K,1%,1/16W,EMPTB  I63  R657
   1 P3V3_AUX      A @SCM_LIB.SCM(SCH_1):P3V3_AUX
   2 EMMC_DT2_R      B @SCM_LIB.SCM(SCH_1):EMMC_DT2_R

Q_RES_0402LF-10K,1%,1/16W,EMPTB  I64  R659
   1 P3V3_AUX      A @SCM_LIB.SCM(SCH_1):P3V3_AUX
   2 EMMC_DT4_R      B @SCM_LIB.SCM(SCH_1):EMMC_DT4_R

Q_RES_0402LF-10K,1%,1/16W,EMPTB  I66  R656
   1 P3V3_AUX      A @SCM_LIB.SCM(SCH_1):P3V3_AUX
   2 EMMC_DT1_R      B @SCM_LIB.SCM(SCH_1):EMMC_DT1_R

Q_RES_0402LF-10K,1%,1/16W,EMPTB  I67  R655
   1 P3V3_AUX      A @SCM_LIB.SCM(SCH_1):P3V3_AUX
   2 EMMC_DT0_R      B @SCM_LIB.SCM(SCH_1):EMMC_DT0_R

Q_CAP_0402-0.1UF,25V,10%,EMPTYA  I80  C235
   1 P3V3_AUX      A @SCM_LIB.SCM(SCH_1):P3V3_AUX
   2    GND      B @SCM_LIB.SCM(SCH_1):GND

Q_CAP_C0603-22UF,10V,20%,EMPTYA  I81  C234
   1 P3V3_AUX      A @SCM_LIB.SCM(SCH_1):P3V3_AUX
   2    GND      B @SCM_LIB.SCM(SCH_1):GND

SCONN67_NASA0S6730TS67-SCONN67A  I84  J4
   2 P3V3_AUX      2 @SCM_LIB.SCM(SCH_1):P3V3_AUX
   4 P3V3_AUX      4 @SCM_LIB.SCM(SCH_1):P3V3_AUX
   6     NC      6     NC
  16 BSM_PRSNT_N     16 @SCM_LIB.SCM(SCH_1):BSM_PRSNT_N
  18    GND     18 @SCM_LIB.SCM(SCH_1):GND
  20     NC     20     NC
  22     NC     22     NC
  24    GND     24 @SCM_LIB.SCM(SCH_1):GND
  26 SPI_BMC_HOLD1_N     26 @SCM_LIB.SCM(SCH_1):SPI_BMC_HOLD1_N
  28 SPI_BMC_HOLD0_N     28 @SCM_LIB.SCM(SCH_1):SPI_BMC_HOLD0_N
  30    GND     30 @SCM_LIB.SCM(SCH_1):GND
  32     NC     32     NC
  34     NC     34     NC
  36    GND     36 @SCM_LIB.SCM(SCH_1):GND
  38     NC     38     NC
  40 SMB_BMC_MM16_R1_SCL     40 @SCM_LIB.SCM(SCH_1):SMB_BMC_MM16_R1_SCL
  42 SMB_BMC_MM16_R1_SDA     42 @SCM_LIB.SCM(SCH_1):SMB_BMC_MM16_R1_SDA
  44     NC     44     NC
  46 EMMC_WP     46 @SCM_LIB.SCM(SCH_1):EMMC_WP
  48     NC     48     NC
  50     NC     50     NC
  52 EMMC_DT7_R     52 @SCM_LIB.SCM(SCH_1):EMMC_DT7_R
  54 EMMC_DT6_R     54 @SCM_LIB.SCM(SCH_1):EMMC_DT6_R
  56 EMMC_DT5_R     56 @SCM_LIB.SCM(SCH_1):EMMC_DT5_R
  58 EMMC_DT4_R     58 @SCM_LIB.SCM(SCH_1):EMMC_DT4_R
  60     NC     60     NC
  62     NC     62     NC
  64     NC     64     NC
  66 BMC_EMMC_RST_N     66 @SCM_LIB.SCM(SCH_1):BMC_EMMC_RST_N
  68     NC     68     NC
  70     NC     70     NC
  72 P3V3_AUX     72 @SCM_LIB.SCM(SCH_1):P3V3_AUX
  74 P3V3_AUX     74 @SCM_LIB.SCM(SCH_1):P3V3_AUX
   1    GND      1 @SCM_LIB.SCM(SCH_1):GND
   3 SPI_BMC_BT_WP1_N_R      3 @SCM_LIB.SCM(SCH_1):SPI_BMC_BT_WP1_N_R
   5 SPI_BMC_BT_WP0_N_R      5 @SCM_LIB.SCM(SCH_1):SPI_BMC_BT_WP0_N_R
   7    GND      7 @SCM_LIB.SCM(SCH_1):GND
  17     NC     17     NC
  19 RST_SPI_BMC_FLASH_R2_N     19 @SCM_LIB.SCM(SCH_1):RST_SPI_BMC_FLASH_R2_N
  21 RST_SPI_BMC_FLASH_R1_N     21 @SCM_LIB.SCM(SCH_1):RST_SPI_BMC_FLASH_R1_N
  23    GND     23 @SCM_LIB.SCM(SCH_1):GND
  25 SPI_BMC_IO1_FLASH_R     25 @SCM_LIB.SCM(SCH_1):SPI_BMC_IO1_FLASH_R
  27 SPI_BMC_IO0_FLASH_R     27 @SCM_LIB.SCM(SCH_1):SPI_BMC_IO0_FLASH_R
  29    GND     29 @SCM_LIB.SCM(SCH_1):GND
  31 SPI_BMC_CLK_FLASH_R     31 @SCM_LIB.SCM(SCH_1):SPI_BMC_CLK_FLASH_R
  33    GND     33 @SCM_LIB.SCM(SCH_1):GND
  35 SPI_BMC_CS1_FLASH_R_N     35 @SCM_LIB.SCM(SCH_1):SPI_BMC_CS1_FLASH_R_N
  37 SPI_BMC_CS0_FLASH_R_N     37 @SCM_LIB.SCM(SCH_1):SPI_BMC_CS0_FLASH_R_N
  39    GND     39 @SCM_LIB.SCM(SCH_1):GND
  41     NC     41     NC
  43     NC     43     NC
  45    GND     45 @SCM_LIB.SCM(SCH_1):GND
  47     NC     47     NC
  49     NC     49     NC
  51    GND     51 @SCM_LIB.SCM(SCH_1):GND
  53     NC     53     NC
  55 EMMC_CLK_R     55 @SCM_LIB.SCM(SCH_1):EMMC_CLK_R
  57    GND     57 @SCM_LIB.SCM(SCH_1):GND
  59 EMMC_CMD_R     59 @SCM_LIB.SCM(SCH_1):EMMC_CMD_R
  61 EMMC_DT3_R     61 @SCM_LIB.SCM(SCH_1):EMMC_DT3_R
  63    GND     63 @SCM_LIB.SCM(SCH_1):GND
  65 EMMC_DT2_R     65 @SCM_LIB.SCM(SCH_1):EMMC_DT2_R
  67 EMMC_DT1_R     67 @SCM_LIB.SCM(SCH_1):EMMC_DT1_R
  69    GND     69 @SCM_LIB.SCM(SCH_1):GND
  71 EMMC_DT0_R     71 @SCM_LIB.SCM(SCH_1):EMMC_DT0_R
  73     NC     73     NC
  75    GND     75 @SCM_LIB.SCM(SCH_1):GND
  G1    GND     G1 @SCM_LIB.SCM(SCH_1):GND
  G2    GND     G2 @SCM_LIB.SCM(SCH_1):GND

Q_RES_0402LF-33.2,1%,1/16W,EMPA  I98  R651
   1 BMC_EMMC_DT6      A @SCM_LIB.SCM(SCH_1):BMC_EMMC_DT6
   2 EMMC_DT6_R      B @SCM_LIB.SCM(SCH_1):EMMC_DT6_R

Q_RES_0402LF-33.2,1%,1/16W,EMPA  I99  R650
   1 BMC_EMMC_DT7      A @SCM_LIB.SCM(SCH_1):BMC_EMMC_DT7
   2 EMMC_DT7_R      B @SCM_LIB.SCM(SCH_1):EMMC_DT7_R

Q_RES_0402LF-33.2,1%,1/16W,EMPA  I100  R653
   1 BMC_EMMC_DT4      A @SCM_LIB.SCM(SCH_1):BMC_EMMC_DT4
   2 EMMC_DT4_R      B @SCM_LIB.SCM(SCH_1):EMMC_DT4_R

Q_RES_0402LF-33.2,1%,1/16W,EMPA  I101  R652
   1 BMC_EMMC_DT5      A @SCM_LIB.SCM(SCH_1):BMC_EMMC_DT5
   2 EMMC_DT5_R      B @SCM_LIB.SCM(SCH_1):EMMC_DT5_R

Q_RES_0402LF-1K,1%,1/16W,EMPTYB  I125  R665
   1 SPI_BMC_BT_WP0_N_R      A @SCM_LIB.SCM(SCH_1):SPI_BMC_BT_WP0_N_R
   2    GND      B @SCM_LIB.SCM(SCH_1):GND

Q_RES_0402LF-1K,1%,1/16W,EMPTYB  I128  R664
   1 SPI_BMC_BT_WP1_N_R      A @SCM_LIB.SCM(SCH_1):SPI_BMC_BT_WP1_N_R
   2    GND      B @SCM_LIB.SCM(SCH_1):GND

Q_RES_0402LF-4.7K,1%,1/16W,EMPB  I147  R543
   1 P3V3_AUX      A @SCM_LIB.SCM(SCH_1):P3V3_AUX
   2 SPI_BMC_HOLD1_N      B @SCM_LIB.SCM(SCH_1):SPI_BMC_HOLD1_N

Q_RES_0402LF-33.2,1%,1/16W,CHIA  I156  R850
   1 SMB_BMC_MM16_R5_SDA      A @SCM_LIB.SCM(SCH_1):SMB_BMC_MM16_R5_SDA
   2 SMB_BMC_MM16_R1_SDA      B @SCM_LIB.SCM(SCH_1):SMB_BMC_MM16_R1_SDA

Q_RES_0402LF-33.2,1%,1/16W,CHIA  I157  R849
   1 SMB_BMC_MM16_R5_SCL      A @SCM_LIB.SCM(SCH_1):SMB_BMC_MM16_R5_SCL
   2 SMB_BMC_MM16_R1_SCL      B @SCM_LIB.SCM(SCH_1):SMB_BMC_MM16_R1_SCL

Q_RES_0402LF-1K,1%,1/16W,EMPTYA  I161  R867
   1 P3V3_AUX      A @SCM_LIB.SCM(SCH_1):P3V3_AUX
   2 EMMC_WP      B @SCM_LIB.SCM(SCH_1):EMMC_WP

Q_RES_0402LF-10K,1%,1/16W,CHIPA  I166  R404
   1 P3V3_AUX      A @SCM_LIB.SCM(SCH_1):P3V3_AUX
   2 BSM_PRSNT_N      B @SCM_LIB.SCM(SCH_1):BSM_PRSNT_N

Q_RES_0402LF-0,5%,1/16W,CHIP,CA  I167  R57
   1 BSM_PRSNT_R_N      A @SCM_LIB.SCM(SCH_1):BSM_PRSNT_R_N
   2 BSM_PRSNT_N      B @SCM_LIB.SCM(SCH_1):BSM_PRSNT_N

Q_RES_0402LF-4.7K,1%,1/16W,EMPB  I168  R58
   1 P3V3_AUX      A @SCM_LIB.SCM(SCH_1):P3V3_AUX
   2 SPI_BMC_HOLD0_N      B @SCM_LIB.SCM(SCH_1):SPI_BMC_HOLD0_N

Q_RES_0402LF-4.7K,1%,1/16W,CHIA  I172  R11
   1 P3V3_AUX      A @SCM_LIB.SCM(SCH_1):P3V3_AUX
   2 BMC_EMMC_RST_N      B @SCM_LIB.SCM(SCH_1):BMC_EMMC_RST_N

Q_RES_0402LF-4.7K,1%,1/16W,CHIA  I173  R557
   1 P3V3_AUX      A @SCM_LIB.SCM(SCH_1):P3V3_AUX
   2 SPI_BMC_CS0_FLASH_R_N      B @SCM_LIB.SCM(SCH_1):SPI_BMC_CS0_FLASH_R_N

Q_RES_0402LF-4.7K,1%,1/16W,CHIA  I174  R558
   1 P3V3_AUX      A @SCM_LIB.SCM(SCH_1):P3V3_AUX
   2 SPI_BMC_CS1_FLASH_R_N      B @SCM_LIB.SCM(SCH_1):SPI_BMC_CS1_FLASH_R_N

Q_RES_0402LF-33.2,1%,1/16W,CHIA  I175  R553
   1 SPI_BMC_CS0_FLASH_R_N      A @SCM_LIB.SCM(SCH_1):SPI_BMC_CS0_FLASH_R_N
   2 SPI_BMC_BOOT_CS0_R_N      B @SCM_LIB.SCM(SCH_1):SPI_BMC_BOOT_CS0_R_N

Q_RES_0402LF-33.2,1%,1/16W,CHIA  I176  R547
   1 SPI_BMC_CS1_FLASH_R_N      A @SCM_LIB.SCM(SCH_1):SPI_BMC_CS1_FLASH_R_N
   2 SPI_BMC_BOOT_CS1_R_N      B @SCM_LIB.SCM(SCH_1):SPI_BMC_BOOT_CS1_R_N

Q_RES_0402LF-33.2,1%,1/16W,CHIA  I177  R549
   1 SPI_BMC_CLK_FLASH_R      A @SCM_LIB.SCM(SCH_1):SPI_BMC_CLK_FLASH_R
   2 SPI_BMC_BOOT_CLK      B @SCM_LIB.SCM(SCH_1):SPI_BMC_BOOT_CLK

Q_RES_0402LF-33.2,1%,1/16W,CHIA  I178  R550
   1 SPI_BMC_IO0_FLASH_R      A @SCM_LIB.SCM(SCH_1):SPI_BMC_IO0_FLASH_R
   2 SPI_BMC_BOOT_MOSI      B @SCM_LIB.SCM(SCH_1):SPI_BMC_BOOT_MOSI

Q_RES_0402LF-33.2,1%,1/16W,CHIA  I179  R552
   1 SPI_BMC_IO1_FLASH_R      A @SCM_LIB.SCM(SCH_1):SPI_BMC_IO1_FLASH_R
   2 SPI_BMC_BOOT_MISO      B @SCM_LIB.SCM(SCH_1):SPI_BMC_BOOT_MISO

Q_RES_0402LF-33.2,1%,1/16W,CHIA  I180  R562
   1 RST_SPI_BMC_FLASH_R1_N      A @SCM_LIB.SCM(SCH_1):RST_SPI_BMC_FLASH_R1_N
   2 RST_SPI_FLASH_BUF_N      B @SCM_LIB.SCM(SCH_1):RST_SPI_FLASH_BUF_N

Q_RES_0402LF-33.2,1%,1/16W,EMPA  I181  R561
   1 RST_SPI_BMC_FLASH_R2_N      A @SCM_LIB.SCM(SCH_1):RST_SPI_BMC_FLASH_R2_N
   2 RST_SPI_FLASH_BUF_N      B @SCM_LIB.SCM(SCH_1):RST_SPI_FLASH_BUF_N

Q_RES_0402LF-4.7K,1%,1/16W,EMPA  I182  R90
   1 P3V3_AUX      A @SCM_LIB.SCM(SCH_1):P3V3_AUX
   2 RST_SPI_BMC_FLASH_R2_N      B @SCM_LIB.SCM(SCH_1):RST_SPI_BMC_FLASH_R2_N


DRAWING: @SCM_LIB.SCM(SCH_1):PAGE22 

MMBT39047F-MMBT3904-7-F,SMLF,IA  I2  Q1
   B BJT_Q3_C      1 @SCM_LIB.SCM(SCH_1):BJT_Q3_C
   E    GND      2 @SCM_LIB.SCM(SCH_1):GND
   C RST_BMC_EXTRST_R2_N      3 @SCM_LIB.SCM(SCH_1):RST_BMC_EXTRST_R2_N

MMBT39047F-MMBT3904-7-F,SMLF,IA  I4  Q3
   B BJT_Q3_B      1 @SCM_LIB.SCM(SCH_1):BJT_Q3_B
   E    GND      2 @SCM_LIB.SCM(SCH_1):GND
   C BJT_Q3_C      3 @SCM_LIB.SCM(SCH_1):BJT_Q3_C

Q_RES_0402LF-499,1%,1/16W,CHIPA  I5  R287
   1 P3V3_RGM      A @SCM_LIB.SCM(SCH_1):P3V3_RGM
   2 RST_BMC_EXTRST_R2_N      B @SCM_LIB.SCM(SCH_1):RST_BMC_EXTRST_R2_N

Q_RES_0402LF-10K,1%,1/16W,CHIPA  I7  R289
   1 P3V3_RGM      A @SCM_LIB.SCM(SCH_1):P3V3_RGM
   2 BJT_Q3_C      B @SCM_LIB.SCM(SCH_1):BJT_Q3_C

Q_RES_0402LF-47K,1%,1/16W,CHIPA  I8  R290
   1 BJT_Q3_B      A @SCM_LIB.SCM(SCH_1):BJT_Q3_B
   2 RST_BMC_EXTRST_R1_N      B @SCM_LIB.SCM(SCH_1):RST_BMC_EXTRST_R1_N

Q_RES_0402LF-4.7K,1%,1/16W,CHIA  I9  R291
   1 P3V3_RGM      A @SCM_LIB.SCM(SCH_1):P3V3_RGM
   2 RST_BMC_EXTRST_R1_N      B @SCM_LIB.SCM(SCH_1):RST_BMC_EXTRST_R1_N

Q_RES_0402LF-0,5%,1/16W,CHIP,CA  I10  R636
   1 RST_EXTRST_N      A @SCM_LIB.SCM(SCH_1):RST_EXTRST_N
   2 RST_BMC_EXTRST_R2_N      B @SCM_LIB.SCM(SCH_1):RST_BMC_EXTRST_R2_N

Q_RES_0402LF-0,5%,1/16W,EMPTY,A  I12  R106
   1 RST_BMC_SRST_N      A @SCM_LIB.SCM(SCH_1):RST_BMC_SRST_N
   2 RST_BMC_EXTRST_R2_N      B @SCM_LIB.SCM(SCH_1):RST_BMC_EXTRST_R2_N

MOSFET_N_SMLF-BSS138K,BSS138K,A  I14  U12
   G RST_BMC_SELF_HW_D_C   GATE @SCM_LIB.SCM(SCH_1):RST_BMC_SELF_HW_D_C
   D RST_BMC_EXTRST_R1_N  DRAIN @SCM_LIB.SCM(SCH_1):RST_BMC_EXTRST_R1_N
   S    GND SOURCE @SCM_LIB.SCM(SCH_1):GND

Q_CAP_0402-0.1UF,25V,10%,EMPTYA  I17  C147
   1 P3V3_AUX      A @SCM_LIB.SCM(SCH_1):P3V3_AUX
   2    GND      B @SCM_LIB.SCM(SCH_1):GND

Q_CAP_C0402-1UF,25V,10%,X6S,CHA  I23  C161
   1 RST_BMC_SELF_HW_D      A @SCM_LIB.SCM(SCH_1):RST_BMC_SELF_HW_D
   2 RST_BMC_SELF_HW_D_C      B @SCM_LIB.SCM(SCH_1):RST_BMC_SELF_HW_D_C

Q_RES_0402LF-100K,1%,1/16W,CHIA  I26  R314
   1 RST_BMC_SELF_HW_D_C      A @SCM_LIB.SCM(SCH_1):RST_BMC_SELF_HW_D_C
   2    GND      B @SCM_LIB.SCM(SCH_1):GND

Q_DIODE_SMLF-SDMK0340L-7-F,IC,A  I28  D17
   1 RST_BMC_HW_OUT      1 @SCM_LIB.SCM(SCH_1):RST_BMC_HW_OUT
   2 RST_BMC_SELF_HW_D      2 @SCM_LIB.SCM(SCH_1):RST_BMC_SELF_HW_D

Q_RES_0402LF-470K,1%,1/16W,CHIA  I30  R313
   1 RST_BMC_SELF_HW_D      A @SCM_LIB.SCM(SCH_1):RST_BMC_SELF_HW_D
   2    GND      B @SCM_LIB.SCM(SCH_1):GND

Q_RES_0402LF-100K,1%,1/16W,CHIA  I35  R614
   1 RST_SRST_PLD_BMC_R1_N      A @SCM_LIB.SCM(SCH_1):RST_SRST_PLD_BMC_R1_N
   2    GND      B @SCM_LIB.SCM(SCH_1):GND

Q_RES_0402LF-49.9,1%,1/16W,CHIA  I41  R192
   1 PWRGD_P1V0_AUX_DELAY_BUF      A @SCM_LIB.SCM(SCH_1):PWRGD_P1V0_AUX_DELAY_BUF
   2 RST_BMC_SRST_BUF_R_N      B @SCM_LIB.SCM(SCH_1):RST_BMC_SRST_BUF_R_N

Q_CAP_0402-0.1UF,25V,10%,X7R,CA  I42  C34
   1 P3V3_AUX      A @SCM_LIB.SCM(SCH_1):P3V3_AUX
   2    GND      B @SCM_LIB.SCM(SCH_1):GND

Q_CAP_C0402-4700P,25V,10%,EMPTA  I46  C223
   1 RST_BMC_SRST_BUF_R_N      A @SCM_LIB.SCM(SCH_1):RST_BMC_SRST_BUF_R_N
   2    GND      B @SCM_LIB.SCM(SCH_1):GND

Q_RES_0402LF-0,5%,1/16W,EMPTY,A  I49  R711
   1 PWRGD_PSU_AC_PWROK      A @SCM_LIB.SCM(SCH_1):PWRGD_PSU_AC_PWROK
   2 PWRGD_P1V0_AUX_DELAY      B @SCM_LIB.SCM(SCH_1):PWRGD_P1V0_AUX_DELAY

Q_RES_0402LF-100K,1%,1/16W,CHIA  I55  R710
   1 P3V3_AUX      A @SCM_LIB.SCM(SCH_1):P3V3_AUX
   2 U43_CT      B @SCM_LIB.SCM(SCH_1):U43_CT

Q_CAP_0402-0.1UF,25V,10%,X7R,CA  I57  C253
   1 P3V3_AUX      A @SCM_LIB.SCM(SCH_1):P3V3_AUX
   2    GND      B @SCM_LIB.SCM(SCH_1):GND

Q_CAP_0402-0.1UF,25V,10%,X7R,CA  I59  C264
   1 U43_CT      A @SCM_LIB.SCM(SCH_1):U43_CT
   2    GND      B @SCM_LIB.SCM(SCH_1):GND

Q_RES_0402LF-49.9,1%,1/16W,CHIA  I65  R108
   1 RST_SRST_PLD_BMC_BUF_N      A @SCM_LIB.SCM(SCH_1):RST_SRST_PLD_BMC_BUF_N
   2 RST_BMC_SRST_BUF_R_N      B @SCM_LIB.SCM(SCH_1):RST_BMC_SRST_BUF_R_N

Q_RES_0402LF-2K,1%,1/16W,CHIP,A  I67  R124
   1 P3V3_AUX      A @SCM_LIB.SCM(SCH_1):P3V3_AUX
   2 RST_BMC_SRST_BUF_R_N      B @SCM_LIB.SCM(SCH_1):RST_BMC_SRST_BUF_R_N

Q_RES_0402LF-100,1%,1/16W,CHIPA  I69  R125
   1 RST_BMC_SRST_BUF_R_N      A @SCM_LIB.SCM(SCH_1):RST_BMC_SRST_BUF_R_N
   2 RST_BMC_SRST_N      B @SCM_LIB.SCM(SCH_1):RST_BMC_SRST_N

Q_RES_0402LF-0,5%,1/16W,EMPTY,A  I71  R315
   1 RST_BMC_SRST_BUF_R_N      A @SCM_LIB.SCM(SCH_1):RST_BMC_SRST_BUF_R_N
   2 RST_BMC_SRST_BUF_R1_N      B @SCM_LIB.SCM(SCH_1):RST_BMC_SRST_BUF_R1_N

Q_RES_0402LF-0,5%,1/16W,CHIP,CA  I72  R49
   1 PWRGD_P1V0_AUX      A @SCM_LIB.SCM(SCH_1):PWRGD_P1V0_AUX
   2 PWRGD_P1V0_AUX_R2      B @SCM_LIB.SCM(SCH_1):PWRGD_P1V0_AUX_R2

Q_RES_0402LF-0,5%,1/16W,CHIP,CA  I74  R451
   1 PWRGD_P1V0_AUX_DELAY      A @SCM_LIB.SCM(SCH_1):PWRGD_P1V0_AUX_DELAY
   2 PWRGD_P1V0_AUX_DELAY_R1      B @SCM_LIB.SCM(SCH_1):PWRGD_P1V0_AUX_DELAY_R1

Q_RES_0402LF-1K,1%,1/16W,EMPTYA  I81  R633
   1 P3V3_AUX      A @SCM_LIB.SCM(SCH_1):P3V3_AUX
   2 RST_BMC_HW_OUT      B @SCM_LIB.SCM(SCH_1):RST_BMC_HW_OUT

Q_RES_0402LF-2K,1%,1/16W,CHIP,A  I83  R751
   1 P3V3_AUX      A @SCM_LIB.SCM(SCH_1):P3V3_AUX
   2 PWRGD_P1V0_AUX_DELAY_R1      B @SCM_LIB.SCM(SCH_1):PWRGD_P1V0_AUX_DELAY_R1

74LVC2G07DW7-74LVC2G07DW-7,SMLA  I87  U6
   1 PWRGD_P1V0_AUX_DELAY     1A @SCM_LIB.SCM(SCH_1):PWRGD_P1V0_AUX_DELAY
   3 RST_SRST_PLD_BMC_R1_N     2A @SCM_LIB.SCM(SCH_1):RST_SRST_PLD_BMC_R1_N
   6 PWRGD_P1V0_AUX_DELAY_BUF     1Y @SCM_LIB.SCM(SCH_1):PWRGD_P1V0_AUX_DELAY_BUF
   4 RST_SRST_PLD_BMC_BUF_N     2Y @SCM_LIB.SCM(SCH_1):RST_SRST_PLD_BMC_BUF_N
   2    GND    GND @SCM_LIB.SCM(SCH_1):GND
   5 P3V3_AUX    VCC @SCM_LIB.SCM(SCH_1):P3V3_AUX

MC74VHC1G07DFT2G-MC74VHC1G07DFA  I89  U13
   5 P3V3_AUX    VCC @SCM_LIB.SCM(SCH_1):P3V3_AUX
   2 RST_BMC_SRST_BUF_R1_N   IN_A @SCM_LIB.SCM(SCH_1):RST_BMC_SRST_BUF_R1_N
   3    GND    GND @SCM_LIB.SCM(SCH_1):GND
   4 RST_BMC_EXTRST_R1_N  OUT_Y @SCM_LIB.SCM(SCH_1):RST_BMC_EXTRST_R1_N
   1     NC    NC1     NC

TPS3808G18DBVR-TPS3808G01DBVR,A  I90  U43
   1 PWRGD_P1V0_AUX_DELAY_R1 #RESET @SCM_LIB.SCM(SCH_1):PWRGD_P1V0_AUX_DELAY_R1
   2    GND    GND @SCM_LIB.SCM(SCH_1):GND
   3 PWRGD_P1V0_AUX_R2    #MR @SCM_LIB.SCM(SCH_1):PWRGD_P1V0_AUX_R2
   6 P3V3_AUX    VDD @SCM_LIB.SCM(SCH_1):P3V3_AUX
   4 U43_CT     CT @SCM_LIB.SCM(SCH_1):U43_CT
   5 P1V0_AUX  SENSE @SCM_LIB.SCM(SCH_1):P1V0_AUX

Q_RES_0402LF-33.2,1%,1/16W,CHIA  I92  R388
   1 RST_SRST_PLD_BMC_R_N      A @SCM_LIB.SCM(SCH_1):RST_SRST_PLD_BMC_R_N
   2 RST_SRST_PLD_BMC_R1_N      B @SCM_LIB.SCM(SCH_1):RST_SRST_PLD_BMC_R1_N

MC74VHC1G32DTT1G-MC74VHC1G32DTA  I94  U58
   4 RST_BMC_HW_OUT  OUT_Y @SCM_LIB.SCM(SCH_1):RST_BMC_HW_OUT
   1 RST_BMC_SELF_HW_R3   IN_B @SCM_LIB.SCM(SCH_1):RST_BMC_SELF_HW_R3
   2 RST_BMC_HW_R1   IN_A @SCM_LIB.SCM(SCH_1):RST_BMC_HW_R1
   3    GND    GND @SCM_LIB.SCM(SCH_1):GND
   5 P3V3_AUX    VCC @SCM_LIB.SCM(SCH_1):P3V3_AUX

Q_CAP_0402-0.1UF,25V,10%,X7R,CA  I97  C337
   1 P3V3_AUX      A @SCM_LIB.SCM(SCH_1):P3V3_AUX
   2    GND      B @SCM_LIB.SCM(SCH_1):GND

Q_RES_0402LF-0,5%,1/16W,CHIP,CA  I100  R282
   1 RST_BMC_HW_R1      A @SCM_LIB.SCM(SCH_1):RST_BMC_HW_R1
   2 RST_BMC_HW      B @SCM_LIB.SCM(SCH_1):RST_BMC_HW

Q_RES_0402LF-0,5%,1/16W,CHIP,CA  I101  R450
   1 RST_BMC_SELF_HW      A @SCM_LIB.SCM(SCH_1):RST_BMC_SELF_HW
   2 RST_BMC_SELF_HW_R3      B @SCM_LIB.SCM(SCH_1):RST_BMC_SELF_HW_R3

Q_RES_0402LF-1K,1%,1/16W,EMPTYA  I102  R888
   1 P3V3_AUX      A @SCM_LIB.SCM(SCH_1):P3V3_AUX
   2 RST_BMC_SELF_HW      B @SCM_LIB.SCM(SCH_1):RST_BMC_SELF_HW

Q_RES_0402LF-4.7K,1%,1/16W,EMPA  I106  R887
   1 P3V3_AUX      A @SCM_LIB.SCM(SCH_1):P3V3_AUX
   2 RST_BMC_HW      B @SCM_LIB.SCM(SCH_1):RST_BMC_HW

Q_CAP_0402-2200PF,50V,10%,X7R,A  I107  C173
   1 RST_BMC_SELF_HW_D_C      A @SCM_LIB.SCM(SCH_1):RST_BMC_SELF_HW_D_C
   2    GND      B @SCM_LIB.SCM(SCH_1):GND


DRAWING: @SCM_LIB.SCM(SCH_1):PAGE23 

MOSFET_NCH_DUAL-2N7002KDW,SMLFA  I2  Q2
   3 V_BMC_LS_DDC_SCL     D2 @SCM_LIB.SCM(SCH_1):V_BMC_LS_DDC_SCL
   5 V_BMC_DDC_LS_GATE     G2 @SCM_LIB.SCM(SCH_1):V_BMC_DDC_LS_GATE
   4 V_BMC_DDC_SCL     S2 @SCM_LIB.SCM(SCH_1):V_BMC_DDC_SCL

Q_CAP_0402-0.1UF,25V,10%,X7R,CA  I11  C202
   1 P5V_AUX      A @SCM_LIB.SCM(SCH_1):P5V_AUX
   2    GND      B @SCM_LIB.SCM(SCH_1):GND

Q_CAP_0402-0.1UF,25V,10%,X7R,CA  I12  C203
   1 P5V_AUX      A @SCM_LIB.SCM(SCH_1):P5V_AUX
   2    GND      B @SCM_LIB.SCM(SCH_1):GND

Q_RES_0402LF-0,5%,1/16W,CHIP,CA  I19  R18
   1 P5V_AUX      A @SCM_LIB.SCM(SCH_1):P5V_AUX
   2 BMC_DDC_BUF_PWR      B @SCM_LIB.SCM(SCH_1):BMC_DDC_BUF_PWR

Q_CAP_0402-15PF,50V,5%,C0G,CH0A  I25  C205
   1 V_DACR      A @SCM_LIB.SCM(SCH_1):V_DACR
   2    GND      B @SCM_LIB.SCM(SCH_1):GND

Q_CAP_0402-15PF,50V,5%,C0G,CH0A  I26  C206
   1 V_DACG      A @SCM_LIB.SCM(SCH_1):V_DACG
   2    GND      B @SCM_LIB.SCM(SCH_1):GND

Q_RES_0402LF-4.7K,1%,1/16W,CHIA  I27  R31
   1 P3V3_RGM      A @SCM_LIB.SCM(SCH_1):P3V3_RGM
   2 V_BMC_DDC_SDA      B @SCM_LIB.SCM(SCH_1):V_BMC_DDC_SDA

Q_CAP_0402-15PF,50V,5%,C0G,CH0A  I29  C207
   1 V_DACB      A @SCM_LIB.SCM(SCH_1):V_DACB
   2    GND      B @SCM_LIB.SCM(SCH_1):GND

74HC1G126GW-74HC1G126GW,SMLF,IA  I32  U33
   2 V_VGAHS      2 @SCM_LIB.SCM(SCH_1):V_VGAHS
   4 V_VGAHS_BUF_R      4 @SCM_LIB.SCM(SCH_1):V_VGAHS_BUF_R
   5 BMC_DDC_BUF_PWR      5 @SCM_LIB.SCM(SCH_1):BMC_DDC_BUF_PWR
   1 BMC_DDC_BUF_EN      1 @SCM_LIB.SCM(SCH_1):BMC_DDC_BUF_EN
   3    GND    GND @SCM_LIB.SCM(SCH_1):GND

74HC1G126GW-74HC1G126GW,SMLF,IA  I33  U26
   2 V_VGAVS      2 @SCM_LIB.SCM(SCH_1):V_VGAVS
   4 V_VGAVS_BUF_R      4 @SCM_LIB.SCM(SCH_1):V_VGAVS_BUF_R
   5 BMC_DDC_BUF_PWR      5 @SCM_LIB.SCM(SCH_1):BMC_DDC_BUF_PWR
   1 BMC_DDC_BUF_EN      1 @SCM_LIB.SCM(SCH_1):BMC_DDC_BUF_EN
   3    GND    GND @SCM_LIB.SCM(SCH_1):GND

Q_RES_0402LF-33.2,1%,1/16W,CHIA  I34  R29
   1 V_BMC_LS_DDC_SDA      A @SCM_LIB.SCM(SCH_1):V_BMC_LS_DDC_SDA
   2 V_BMC_LS_DDC_SDA_R      B @SCM_LIB.SCM(SCH_1):V_BMC_LS_DDC_SDA_R

Q_RES_0402LF-0,5%,1/16W,CHIP,CA  I39  R30
   1 CRT_VCC5      A @SCM_LIB.SCM(SCH_1):CRT_VCC5
   2 BMC_DDC_BUF_EN      B @SCM_LIB.SCM(SCH_1):BMC_DDC_BUF_EN

Q_RES_0603LF-0,5%,1/10W,EMPTY,A  I40  R27
   1 P5V_AUX      A @SCM_LIB.SCM(SCH_1):P5V_AUX
   2 CRT_VCC5      B @SCM_LIB.SCM(SCH_1):CRT_VCC5

SCHOTTKY_AC-SS0530,SMLF,IC,BCSA  I41  D11
   A P5V_AUX      A @SCM_LIB.SCM(SCH_1):P5V_AUX
   C CRT_VCC5      C @SCM_LIB.SCM(SCH_1):CRT_VCC5

SCHOTTKY_AC-SS0530,SMLF,EMPTY,A  I42  D9
   A P5V_AUX      A @SCM_LIB.SCM(SCH_1):P5V_AUX
   C CRT_VCC5      C @SCM_LIB.SCM(SCH_1):CRT_VCC5

Q_CAP_0603-1UF,16V,10%,EMPTY,TA  I45  C204
   1 CRT_VCC5      A @SCM_LIB.SCM(SCH_1):CRT_VCC5
   2    GND      B @SCM_LIB.SCM(SCH_1):GND

Q_RES_0402LF-4.7K,1%,1/16W,CHIA  I50  R32
   1 P3V3_RGM      A @SCM_LIB.SCM(SCH_1):P3V3_RGM
   2 V_BMC_DDC_SCL      B @SCM_LIB.SCM(SCH_1):V_BMC_DDC_SCL

Q_RES_0402LF-0,5%,1/16W,CHIP,CA  I51  R86
   1 P3V3_RGM      A @SCM_LIB.SCM(SCH_1):P3V3_RGM
   2 V_BMC_DDC_LS_GATE      B @SCM_LIB.SCM(SCH_1):V_BMC_DDC_LS_GATE

Q_CAP_0402-18PF,50V,5%,C0G,CH0A  I54  C209
   1 V_DACG_IO      A @SCM_LIB.SCM(SCH_1):V_DACG_IO
   2    GND      B @SCM_LIB.SCM(SCH_1):GND

MOSFET_NCH_DUAL-2N7002KDW,SMLFA  I56  Q2
   1 V_BMC_DDC_SDA     S1 @SCM_LIB.SCM(SCH_1):V_BMC_DDC_SDA
   2 V_BMC_DDC_LS_GATE     G1 @SCM_LIB.SCM(SCH_1):V_BMC_DDC_LS_GATE
   6 V_BMC_LS_DDC_SDA     D1 @SCM_LIB.SCM(SCH_1):V_BMC_LS_DDC_SDA

Q_RES_0402LF-150,1%,1/16W,CHIPA  I57  R87
   1 V_DACB_IO      A @SCM_LIB.SCM(SCH_1):V_DACB_IO
   2    GND      B @SCM_LIB.SCM(SCH_1):GND

Q_RES_0402LF-150,1%,1/16W,CHIPA  I59  R88
   1 V_DACG_IO      A @SCM_LIB.SCM(SCH_1):V_DACG_IO
   2    GND      B @SCM_LIB.SCM(SCH_1):GND

Q_RES_0402LF-0,5%,1/16W,CHIP,CA  I60  R85
   1 V_VGAHS_BUF_R      A @SCM_LIB.SCM(SCH_1):V_VGAHS_BUF_R
   2 V_VGAHS_BUF      B @SCM_LIB.SCM(SCH_1):V_VGAHS_BUF

Q_RES_0402LF-0,5%,1/16W,CHIP,CA  I61  R84
   1 V_VGAVS_BUF_R      A @SCM_LIB.SCM(SCH_1):V_VGAVS_BUF_R
   2 V_VGAVS_BUF      B @SCM_LIB.SCM(SCH_1):V_VGAVS_BUF

Q_RES_0402LF-2.2K,5%,1/16W,CHIA  I62  R91
   1 CRT_VCC5      A @SCM_LIB.SCM(SCH_1):CRT_VCC5
   2 V_BMC_LS_DDC_SDA      B @SCM_LIB.SCM(SCH_1):V_BMC_LS_DDC_SDA

Q_RES_0402LF-2.2K,5%,1/16W,CHIA  I64  R92
   1 CRT_VCC5      A @SCM_LIB.SCM(SCH_1):CRT_VCC5
   2 V_BMC_LS_DDC_SCL      B @SCM_LIB.SCM(SCH_1):V_BMC_LS_DDC_SCL

Q_RES_0402LF-150,1%,1/16W,CHIPA  I65  R89
   1 V_DACR_IO      A @SCM_LIB.SCM(SCH_1):V_DACR_IO
   2    GND      B @SCM_LIB.SCM(SCH_1):GND

Q_CAP_0402-10PF,50V,1%,NPO,TMPA  I67  C211
   1 V_VGAHS_BUF      A @SCM_LIB.SCM(SCH_1):V_VGAHS_BUF
   2    GND      B @SCM_LIB.SCM(SCH_1):GND

Q_RES_0402LF-2.21K,1%,1/16W,EMA  I68  R17
   1 V_BMC_LS_DDC_SDA_R      A @SCM_LIB.SCM(SCH_1):V_BMC_LS_DDC_SDA_R
   2 CRT_VCC5      B @SCM_LIB.SCM(SCH_1):CRT_VCC5

BZA462A-BZA462A,SMLF,EMPTY,BCZA  I74  D12
   2    GND      2 @SCM_LIB.SCM(SCH_1):GND
   5    GND      5 @SCM_LIB.SCM(SCH_1):GND
   1 CRT_VCC5      1 @SCM_LIB.SCM(SCH_1):CRT_VCC5
   3 CRT_VCC5      3 @SCM_LIB.SCM(SCH_1):CRT_VCC5
   4 CRT_VCC5      4 @SCM_LIB.SCM(SCH_1):CRT_VCC5
   6 CRT_VCC5      6 @SCM_LIB.SCM(SCH_1):CRT_VCC5

Q_RES_0402LF-2.21K,1%,1/16W,EMA  I75  R16
   1 V_BMC_LS_DDC_SCL_R      A @SCM_LIB.SCM(SCH_1):V_BMC_LS_DDC_SCL_R
   2 CRT_VCC5      B @SCM_LIB.SCM(SCH_1):CRT_VCC5

Q_CAP_0402-10PF,50V,1%,NPO,TMPA  I77  C212
   1 V_VGAVS_BUF      A @SCM_LIB.SCM(SCH_1):V_VGAVS_BUF
   2    GND      B @SCM_LIB.SCM(SCH_1):GND

Q_CAP_0402-100PF,50V,5%,EMPTY,A  I83  C213
   1 V_BMC_LS_DDC_SDA_R      A @SCM_LIB.SCM(SCH_1):V_BMC_LS_DDC_SDA_R
   2    GND      B @SCM_LIB.SCM(SCH_1):GND

Q_CAP_0402-100PF,50V,5%,EMPTY,A  I84  C214
   1 V_BMC_LS_DDC_SCL_R      A @SCM_LIB.SCM(SCH_1):V_BMC_LS_DDC_SCL_R
   2    GND      B @SCM_LIB.SCM(SCH_1):GND

Q_RES_0402LF-33.2,1%,1/16W,CHIA  I99  R28
   1 V_BMC_LS_DDC_SCL      A @SCM_LIB.SCM(SCH_1):V_BMC_LS_DDC_SCL
   2 V_BMC_LS_DDC_SCL_R      B @SCM_LIB.SCM(SCH_1):V_BMC_LS_DDC_SCL_R

Q_FUSE_SMLF-1.1A/8V,EMPTY,DK11A  I153  FS1
   1 CRT_VCC5_2_D      1 @SCM_LIB.SCM(SCH_1):CRT_VCC5_2_D
   2 CRT_VCC5_2_FUSE      2 @SCM_LIB.SCM(SCH_1):CRT_VCC5_2_FUSE

DT1240E04LP7-DT1240E-04LP-7,SMA  I155  U35
   1 V_DACB_IO    IO1 @SCM_LIB.SCM(SCH_1):V_DACB_IO
   3    GND   VSS1 @SCM_LIB.SCM(SCH_1):GND
   4 V_DACR_IO    IO3 @SCM_LIB.SCM(SCH_1):V_DACR_IO
   6 TP_ESD_VGA_P4    NC1 @SCM_LIB.SCM(SCH_1):TP_ESD_VGA_P4
   8    GND   VSS2 @SCM_LIB.SCM(SCH_1):GND
   9 V_DACG_IO    NC3 @SCM_LIB.SCM(SCH_1):V_DACG_IO
  10 V_DACB_IO    NC4 @SCM_LIB.SCM(SCH_1):V_DACB_IO
   2 V_DACG_IO    IO2 @SCM_LIB.SCM(SCH_1):V_DACG_IO
   5    TP4    IO4 @SCM_LIB.SCM(SCH_1):TP4
   7 V_DACR_IO    NC2 @SCM_LIB.SCM(SCH_1):V_DACR_IO

DT1240E04LP7-DT1240E-04LP-7,SMA  I156  U34
   1 V_BMC_LS_DDC_SCL_R    IO1 @SCM_LIB.SCM(SCH_1):V_BMC_LS_DDC_SCL_R
   3    GND   VSS1 @SCM_LIB.SCM(SCH_1):GND
   4 V_VGAHS_BUF    IO3 @SCM_LIB.SCM(SCH_1):V_VGAHS_BUF
   6 V_VGAVS_BUF    NC1 @SCM_LIB.SCM(SCH_1):V_VGAVS_BUF
   8    GND   VSS2 @SCM_LIB.SCM(SCH_1):GND
   9 V_BMC_LS_DDC_SDA_R    NC3 @SCM_LIB.SCM(SCH_1):V_BMC_LS_DDC_SDA_R
  10 V_BMC_LS_DDC_SCL_R    NC4 @SCM_LIB.SCM(SCH_1):V_BMC_LS_DDC_SCL_R
   2 V_BMC_LS_DDC_SDA_R    IO2 @SCM_LIB.SCM(SCH_1):V_BMC_LS_DDC_SDA_R
   5 V_VGAVS_BUF    IO4 @SCM_LIB.SCM(SCH_1):V_VGAVS_BUF
   7 V_VGAHS_BUF    NC2 @SCM_LIB.SCM(SCH_1):V_VGAHS_BUF

SCHOTTKY_12-SBA130Q,SMLF,EMPTYA  I161  D16
   1 P5V_AUX      A @SCM_LIB.SCM(SCH_1):P5V_AUX
   2 CRT_VCC5_2_D      C @SCM_LIB.SCM(SCH_1):CRT_VCC5_2_D

SCONN13_502280130CV01-SCONN13_A  I165  J8
   1 V_DACR_IO      1 @SCM_LIB.SCM(SCH_1):V_DACR_IO
   2    GND      2 @SCM_LIB.SCM(SCH_1):GND
   3 V_DACG_IO      3 @SCM_LIB.SCM(SCH_1):V_DACG_IO
   4    GND      4 @SCM_LIB.SCM(SCH_1):GND
   5 V_DACB_IO      5 @SCM_LIB.SCM(SCH_1):V_DACB_IO
   6    GND      6 @SCM_LIB.SCM(SCH_1):GND
   7 V_VGAVS_BUF      7 @SCM_LIB.SCM(SCH_1):V_VGAVS_BUF
   8    GND      8 @SCM_LIB.SCM(SCH_1):GND
   9 V_VGAHS_BUF      9 @SCM_LIB.SCM(SCH_1):V_VGAHS_BUF
  10    GND     10 @SCM_LIB.SCM(SCH_1):GND
  11 V_BMC_LS_DDC_SDA_R     11 @SCM_LIB.SCM(SCH_1):V_BMC_LS_DDC_SDA_R
  12 V_BMC_LS_DDC_SCL_R     12 @SCM_LIB.SCM(SCH_1):V_BMC_LS_DDC_SCL_R
  13 CRT_VCC5_2_FUSE     13 @SCM_LIB.SCM(SCH_1):CRT_VCC5_2_FUSE
  G1    GND     G1 @SCM_LIB.SCM(SCH_1):GND
  G2    GND     G2 @SCM_LIB.SCM(SCH_1):GND

Q_INDUCTOR_SMLF-BLM18BB470/500A  I166  L28
   2 V_DACB_IO      2 @SCM_LIB.SCM(SCH_1):V_DACB_IO
   1 V_DACB      1 @SCM_LIB.SCM(SCH_1):V_DACB

Q_INDUCTOR_SMLF-BLM18BB470/500A  I167  L29
   2 V_DACG_IO      2 @SCM_LIB.SCM(SCH_1):V_DACG_IO
   1 V_DACG      1 @SCM_LIB.SCM(SCH_1):V_DACG

Q_INDUCTOR_SMLF-BLM18BB470/500A  I168  L30
   2 V_DACR_IO      2 @SCM_LIB.SCM(SCH_1):V_DACR_IO
   1 V_DACR      1 @SCM_LIB.SCM(SCH_1):V_DACR

Q_CAP_0402-22PF,50V,5%,NPO,TMPA  I169  C208
   1 V_DACR_IO      A @SCM_LIB.SCM(SCH_1):V_DACR_IO
   2    GND      B @SCM_LIB.SCM(SCH_1):GND

Q_CAP_0402-22PF,50V,5%,NPO,TMPA  I170  C210
   1 V_DACB_IO      A @SCM_LIB.SCM(SCH_1):V_DACB_IO
   2    GND      B @SCM_LIB.SCM(SCH_1):GND


DRAWING: @SCM_LIB.SCM(SCH_1):PAGE25 

Q_RES_0402LF-4.7K,1%,1/16W,CHIA  I3  R563
   1 P3V3_AUX      A @SCM_LIB.SCM(SCH_1):P3V3_AUX
   2 RST_SPI_FLASH_BUF_N      B @SCM_LIB.SCM(SCH_1):RST_SPI_FLASH_BUF_N

SN74LVC1G07DCKR-SN74LVC1G07DCKA  I61  U44
   5 P3V3_AUX    VCC @SCM_LIB.SCM(SCH_1):P3V3_AUX
   2 RST_SPI_FLASH_R_N      A @SCM_LIB.SCM(SCH_1):RST_SPI_FLASH_R_N
   3    GND    GND @SCM_LIB.SCM(SCH_1):GND
   4 RST_SPI_FLASH_BUF_R3_N      Y @SCM_LIB.SCM(SCH_1):RST_SPI_FLASH_BUF_R3_N
   1     NC    NC1     NC

Q_CAP_0402-0.1UF,25V,10%,X7R,CA  I65  C304
   1 P3V3_AUX      A @SCM_LIB.SCM(SCH_1):P3V3_AUX
   2    GND      B @SCM_LIB.SCM(SCH_1):GND

Q_RES_0402LF-33.2,1%,1/16W,CHIA  I67  R752
   1 RST_SPI_FLASH_N      A @SCM_LIB.SCM(SCH_1):RST_SPI_FLASH_N
   2 RST_SPI_FLASH_R_N      B @SCM_LIB.SCM(SCH_1):RST_SPI_FLASH_R_N

Q_RES_0402LF-33.2,1%,1/16W,CHIA  I73  R827
   1 RST_SPI_FLASH_BUF_R3_N      A @SCM_LIB.SCM(SCH_1):RST_SPI_FLASH_BUF_R3_N
   2 RST_SPI_FLASH_BUF_N      B @SCM_LIB.SCM(SCH_1):RST_SPI_FLASH_BUF_N

74LVC1G74DP-74LVC1G74DP,SMLF,IA  I138  U54
   1 FLASH_LATCH_CP     CP @SCM_LIB.SCM(SCH_1):FLASH_LATCH_CP
   2 FLASH_LATCH_D      D @SCM_LIB.SCM(SCH_1):FLASH_LATCH_D
   3 FLASH_LATCH_Q_N_R    Q_N @SCM_LIB.SCM(SCH_1):FLASH_LATCH_Q_N_R
   4    GND    GND @SCM_LIB.SCM(SCH_1):GND
   8 P3V3_AUX    VCC @SCM_LIB.SCM(SCH_1):P3V3_AUX
   6   RD_N   RD_N @SCM_LIB.SCM(SCH_1):RD_N
   7 FM_FLASH_LATCH_N   SD_N @SCM_LIB.SCM(SCH_1):FM_FLASH_LATCH_N
   5 NC_U54_P1      Q @SCM_LIB.SCM(SCH_1):NC_U54_P1

Q_RES_0402LF-0,5%,1/16W,CHIP,CA  I142  R182
   1    GND      A @SCM_LIB.SCM(SCH_1):GND
   2 FLASH_LATCH_D      B @SCM_LIB.SCM(SCH_1):FLASH_LATCH_D

Q_RES_0402LF-0,5%,1/16W,CHIP,CA  I143  R545
   1    GND      A @SCM_LIB.SCM(SCH_1):GND
   2 FLASH_LATCH_CP      B @SCM_LIB.SCM(SCH_1):FLASH_LATCH_CP

Q_CAP_0402-0.1UF,25V,10%,X7R,CA  I146  C312
   1 P3V3_AUX      A @SCM_LIB.SCM(SCH_1):P3V3_AUX
   2    GND      B @SCM_LIB.SCM(SCH_1):GND

Q_RES_0402LF-0,5%,1/16W,CHIP,CA  I149  R560
   1 FLASH_LATCH_Q_N_R1      A @SCM_LIB.SCM(SCH_1):FLASH_LATCH_Q_N_R1
   2 FLASH_LATCH_Q_N_R2      B @SCM_LIB.SCM(SCH_1):FLASH_LATCH_Q_N_R2

SN74LVC1G14DCKR_SMLF-IC,SN74LVA  I150  U55
   2 FLASH_LATCH_Q_N_R2      A @SCM_LIB.SCM(SCH_1):FLASH_LATCH_Q_N_R2
   4 FLASH_R_WP_STATUS      Y @SCM_LIB.SCM(SCH_1):FLASH_R_WP_STATUS
   1 NC_U55_P1     NC @SCM_LIB.SCM(SCH_1):NC_U55_P1
   5 P3V3_AUX    VCC @SCM_LIB.SCM(SCH_1):P3V3_AUX
   3    GND    GND @SCM_LIB.SCM(SCH_1):GND

Q_CAP_0402-0.1UF,25V,10%,X7R,CA  I154  C313
   1 P3V3_AUX      A @SCM_LIB.SCM(SCH_1):P3V3_AUX
   2    GND      B @SCM_LIB.SCM(SCH_1):GND

Q_RES_0402LF-4.7K,1%,1/16W,EMPB  I156  R554
   1 P3V3_AUX      A @SCM_LIB.SCM(SCH_1):P3V3_AUX
   2 FLASH_R_WP_STATUS      B @SCM_LIB.SCM(SCH_1):FLASH_R_WP_STATUS

SCONN3_212H9103GBR1-SCONN3_212A  I169  J1
   3 NC_J1_P3      3 @SCM_LIB.SCM(SCH_1):NC_J1_P3
   2 FLASH_LATCH_Q_N_R2      2 @SCM_LIB.SCM(SCH_1):FLASH_LATCH_Q_N_R2
   1 PU_J1_P1      1 @SCM_LIB.SCM(SCH_1):PU_J1_P1

Q_RES_0402LF-4.7K,1%,1/16W,CHIA  I170  R181
   1 P3V3_AUX      A @SCM_LIB.SCM(SCH_1):P3V3_AUX
   2 FM_FLASH_LATCH_N      B @SCM_LIB.SCM(SCH_1):FM_FLASH_LATCH_N

Q_RES_0402LF-4.7K,1%,1/16W,CHIA  I171  R592
   1 P3V3_AUX      A @SCM_LIB.SCM(SCH_1):P3V3_AUX
   2 PU_J1_P1      B @SCM_LIB.SCM(SCH_1):PU_J1_P1

Q_RES_0402LF-33.2,1%,1/16W,CHIA  I172  R548
   1 BMC_RSTIND_N      A @SCM_LIB.SCM(SCH_1):BMC_RSTIND_N
   2   RD_N      B @SCM_LIB.SCM(SCH_1):RD_N

Q_RES_0402LF-33.2,1%,1/16W,CHIA  I173  R551
   1 FLASH_WP_STATUS      A @SCM_LIB.SCM(SCH_1):FLASH_WP_STATUS
   2 FLASH_R_WP_STATUS      B @SCM_LIB.SCM(SCH_1):FLASH_R_WP_STATUS

Q_RES_0402LF-33.2,1%,1/16W,CHIA  I174  R555
   1 FLASH_LATCH_Q_N_R      A @SCM_LIB.SCM(SCH_1):FLASH_LATCH_Q_N_R
   2 FLASH_LATCH_Q_N_R1      B @SCM_LIB.SCM(SCH_1):FLASH_LATCH_Q_N_R1

Q_RES_0402LF-33.2,1%,1/16W,CHIA  I175  R556
   1 SPI_BMC_BT_WP1_N_R      A @SCM_LIB.SCM(SCH_1):SPI_BMC_BT_WP1_N_R
   2 FLASH_LATCH_Q_N_R2      B @SCM_LIB.SCM(SCH_1):FLASH_LATCH_Q_N_R2

Q_RES_0402LF-33.2,1%,1/16W,CHIA  I176  R559
   1 SPI_BMC_BT_WP0_N_R      A @SCM_LIB.SCM(SCH_1):SPI_BMC_BT_WP0_N_R
   2 FLASH_LATCH_Q_N_R2      B @SCM_LIB.SCM(SCH_1):FLASH_LATCH_Q_N_R2


DRAWING: @SCM_LIB.SCM(SCH_1):PAGE26 

Q_RES_0402LF-100,1%,1/16W,CHIPA  I6  R411
   1 FRU_E0      A @SCM_LIB.SCM(SCH_1):FRU_E0
   2    GND      B @SCM_LIB.SCM(SCH_1):GND

Q_RES_0402LF-100,1%,1/16W,CHIPA  I8  R412
   1 FRU_E1      A @SCM_LIB.SCM(SCH_1):FRU_E1
   2    GND      B @SCM_LIB.SCM(SCH_1):GND

Q_RES_0402LF-4.7K,1%,1/16W,EMPA  I9  R12
   1 P3V3_AUX      A @SCM_LIB.SCM(SCH_1):P3V3_AUX
   2 FRU_E0      B @SCM_LIB.SCM(SCH_1):FRU_E0

Q_RES_0402LF-4.7K,1%,1/16W,EMPA  I11  R13
   1 P3V3_AUX      A @SCM_LIB.SCM(SCH_1):P3V3_AUX
   2 FRU_E1      B @SCM_LIB.SCM(SCH_1):FRU_E1

Q_RES_0402LF-100,1%,1/16W,CHIPA  I12  R413
   1 FRU_E2      A @SCM_LIB.SCM(SCH_1):FRU_E2
   2    GND      B @SCM_LIB.SCM(SCH_1):GND

Q_RES_0402LF-4.7K,1%,1/16W,EMPA  I14  R14
   1 P3V3_AUX      A @SCM_LIB.SCM(SCH_1):P3V3_AUX
   2 FRU_E2      B @SCM_LIB.SCM(SCH_1):FRU_E2

M24128BWDW6TP-M24128-BWDW6TP,SA  I15  U19
   8 P3V3_AUX    VCC @SCM_LIB.SCM(SCH_1):P3V3_AUX
   7 PD_FRU_WC_N    WC# @SCM_LIB.SCM(SCH_1):PD_FRU_WC_N
   6 SMB_BMC_MM16_R2_SCL    SCL @SCM_LIB.SCM(SCH_1):SMB_BMC_MM16_R2_SCL
   5 SMB_BMC_MM16_R2_SDA    SDA @SCM_LIB.SCM(SCH_1):SMB_BMC_MM16_R2_SDA
   4    GND    VSS @SCM_LIB.SCM(SCH_1):GND
   3 FRU_E2     E2 @SCM_LIB.SCM(SCH_1):FRU_E2
   2 FRU_E1     E1 @SCM_LIB.SCM(SCH_1):FRU_E1
   1 FRU_E0     E0 @SCM_LIB.SCM(SCH_1):FRU_E0

Q_CAP_0402-0.1UF,25V,10%,X7R,CA  I17  C192
   1 P3V3_AUX      A @SCM_LIB.SCM(SCH_1):P3V3_AUX
   2    GND      B @SCM_LIB.SCM(SCH_1):GND

Q_RES_0402LF-1K,1%,1/16W,CHIP,A  I32  R15
   1 PD_FRU_WC_N      A @SCM_LIB.SCM(SCH_1):PD_FRU_WC_N
   2    GND      B @SCM_LIB.SCM(SCH_1):GND

Q_RES_0402LF-33.2,1%,1/16W,CHIA  I33  R421
   1 SMB_BMC_MM16_R2_SDA      A @SCM_LIB.SCM(SCH_1):SMB_BMC_MM16_R2_SDA
   2 SMB_BMC_MM16_SDA      B @SCM_LIB.SCM(SCH_1):SMB_BMC_MM16_SDA

Q_RES_0402LF-1K,1%,1/16W,CHIP,A  I37  R419
   1 TMC75_A2      A @SCM_LIB.SCM(SCH_1):TMC75_A2
   2    GND      B @SCM_LIB.SCM(SCH_1):GND

Q_RES_0402LF-1K,1%,1/16W,EMPTYA  I39  R417
   1 TMC75_A0      A @SCM_LIB.SCM(SCH_1):TMC75_A0
   2    GND      B @SCM_LIB.SCM(SCH_1):GND

Q_RES_0402LF-4.7K,1%,1/16W,EMPA  I40  R418
   1 P3V3_AUX      A @SCM_LIB.SCM(SCH_1):P3V3_AUX
   2 TMC75_A2      B @SCM_LIB.SCM(SCH_1):TMC75_A2

Q_RES_0402LF-4.7K,1%,1/16W,CHIA  I41  R416
   1 P3V3_AUX      A @SCM_LIB.SCM(SCH_1):P3V3_AUX
   2 TMC75_A0      B @SCM_LIB.SCM(SCH_1):TMC75_A0

Q_CAP_0402-0.1UF,25V,10%,X7R,CA  I54  C191
   1 P3V3_AUX      A @SCM_LIB.SCM(SCH_1):P3V3_AUX
   2    GND      B @SCM_LIB.SCM(SCH_1):GND

Q_RES_0402LF-49.9,1%,1/16W,CHIA  I56  R410
   1 SMB_TMP421_BMC_MM2_SCL      A @SCM_LIB.SCM(SCH_1):SMB_TMP421_BMC_MM2_SCL
   2 SMB_BMC_MM2_SCL      B @SCM_LIB.SCM(SCH_1):SMB_BMC_MM2_SCL

Q_RES_0402LF-49.9,1%,1/16W,CHIA  I57  R409
   1 SMB_TMP421_BMC_MM2_SDA      A @SCM_LIB.SCM(SCH_1):SMB_TMP421_BMC_MM2_SDA
   2 SMB_BMC_MM2_SDA      B @SCM_LIB.SCM(SCH_1):SMB_BMC_MM2_SDA

Q_RES_0402LF-10K,1%,1/16W,CHIPA  I65  R54
   1 SMB_BMC_ALERT16_R_N      A @SCM_LIB.SCM(SCH_1):SMB_BMC_ALERT16_R_N
   2 SMB_BMC_ALERT16_N      B @SCM_LIB.SCM(SCH_1):SMB_BMC_ALERT16_N

Q_RES_0402LF-1K,1%,1/16W,EMPTYA  I66  R53
   1 TMC75_A1      A @SCM_LIB.SCM(SCH_1):TMC75_A1
   2    GND      B @SCM_LIB.SCM(SCH_1):GND

Q_RES_0402LF-4.7K,1%,1/16W,CHIA  I67  R52
   1 P3V3_AUX      A @SCM_LIB.SCM(SCH_1):P3V3_AUX
   2 TMC75_A1      B @SCM_LIB.SCM(SCH_1):TMC75_A1

Q_RES_0402LF-150,1%,1/16W,CHIPA  I69  R420
   1 SMB_BMC_MM16_R2_SCL      A @SCM_LIB.SCM(SCH_1):SMB_BMC_MM16_R2_SCL
   2 SMB_BMC_MM16_SCL      B @SCM_LIB.SCM(SCH_1):SMB_BMC_MM16_SCL

CONN8_TSW10407FD-CONN8_TSW-104A  I71  J14
   5 TMC75_A1      5 @SCM_LIB.SCM(SCH_1):TMC75_A1
   6 SMB_BMC_ALERT16_R_N      6 @SCM_LIB.SCM(SCH_1):SMB_BMC_ALERT16_R_N
   7 TMC75_A2      7 @SCM_LIB.SCM(SCH_1):TMC75_A2
   8    GND      8 @SCM_LIB.SCM(SCH_1):GND
   3 TMC75_A0      3 @SCM_LIB.SCM(SCH_1):TMC75_A0
   1 P3V3_AUX      1 @SCM_LIB.SCM(SCH_1):P3V3_AUX
   4 SMB_TMP421_BMC_MM2_SCL      4 @SCM_LIB.SCM(SCH_1):SMB_TMP421_BMC_MM2_SCL
   2 SMB_TMP421_BMC_MM2_SDA      2 @SCM_LIB.SCM(SCH_1):SMB_TMP421_BMC_MM2_SDA


DRAWING: @SCM_LIB.SCM(SCH_1):PAGE27 

Q_RES_0402LF-4.7K,1%,1/16W,CHIA  I84  R269
   1 P3V3_AUX      A @SCM_LIB.SCM(SCH_1):P3V3_AUX
   2 SMB_BMC_ALERT4_N      B @SCM_LIB.SCM(SCH_1):SMB_BMC_ALERT4_N

Q_RES_0402LF-4.7K,1%,1/16W,EMPA  I85  R267
   1 P3V3_AUX      A @SCM_LIB.SCM(SCH_1):P3V3_AUX
   2 VOL_SEN_ALERT_R      B @SCM_LIB.SCM(SCH_1):VOL_SEN_ALERT_R

Q_RES_0402LF-4.7K,1%,1/16W,CHIA  I86  R268
   1 P3V3_AUX      A @SCM_LIB.SCM(SCH_1):P3V3_AUX
   2 SMB_BMC_ALERT3_N      B @SCM_LIB.SCM(SCH_1):SMB_BMC_ALERT3_N

Q_RES_0402LF-2.2K,5%,1/16W,CHIA  I88  R265
   1 P3V3_AUX      A @SCM_LIB.SCM(SCH_1):P3V3_AUX
   2 SMB_BMC_MM16_SDA      B @SCM_LIB.SCM(SCH_1):SMB_BMC_MM16_SDA

Q_RES_0402LF-2.2K,5%,1/16W,CHIA  I89  R264
   1 P3V3_AUX      A @SCM_LIB.SCM(SCH_1):P3V3_AUX
   2 SMB_BMC_MM16_SCL      B @SCM_LIB.SCM(SCH_1):SMB_BMC_MM16_SCL

Q_RES_0402LF-10K,1%,1/16W,CHIPA  I93  R262
   1 P3V3_AUX      A @SCM_LIB.SCM(SCH_1):P3V3_AUX
   2 SMB_BMC_MM10_SCL      B @SCM_LIB.SCM(SCH_1):SMB_BMC_MM10_SCL

Q_RES_0402LF-10K,1%,1/16W,CHIPA  I94  R261
   1 P3V3_AUX      A @SCM_LIB.SCM(SCH_1):P3V3_AUX
   2 SMB_BMC_MM9_SDA      B @SCM_LIB.SCM(SCH_1):SMB_BMC_MM9_SDA

Q_RES_0402LF-4.7K,1%,1/16W,EMPA  I95  R266
   1 P3V3_AUX      A @SCM_LIB.SCM(SCH_1):P3V3_AUX
   2 FM_ME_BT_DONE      B @SCM_LIB.SCM(SCH_1):FM_ME_BT_DONE

Q_RES_0402LF-2.2K,5%,1/16W,CHIA  I96  R259
   1 P3V3_AUX      A @SCM_LIB.SCM(SCH_1):P3V3_AUX
   2 SMB_BMC_MM8_SDA      B @SCM_LIB.SCM(SCH_1):SMB_BMC_MM8_SDA

Q_RES_0402LF-10K,1%,1/16W,CHIPA  I97  R260
   1 P3V3_AUX      A @SCM_LIB.SCM(SCH_1):P3V3_AUX
   2 SMB_BMC_MM9_SCL      B @SCM_LIB.SCM(SCH_1):SMB_BMC_MM9_SCL

Q_RES_0402LF-2.2K,5%,1/16W,CHIA  I98  R258
   1 P3V3_AUX      A @SCM_LIB.SCM(SCH_1):P3V3_AUX
   2 SMB_BMC_MM8_SCL      B @SCM_LIB.SCM(SCH_1):SMB_BMC_MM8_SCL

Q_RES_0402LF-2.2K,5%,1/16W,CHIA  I99  R257
   1 P3V3_AUX      A @SCM_LIB.SCM(SCH_1):P3V3_AUX
   2 SMB_BMC_MM7_R_SDA      B @SCM_LIB.SCM(SCH_1):SMB_BMC_MM7_R_SDA

Q_RES_0402LF-2.2K,5%,1/16W,CHIA  I100  R256
   1 P3V3_AUX      A @SCM_LIB.SCM(SCH_1):P3V3_AUX
   2 SMB_BMC_MM7_R_SCL      B @SCM_LIB.SCM(SCH_1):SMB_BMC_MM7_R_SCL

Q_RES_0402LF-10K,1%,1/16W,CHIPA  I101  R254
   1 P3V3_AUX      A @SCM_LIB.SCM(SCH_1):P3V3_AUX
   2 SMB_BMC_MM6_SCL      B @SCM_LIB.SCM(SCH_1):SMB_BMC_MM6_SCL

Q_RES_0402LF-10K,1%,1/16W,CHIPA  I102  R255
   1 P3V3_AUX      A @SCM_LIB.SCM(SCH_1):P3V3_AUX
   2 SMB_BMC_MM6_SDA      B @SCM_LIB.SCM(SCH_1):SMB_BMC_MM6_SDA

Q_RES_0402LF-2.2K,5%,1/16W,CHIA  I103  R253
   1 P3V3_AUX      A @SCM_LIB.SCM(SCH_1):P3V3_AUX
   2 SMB_BMC_MM5_R_SDA      B @SCM_LIB.SCM(SCH_1):SMB_BMC_MM5_R_SDA

Q_RES_0402LF-2.2K,5%,1/16W,CHIA  I105  R252
   1 P3V3_AUX      A @SCM_LIB.SCM(SCH_1):P3V3_AUX
   2 SMB_BMC_MM5_R_SCL      B @SCM_LIB.SCM(SCH_1):SMB_BMC_MM5_R_SCL

Q_RES_0402LF-402,1%,1/16W,CHIPA  I106  R250
   1 P3V3_AUX      A @SCM_LIB.SCM(SCH_1):P3V3_AUX
   2 SMB_BMC_MM4_SCL      B @SCM_LIB.SCM(SCH_1):SMB_BMC_MM4_SCL

Q_RES_0402LF-2.2K,5%,1/16W,CHIA  I107  R248
   1 P3V3_AUX      A @SCM_LIB.SCM(SCH_1):P3V3_AUX
   2 SMB_BMC_MM3_SCL      B @SCM_LIB.SCM(SCH_1):SMB_BMC_MM3_SCL

Q_RES_0402LF-2.2K,5%,1/16W,CHIA  I108  R249
   1 P3V3_AUX      A @SCM_LIB.SCM(SCH_1):P3V3_AUX
   2 SMB_BMC_MM3_SDA      B @SCM_LIB.SCM(SCH_1):SMB_BMC_MM3_SDA

Q_RES_0402LF-2.2K,5%,1/16W,CHIA  I109  R247
   1 P3V3_AUX      A @SCM_LIB.SCM(SCH_1):P3V3_AUX
   2 SMB_BMC_MM2_SDA      B @SCM_LIB.SCM(SCH_1):SMB_BMC_MM2_SDA

Q_RES_0402LF-2.2K,5%,1/16W,CHIA  I145  R246
   1 P3V3_AUX      A @SCM_LIB.SCM(SCH_1):P3V3_AUX
   2 SMB_BMC_MM2_SCL      B @SCM_LIB.SCM(SCH_1):SMB_BMC_MM2_SCL

Q_RES_0402LF-1.8K,1%,1/16W,CHIA  I146  R245
   1 P3V3_AUX      A @SCM_LIB.SCM(SCH_1):P3V3_AUX
   2 SMB_BMC_MM1_SDA      B @SCM_LIB.SCM(SCH_1):SMB_BMC_MM1_SDA

Q_RES_0402LF-1.8K,1%,1/16W,CHIA  I147  R244
   1 P3V3_AUX      A @SCM_LIB.SCM(SCH_1):P3V3_AUX
   2 SMB_BMC_MM1_SCL      B @SCM_LIB.SCM(SCH_1):SMB_BMC_MM1_SCL

Q_RES_0402LF-4.7K,1%,1/16W,EMPA  I163  R699
   1 P3V3_AUX      A @SCM_LIB.SCM(SCH_1):P3V3_AUX
   2 SPI_BMC_BOOT_CLK      B @SCM_LIB.SCM(SCH_1):SPI_BMC_BOOT_CLK

Q_RES_0402LF-2K,1%,1/16W,CHIP,A  I165  R714
   1 LPC_ESPI_SEL      A @SCM_LIB.SCM(SCH_1):LPC_ESPI_SEL
   2 LPC_ESPI_SEL_R1      B @SCM_LIB.SCM(SCH_1):LPC_ESPI_SEL_R1

Q_CAP_0402-1UF,16V,10%,EMPTY,TA  I166  C267
   1 LPC_ESPI_SEL_R1      A @SCM_LIB.SCM(SCH_1):LPC_ESPI_SEL_R1
   2    GND      B @SCM_LIB.SCM(SCH_1):GND

Q_RES_0402LF-4.7K,1%,1/16W,CHIA  I168  R842
   1 P3V3_AUX      A @SCM_LIB.SCM(SCH_1):P3V3_AUX
   2 SMB_BMC_ALERT9_N      B @SCM_LIB.SCM(SCH_1):SMB_BMC_ALERT9_N

Q_RES_0402LF-4.7K,1%,1/16W,CHIA  I177  R843
   1 P3V3_AUX      A @SCM_LIB.SCM(SCH_1):P3V3_AUX
   2 SMB_BMC_ALERT10_N      B @SCM_LIB.SCM(SCH_1):SMB_BMC_ALERT10_N

Q_RES_0402LF-4.7K,1%,1/16W,CHIA  I179  R844
   1 P3V3_AUX      A @SCM_LIB.SCM(SCH_1):P3V3_AUX
   2 SMB_BMC_ALERT12_N      B @SCM_LIB.SCM(SCH_1):SMB_BMC_ALERT12_N

Q_RES_0402LF-4.7K,1%,1/16W,EMPA  I181  R846
   1 P3V3_AUX      A @SCM_LIB.SCM(SCH_1):P3V3_AUX
   2 FM_BMC_EN_DET_R      B @SCM_LIB.SCM(SCH_1):FM_BMC_EN_DET_R

Q_RES_0402LF-4.7K,1%,1/16W,CHIA  I182  R848
   1 P3V3_AUX      A @SCM_LIB.SCM(SCH_1):P3V3_AUX
   2 SMB_BMC_ALERT16_N      B @SCM_LIB.SCM(SCH_1):SMB_BMC_ALERT16_N

Q_RES_0402LF-4.7K,1%,1/16W,CHIA  I184  R851
   1 P3V3_AUX      A @SCM_LIB.SCM(SCH_1):P3V3_AUX
   2 SMB_BMC_ALERT15_N      B @SCM_LIB.SCM(SCH_1):SMB_BMC_ALERT15_N

BAT54C-BAT54C,SMLF,IC,BCBAT54CA  I185  U11
   2 UART_BMC_5_TXD_R      A @SCM_LIB.SCM(SCH_1):UART_BMC_5_TXD_R
   1 FM_BMC_ONCTL_R_N      B @SCM_LIB.SCM(SCH_1):FM_BMC_ONCTL_R_N
   3 FM_BMC_DISABLE      C @SCM_LIB.SCM(SCH_1):FM_BMC_DISABLE

Q_RES_0402LF-4.7K,1%,1/16W,CHIA  I188  R430
   1 P3V3_AUX      A @SCM_LIB.SCM(SCH_1):P3V3_AUX
   2 FM_BMC_ONCTL_R_N      B @SCM_LIB.SCM(SCH_1):FM_BMC_ONCTL_R_N

Q_RES_0402LF-4.7K,1%,1/16W,EMPA  I213  R754
   1 P3V3_RGM      A @SCM_LIB.SCM(SCH_1):P3V3_RGM
   2 UART_BMC_5_TXD_R      B @SCM_LIB.SCM(SCH_1):UART_BMC_5_TXD_R

Q_RES_0402LF-4.7K,1%,1/16W,EMPA  I217  R770
   1    GND      A @SCM_LIB.SCM(SCH_1):GND
   2 UART_BMC_5_TXD_R      B @SCM_LIB.SCM(SCH_1):UART_BMC_5_TXD_R

Q_RES_0402LF-4.7K,1%,1/16W,CHIA  I222  R42
   1 P3V3_AUX      A @SCM_LIB.SCM(SCH_1):P3V3_AUX
   2   Q7_D      B @SCM_LIB.SCM(SCH_1):Q7_D

Q_RES_0402LF-4.7K,1%,1/16W,EMPA  I228  R140
   1 P3V3_AUX      A @SCM_LIB.SCM(SCH_1):P3V3_AUX
   2 SPI_BMC_BOOT_MOSI      B @SCM_LIB.SCM(SCH_1):SPI_BMC_BOOT_MOSI

Q_RES_0402LF-4.7K,1%,1/16W,EMPA  I233  R753
   1 P3V3_AUX      A @SCM_LIB.SCM(SCH_1):P3V3_AUX
   2 SPI_BMC_BOOT_MISO      B @SCM_LIB.SCM(SCH_1):SPI_BMC_BOOT_MISO

Q_RES_0402LF-10K,1%,1/16W,CHIPA  I234  R521
   1 P3V3_AUX      A @SCM_LIB.SCM(SCH_1):P3V3_AUX
   2 SMB_BMC_MM10_SDA      B @SCM_LIB.SCM(SCH_1):SMB_BMC_MM10_SDA

Q_RES_0402LF-10K,1%,1/16W,CHIPA  I235  R145
   1 P3V3_AUX      A @SCM_LIB.SCM(SCH_1):P3V3_AUX
   2 SMB_BMC_MM12_SCL      B @SCM_LIB.SCM(SCH_1):SMB_BMC_MM12_SCL

Q_RES_0402LF-10K,1%,1/16W,CHIPA  I236  R149
   1 P3V3_AUX      A @SCM_LIB.SCM(SCH_1):P3V3_AUX
   2 SMB_BMC_MM12_SDA      B @SCM_LIB.SCM(SCH_1):SMB_BMC_MM12_SDA

Q_RES_0402LF-2.2K,5%,1/16W,CHIA  I237  R610
   1 P3V3_AUX      A @SCM_LIB.SCM(SCH_1):P3V3_AUX
   2 SMB_BMC_MM15_SCL      B @SCM_LIB.SCM(SCH_1):SMB_BMC_MM15_SCL

Q_RES_0402LF-2.2K,5%,1/16W,CHIA  I238  R692
   1 P3V3_AUX      A @SCM_LIB.SCM(SCH_1):P3V3_AUX
   2 SMB_BMC_MM15_SDA      B @SCM_LIB.SCM(SCH_1):SMB_BMC_MM15_SDA

Q_RES_0402LF-2.2K,5%,1/16W,CHIA  I239  R422
   1 P3V3_AUX      A @SCM_LIB.SCM(SCH_1):P3V3_AUX
   2 SMB_BMC_MM13_SCL      B @SCM_LIB.SCM(SCH_1):SMB_BMC_MM13_SCL

Q_RES_0402LF-2.2K,5%,1/16W,CHIA  I240  R428
   1 P3V3_AUX      A @SCM_LIB.SCM(SCH_1):P3V3_AUX
   2 SMB_BMC_MM13_SDA      B @SCM_LIB.SCM(SCH_1):SMB_BMC_MM13_SDA

Q_RES_0402LF-2.2K,5%,1/16W,CHIA  I241  R429
   1 P3V3_AUX      A @SCM_LIB.SCM(SCH_1):P3V3_AUX
   2 SMB_BMC_MM14_SCL      B @SCM_LIB.SCM(SCH_1):SMB_BMC_MM14_SCL

Q_RES_0402LF-2.2K,5%,1/16W,CHIA  I242  R438
   1 P3V3_AUX      A @SCM_LIB.SCM(SCH_1):P3V3_AUX
   2 SMB_BMC_MM14_SDA      B @SCM_LIB.SCM(SCH_1):SMB_BMC_MM14_SDA

2N7002A7-2N7002A-7,SMLF,IC,BAMA  I243  Q7
   G LPC_ESPI_SEL_R1      G @SCM_LIB.SCM(SCH_1):LPC_ESPI_SEL_R1
   D   Q7_D      D @SCM_LIB.SCM(SCH_1):Q7_D
   S SPI_BMC_TPM_MOSI      S @SCM_LIB.SCM(SCH_1):SPI_BMC_TPM_MOSI

Q_RES_0402LF-100,1%,1/16W,EMPTA  I244  R164
   1 SPI_BMC_BOOT_MISO      A @SCM_LIB.SCM(SCH_1):SPI_BMC_BOOT_MISO
   2    GND      B @SCM_LIB.SCM(SCH_1):GND

Q_RES_0402LF-4.7K,1%,1/16W,CHIA  I246  R94
   1 SPI_BMC_BOOT_MOSI      A @SCM_LIB.SCM(SCH_1):SPI_BMC_BOOT_MOSI
   2    GND      B @SCM_LIB.SCM(SCH_1):GND

Q_RES_0402LF-499,1%,1/16W,CHIPA  I247  R251
   1 P3V3_AUX      A @SCM_LIB.SCM(SCH_1):P3V3_AUX
   2 SMB_BMC_MM4_SDA      B @SCM_LIB.SCM(SCH_1):SMB_BMC_MM4_SDA


DRAWING: @SCM_LIB.SCM(SCH_1):PAGE28 

Q_CAP_0402-470PF,50V,10%,X7R,TA  I35  C172
   1 P5V_AUX      A @SCM_LIB.SCM(SCH_1):P5V_AUX
   2    GND      B @SCM_LIB.SCM(SCH_1):GND

Q_CAP_C0805-22UF,10V,20%,X6S,CA  I38  C171
   1 P5V_AUX      A @SCM_LIB.SCM(SCH_1):P5V_AUX
   2    GND      B @SCM_LIB.SCM(SCH_1):GND

Q_RES_0402LF-10K,1%,1/16W,CHIPA  I42  R383
   1 P3V3_AUX      A @SCM_LIB.SCM(SCH_1):P3V3_AUX
   2 USB_OC0_REAR_N      B @SCM_LIB.SCM(SCH_1):USB_OC0_REAR_N

Q_RES_0402LF-20K,1%,1/16W,CHIPA  I54  R378
   1 USB_OC0_ILIM      A @SCM_LIB.SCM(SCH_1):USB_OC0_ILIM
   2    GND      B @SCM_LIB.SCM(SCH_1):GND

Q_RES_0402LF-4.7K,1%,1/16W,CHIA  I62  R376
   1 P5V_AUX      A @SCM_LIB.SCM(SCH_1):P5V_AUX
   2 USB_OC0_EN      B @SCM_LIB.SCM(SCH_1):USB_OC0_EN

Q_RES_0402LF-10K,1%,1/16W,EMPTA  I63  R377
   1 USB_OC0_EN      A @SCM_LIB.SCM(SCH_1):USB_OC0_EN
   2    GND      B @SCM_LIB.SCM(SCH_1):GND

Q_RES_0402LF-4.7K,1%,1/16W,CHIA  I91  R299
   1 P3V3_AUX      A @SCM_LIB.SCM(SCH_1):P3V3_AUX
   2 SMB_DEBUG_AUX_LVC3_USB_R1_SDA      B @SCM_LIB.SCM(SCH_1):SMB_DEBUG_AUX_LVC3_USB_R1_SDA

Q_RES_0402LF-4.7K,1%,1/16W,CHIA  I96  R298
   1 P3V3_AUX      A @SCM_LIB.SCM(SCH_1):P3V3_AUX
   2 SMB_DEBUG_AUX_LVC3_USB_R1_SCL      B @SCM_LIB.SCM(SCH_1):SMB_DEBUG_AUX_LVC3_USB_R1_SCL

Q_CAP_0402-0.1UF,25V,10%,X7R,CA  I98  C159
   1 P3V3_AUX      A @SCM_LIB.SCM(SCH_1):P3V3_AUX
   2    GND      B @SCM_LIB.SCM(SCH_1):GND

PCA9517ADP_SMLF-PCA9517ADP,IC,A  I99  U37
   5 DEBUG_PORT_PRSNT_BUF_EN ENABLE @SCM_LIB.SCM(SCH_1):DEBUG_PORT_PRSNT_BUF_EN
   8 P3V3_AUX   VCCB @SCM_LIB.SCM(SCH_1):P3V3_AUX
   2 SMB_BMC_MM15_R1_SCL   SCLA @SCM_LIB.SCM(SCH_1):SMB_BMC_MM15_R1_SCL
   3 SMB_BMC_MM15_R1_SDA   SDAA @SCM_LIB.SCM(SCH_1):SMB_BMC_MM15_R1_SDA
   6 SMB_DEBUG_AUX_LVC3_USB_R1_SDA   SDAB @SCM_LIB.SCM(SCH_1):SMB_DEBUG_AUX_LVC3_USB_R1_SDA
   7 SMB_DEBUG_AUX_LVC3_USB_R1_SCL   SCLB @SCM_LIB.SCM(SCH_1):SMB_DEBUG_AUX_LVC3_USB_R1_SCL
   1 P3V3_AUX   VCCA @SCM_LIB.SCM(SCH_1):P3V3_AUX
   4    GND    GND @SCM_LIB.SCM(SCH_1):GND

Q_CAP_0402-0.1UF,25V,10%,X7R,CA  I101  C158
   1 P3V3_AUX      A @SCM_LIB.SCM(SCH_1):P3V3_AUX
   2    GND      B @SCM_LIB.SCM(SCH_1):GND

Q_RES_0402LF-0,5%,1/16W,CHIP,CA  I104  R670
   1 DEBUG_PORT_PRSNT_BUF_R_EN      A @SCM_LIB.SCM(SCH_1):DEBUG_PORT_PRSNT_BUF_R_EN
   2 DEBUG_PORT_PRSNT_BUF_EN      B @SCM_LIB.SCM(SCH_1):DEBUG_PORT_PRSNT_BUF_EN

Q_RES_0402LF-100K,1%,1/16W,EMPA  I105  R296
   1 DEBUG_PORT_PRSNT_BUF_R_EN      A @SCM_LIB.SCM(SCH_1):DEBUG_PORT_PRSNT_BUF_R_EN
   2    GND      B @SCM_LIB.SCM(SCH_1):GND

Q_RES_0402LF-0,5%,1/16W,CHIP,CA  I108  R294
   1 SMB_BMC_MM15_SDA      A @SCM_LIB.SCM(SCH_1):SMB_BMC_MM15_SDA
   2 SMB_BMC_MM15_R1_SDA      B @SCM_LIB.SCM(SCH_1):SMB_BMC_MM15_R1_SDA

Q_RES_0402LF-0,5%,1/16W,CHIP,CA  I109  R135
   1 SMB_BMC_MM15_SCL      A @SCM_LIB.SCM(SCH_1):SMB_BMC_MM15_SCL
   2 SMB_BMC_MM15_R1_SCL      B @SCM_LIB.SCM(SCH_1):SMB_BMC_MM15_R1_SCL

Q_RES_0402LF-10K,1%,1/16W,CHIPA  I113  R295
   1 P3V3_AUX      A @SCM_LIB.SCM(SCH_1):P3V3_AUX
   2 DEBUG_PORT_PRSNT_BUF_R_EN      B @SCM_LIB.SCM(SCH_1):DEBUG_PORT_PRSNT_BUF_R_EN

Q_RES_0402LF-0,5%,1/16W,CHIP,CA  I125  R701
   1 PWRGD_SYS_PWROK      A @SCM_LIB.SCM(SCH_1):PWRGD_SYS_PWROK
   2 PWRGD_SYS_PWROK_R1      B @SCM_LIB.SCM(SCH_1):PWRGD_SYS_PWROK_R1

Q_RES_0402LF-0,5%,1/16W,CHIP,CA  I126  R702
   1 RST_PLTRST_N      A @SCM_LIB.SCM(SCH_1):RST_PLTRST_N
   2 RST_PLTRST_R2_N      B @SCM_LIB.SCM(SCH_1):RST_PLTRST_R2_N

Q_RES_0402LF-0,5%,1/16W,CHIP,CA  I127  R703
   1 PWRGD_DSW_PWROK      A @SCM_LIB.SCM(SCH_1):PWRGD_DSW_PWROK
   2 PWRGD_DSW_PWROK_R3      B @SCM_LIB.SCM(SCH_1):PWRGD_DSW_PWROK_R3

Q_RES_0402LF-0,5%,1/16W,EMPTY,A  I128  R719
   1 PWRGD_PSU_AC_PWROK      A @SCM_LIB.SCM(SCH_1):PWRGD_PSU_AC_PWROK
   2 PWRGD_DSW_PWROK_R3      B @SCM_LIB.SCM(SCH_1):PWRGD_DSW_PWROK_R3

PCA9555PW_SMLF-PCA9555PW,IC,TMA  I141  U40
   1 LED_POSTCODE_INT   INT* @SCM_LIB.SCM(SCH_1):LED_POSTCODE_INT
  23 SMB_DEBUG_AUX_LVC3_USB_R3_SDA    SDA @SCM_LIB.SCM(SCH_1):SMB_DEBUG_AUX_LVC3_USB_R3_SDA
  22 SMB_DEBUG_AUX_LVC3_USB_R3_SCL    SCL @SCM_LIB.SCM(SCH_1):SMB_DEBUG_AUX_LVC3_USB_R3_SCL
   4 LED_POSTCODE_0_R1    P00 @SCM_LIB.SCM(SCH_1):LED_POSTCODE_0_R1
   5 LED_POSTCODE_1_R1    P01 @SCM_LIB.SCM(SCH_1):LED_POSTCODE_1_R1
   6 LED_POSTCODE_2_R1    P02 @SCM_LIB.SCM(SCH_1):LED_POSTCODE_2_R1
   7 LED_POSTCODE_3_R1    P03 @SCM_LIB.SCM(SCH_1):LED_POSTCODE_3_R1
   8 LED_POSTCODE_4_R1    P04 @SCM_LIB.SCM(SCH_1):LED_POSTCODE_4_R1
   9 LED_POSTCODE_5_R1    P05 @SCM_LIB.SCM(SCH_1):LED_POSTCODE_5_R1
  10 LED_POSTCODE_6_R1    P06 @SCM_LIB.SCM(SCH_1):LED_POSTCODE_6_R1
  11 LED_POSTCODE_7_R1    P07 @SCM_LIB.SCM(SCH_1):LED_POSTCODE_7_R1
  13 FM_DEBUG_RST_BTN_N    P10 @SCM_LIB.SCM(SCH_1):FM_DEBUG_RST_BTN_N
  14 FM_DEBUG_PWR_BTN_N    P11 @SCM_LIB.SCM(SCH_1):FM_DEBUG_PWR_BTN_N
  15 PWRGD_SYS_PWROK_R1    P12 @SCM_LIB.SCM(SCH_1):PWRGD_SYS_PWROK_R1
  16 RST_PLTRST_R2_N    P13 @SCM_LIB.SCM(SCH_1):RST_PLTRST_R2_N
  17 PWRGD_DSW_PWROK_R3    P14 @SCM_LIB.SCM(SCH_1):PWRGD_DSW_PWROK_R3
  18 FM_CPU_MSMI_CATERR_LVT3_R3_N    P15 @SCM_LIB.SCM(SCH_1):FM_CPU_MSMI_CATERR_LVT3_R3_N
  19 FM_SLPS3_GF_R2_N    P16 @SCM_LIB.SCM(SCH_1):FM_SLPS3_GF_R2_N
  20 FM_UART_SWITCH_N    P17 @SCM_LIB.SCM(SCH_1):FM_UART_SWITCH_N
  21 LED_POSTCODE_A0     A0 @SCM_LIB.SCM(SCH_1):LED_POSTCODE_A0
   2 LED_POSTCODE_A1     A1 @SCM_LIB.SCM(SCH_1):LED_POSTCODE_A1
   3 LED_POSTCODE_A2     A2 @SCM_LIB.SCM(SCH_1):LED_POSTCODE_A2
  24 P3V3_AUX    VDD @SCM_LIB.SCM(SCH_1):P3V3_AUX
  12    GND    VSS @SCM_LIB.SCM(SCH_1):GND

Q_RES_0402LF-0,5%,1/16W,CHIP,CA  I144  R720
   1 FM_CPU_MSMI_CATERR_LVT3_N      A @SCM_LIB.SCM(SCH_1):FM_CPU_MSMI_CATERR_LVT3_N
   2 FM_CPU_MSMI_CATERR_LVT3_R3_N      B @SCM_LIB.SCM(SCH_1):FM_CPU_MSMI_CATERR_LVT3_R3_N

Q_RES_0402LF-0,5%,1/16W,CHIP,CA  I145  R721
   1 FM_SLPS3_GF_N      A @SCM_LIB.SCM(SCH_1):FM_SLPS3_GF_N
   2 FM_SLPS3_GF_R2_N      B @SCM_LIB.SCM(SCH_1):FM_SLPS3_GF_R2_N

Q_CAP_0402-0.1UF,25V,10%,X7R,CA  I146  C300
   1 P3V3_AUX      A @SCM_LIB.SCM(SCH_1):P3V3_AUX
   2    GND      B @SCM_LIB.SCM(SCH_1):GND

Q_RES_0402LF-4.7K,1%,1/16W,CHIA  I147  R667
   1 P3V3_AUX      A @SCM_LIB.SCM(SCH_1):P3V3_AUX
   2 LED_POSTCODE_INT      B @SCM_LIB.SCM(SCH_1):LED_POSTCODE_INT

Q_RES_0402LF-0,5%,1/16W,CHIP,CA  I152  R95
   1 SMB_DEBUG_AUX_LVC3_USB_SDA      A @SCM_LIB.SCM(SCH_1):SMB_DEBUG_AUX_LVC3_USB_SDA
   2 SMB_DEBUG_AUX_LVC3_USB_R3_SDA      B @SCM_LIB.SCM(SCH_1):SMB_DEBUG_AUX_LVC3_USB_R3_SDA

Q_RES_0402LF-0,5%,1/16W,CHIP,CA  I153  R632
   1 SMB_DEBUG_AUX_LVC3_USB_SCL      A @SCM_LIB.SCM(SCH_1):SMB_DEBUG_AUX_LVC3_USB_SCL
   2 SMB_DEBUG_AUX_LVC3_USB_R3_SCL      B @SCM_LIB.SCM(SCH_1):SMB_DEBUG_AUX_LVC3_USB_R3_SCL

Q_RES_0402LF-0,5%,1/16W,CHIP,CA  I161  R626
   1 FM_SOL_UART_CH_SEL      A @SCM_LIB.SCM(SCH_1):FM_SOL_UART_CH_SEL
   2 FM_SOL_UART_CH_SEL_R3      B @SCM_LIB.SCM(SCH_1):FM_SOL_UART_CH_SEL_R3

Q_RES_0402LF-1K,1%,1/16W,CHIP,A  I162  R736
   1 P3V3_AUX      A @SCM_LIB.SCM(SCH_1):P3V3_AUX
   2 FM_SOL_UART_CH_SEL_R3      B @SCM_LIB.SCM(SCH_1):FM_SOL_UART_CH_SEL_R3

2N7002A7-2N7002A-7,SMLF,IC,BAMA  I163  Q8
   G FM_UART_SEL_N      G @SCM_LIB.SCM(SCH_1):FM_UART_SEL_N
   D FM_SOL_UART_CH_SEL_R3      D @SCM_LIB.SCM(SCH_1):FM_SOL_UART_CH_SEL_R3
   S    GND      S @SCM_LIB.SCM(SCH_1):GND

Q_RES_0402LF-0,5%,1/16W,CHIP,CA  I164  R83
   1 FM_UART_SEL_N      A @SCM_LIB.SCM(SCH_1):FM_UART_SEL_N
   2 FM_UART_SWITCH_N      B @SCM_LIB.SCM(SCH_1):FM_UART_SWITCH_N

Q_RES_0402LF-1K,1%,1/16W,CHIP,A  I166  R735
   1 P3V3_AUX      A @SCM_LIB.SCM(SCH_1):P3V3_AUX
   2 FM_UART_SWITCH_N      B @SCM_LIB.SCM(SCH_1):FM_UART_SWITCH_N

Q_RES_0402LF-4.7K,1%,1/16W,CHIA  I168  R740
   1 P3V3_AUX      A @SCM_LIB.SCM(SCH_1):P3V3_AUX
   2 LED_POSTCODE_A2      B @SCM_LIB.SCM(SCH_1):LED_POSTCODE_A2

Q_RES_0402LF-4.7K,1%,1/16W,CHIA  I169  R739
   1 P3V3_AUX      A @SCM_LIB.SCM(SCH_1):P3V3_AUX
   2 LED_POSTCODE_A1      B @SCM_LIB.SCM(SCH_1):LED_POSTCODE_A1

Q_RES_0402LF-4.7K,1%,1/16W,CHIA  I171  R738
   1 P3V3_AUX      A @SCM_LIB.SCM(SCH_1):P3V3_AUX
   2 LED_POSTCODE_A0      B @SCM_LIB.SCM(SCH_1):LED_POSTCODE_A0

Q_RES_0402LF-100,1%,1/16W,EMPTA  I172  R745
   1 LED_POSTCODE_A2      A @SCM_LIB.SCM(SCH_1):LED_POSTCODE_A2
   2    GND      B @SCM_LIB.SCM(SCH_1):GND

Q_RES_0402LF-100,1%,1/16W,EMPTA  I173  R744
   1 LED_POSTCODE_A1      A @SCM_LIB.SCM(SCH_1):LED_POSTCODE_A1
   2    GND      B @SCM_LIB.SCM(SCH_1):GND

Q_RES_0402LF-100,1%,1/16W,EMPTA  I175  R743
   1 LED_POSTCODE_A0      A @SCM_LIB.SCM(SCH_1):LED_POSTCODE_A0
   2    GND      B @SCM_LIB.SCM(SCH_1):GND

NCP380HSNAJAAT1G-NCP380HSNAJAAA  I179  U10
   4 USB_OC0_REAR_N FLAG_N @SCM_LIB.SCM(SCH_1):USB_OC0_REAR_N
   1 P5V_AUX     IN @SCM_LIB.SCM(SCH_1):P5V_AUX
   5 USB_OC0_ILIM   ILIM @SCM_LIB.SCM(SCH_1):USB_OC0_ILIM
   6 P5V_USB_REAR    OUT @SCM_LIB.SCM(SCH_1):P5V_USB_REAR
   3 USB_OC0_EN     EN @SCM_LIB.SCM(SCH_1):USB_OC0_EN
   2    GND    GND @SCM_LIB.SCM(SCH_1):GND

74LVC1G07W57-74LVC1G07W5-7,SMLA  I180  U23
   5 P3V3_AUX    VCC @SCM_LIB.SCM(SCH_1):P3V3_AUX
   2 DEBUG_PORT_PRSNT      A @SCM_LIB.SCM(SCH_1):DEBUG_PORT_PRSNT
   3    GND    GND @SCM_LIB.SCM(SCH_1):GND
   4 DEBUG_PORT_PRSNT_BUF_R_EN      Y @SCM_LIB.SCM(SCH_1):DEBUG_PORT_PRSNT_BUF_R_EN
   1     NC    NC1     NC

Q_CAP_0402-0.1UF,25V,10%,X7R,CA  I181  C157
   1 P3V3_AUX      A @SCM_LIB.SCM(SCH_1):P3V3_AUX
   2    GND      B @SCM_LIB.SCM(SCH_1):GND

Q_RES_0402LF-33.2,1%,1/16W,CHIA  I183  R300
   1 SMB_DEBUG_AUX_LVC3_USB_R1_SCL      A @SCM_LIB.SCM(SCH_1):SMB_DEBUG_AUX_LVC3_USB_R1_SCL
   2 SMB_DEBUG_AUX_LVC3_USB_SCL      B @SCM_LIB.SCM(SCH_1):SMB_DEBUG_AUX_LVC3_USB_SCL

Q_RES_0402LF-33.2,1%,1/16W,CHIA  I184  R302
   1 SMB_DEBUG_AUX_LVC3_USB_R1_SDA      A @SCM_LIB.SCM(SCH_1):SMB_DEBUG_AUX_LVC3_USB_R1_SDA
   2 SMB_DEBUG_AUX_LVC3_USB_SDA      B @SCM_LIB.SCM(SCH_1):SMB_DEBUG_AUX_LVC3_USB_SDA

Q_RES_0402LF-100,1%,1/16W,CHIPA  I185  R384
   1 USB_OC0_REAR_N      A @SCM_LIB.SCM(SCH_1):USB_OC0_REAR_N
   2 USB_OC0_REAR_R_N      B @SCM_LIB.SCM(SCH_1):USB_OC0_REAR_R_N


DRAWING: @SCM_LIB.SCM(SCH_1):PAGE29 

Q_RES_0402LF-0,5%,1/16W,CHIP,CA  I96  R385
   1 USB_FPNL_DN      A @SCM_LIB.SCM(SCH_1):USB_FPNL_DN
   2 USB2_01_F_DN      B @SCM_LIB.SCM(SCH_1):USB2_01_F_DN

PRTR5V0U2X-PRTR5V0U2X,SMLF,IC,A  I99  U38
   2 USB2_01_F_DP    IO1 @SCM_LIB.SCM(SCH_1):USB2_01_F_DP
   1    GND    GND @SCM_LIB.SCM(SCH_1):GND
   4 P5V_USB_REAR    VCC @SCM_LIB.SCM(SCH_1):P5V_USB_REAR
   3 USB2_01_F_DN    IO2 @SCM_LIB.SCM(SCH_1):USB2_01_F_DN

Q_RES_0402LF-0,5%,1/16W,CHIP,CA  I101  R386
   1 USB_FPNL_DP      A @SCM_LIB.SCM(SCH_1):USB_FPNL_DP
   2 USB2_01_F_DP      B @SCM_LIB.SCM(SCH_1):USB2_01_F_DP

Q_INDUCTOR4P_12-67/320MA,320MAA  I102  L23
   4 USB_FPNL_DN      4 @SCM_LIB.SCM(SCH_1):USB_FPNL_DN
   3 USB2_01_F_DN      3 @SCM_LIB.SCM(SCH_1):USB2_01_F_DN
   2 USB2_01_F_DP      2 @SCM_LIB.SCM(SCH_1):USB2_01_F_DP
   1 USB_FPNL_DP      1 @SCM_LIB.SCM(SCH_1):USB_FPNL_DP

Q_RES_0402LF-0,5%,1/16W,CHIP,CA  I109  R675
   1 USB3_01_MUX_FB_RXP      A @SCM_LIB.SCM(SCH_1):USB3_01_MUX_FB_RXP
   2 USB3_01_FB_RXP      B @SCM_LIB.SCM(SCH_1):USB3_01_FB_RXP

Q_RES_0402LF-0,5%,1/16W,CHIP,CA  I111  R668
   1 USB3_01_MUX_FB_RXN      A @SCM_LIB.SCM(SCH_1):USB3_01_MUX_FB_RXN
   2 USB3_01_FB_RXN      B @SCM_LIB.SCM(SCH_1):USB3_01_FB_RXN

Q_INDUCTOR4P_12-67/320MA,320MAA  I113  L22
   4 USB3_01_MUX_FB_RXN      4 @SCM_LIB.SCM(SCH_1):USB3_01_MUX_FB_RXN
   3 USB3_01_FB_RXN      3 @SCM_LIB.SCM(SCH_1):USB3_01_FB_RXN
   2 USB3_01_FB_RXP      2 @SCM_LIB.SCM(SCH_1):USB3_01_FB_RXP
   1 USB3_01_MUX_FB_RXP      1 @SCM_LIB.SCM(SCH_1):USB3_01_MUX_FB_RXP

Q_RES_0402LF-0,5%,1/16W,CHIP,CA  I122  R673
   1 USB3_01_MUX_FB_TXP      A @SCM_LIB.SCM(SCH_1):USB3_01_MUX_FB_TXP
   2 USB3_01_FB_TXP      B @SCM_LIB.SCM(SCH_1):USB3_01_FB_TXP

Q_INDUCTOR4P_12-67/320MA,320MAA  I123  L21
   4 USB3_01_MUX_FB_TXN      4 @SCM_LIB.SCM(SCH_1):USB3_01_MUX_FB_TXN
   3 USB3_01_FB_TXN      3 @SCM_LIB.SCM(SCH_1):USB3_01_FB_TXN
   2 USB3_01_FB_TXP      2 @SCM_LIB.SCM(SCH_1):USB3_01_FB_TXP
   1 USB3_01_MUX_FB_TXP      1 @SCM_LIB.SCM(SCH_1):USB3_01_MUX_FB_TXP

Q_RES_0402LF-0,5%,1/16W,CHIP,CA  I124  R666
   1 USB3_01_MUX_FB_TXN      A @SCM_LIB.SCM(SCH_1):USB3_01_MUX_FB_TXN
   2 USB3_01_FB_TXN      B @SCM_LIB.SCM(SCH_1):USB3_01_FB_TXN

Q_RES_0402LF-0,5%,1/16W,CHIP,CA  I135  R731
   1 SMB_DEBUG_AUX_LVC3_USB_SDA      A @SCM_LIB.SCM(SCH_1):SMB_DEBUG_AUX_LVC3_USB_SDA
   2 SMB_DEBUG_AUX_LVC3_USB_R2_SDA      B @SCM_LIB.SCM(SCH_1):SMB_DEBUG_AUX_LVC3_USB_R2_SDA

Q_RES_0402LF-0,5%,1/16W,CHIP,CA  I136  R732
   1 SMB_DEBUG_AUX_LVC3_USB_SCL      A @SCM_LIB.SCM(SCH_1):SMB_DEBUG_AUX_LVC3_USB_SCL
   2 SMB_DEBUG_AUX_LVC3_USB_R2_SCL      B @SCM_LIB.SCM(SCH_1):SMB_DEBUG_AUX_LVC3_USB_R2_SCL

Q_RES_0402LF-0,5%,1/16W,CHIP,CA  I141  R671
   1 USB3_01_TXP_C      A @SCM_LIB.SCM(SCH_1):USB3_01_TXP_C
   2 USB3_FPNL_TXP      B @SCM_LIB.SCM(SCH_1):USB3_FPNL_TXP

Q_CAP_0402-0.1UF,25V,10%,EMPTYA  I142  C238
   1 USB3_FPNL_TXP      A @SCM_LIB.SCM(SCH_1):USB3_FPNL_TXP
   2 USB3_01_TXP_C      B @SCM_LIB.SCM(SCH_1):USB3_01_TXP_C

Q_CAP_0402-0.1UF,25V,10%,EMPTYA  I143  C239
   1 USB3_FPNL_TXN      A @SCM_LIB.SCM(SCH_1):USB3_FPNL_TXN
   2 USB3_01_TXN_C      B @SCM_LIB.SCM(SCH_1):USB3_01_TXN_C

Q_RES_0402LF-0,5%,1/16W,CHIP,CA  I144  R672
   1 USB3_01_TXN_C      A @SCM_LIB.SCM(SCH_1):USB3_01_TXN_C
   2 USB3_FPNL_TXN      B @SCM_LIB.SCM(SCH_1):USB3_FPNL_TXN

Q_CAP_0402-0.1UF,25V,10%,X7R,CA  I146  C237
   1 P3V3_AUX      A @SCM_LIB.SCM(SCH_1):P3V3_AUX
   2    GND      B @SCM_LIB.SCM(SCH_1):GND

Q_CAP_0402-0.1UF,25V,10%,X7R,CA  I148  C236
   1 P3V3_AUX      A @SCM_LIB.SCM(SCH_1):P3V3_AUX
   2    GND      B @SCM_LIB.SCM(SCH_1):GND

Q_CAP_0402-0.1UF,25V,10%,X7R,CA  I150  C219
   1 P3V3_AUX      A @SCM_LIB.SCM(SCH_1):P3V3_AUX
   2    GND      B @SCM_LIB.SCM(SCH_1):GND

Q_RES_0402LF-10K,1%,1/16W,EMPTA  I153  R712
   1 P3V3_AUX      A @SCM_LIB.SCM(SCH_1):P3V3_AUX
   2 USB3_MUX_PD      B @SCM_LIB.SCM(SCH_1):USB3_MUX_PD

Q_RES_0402LF-100,1%,1/16W,CHIPA  I155  R694
   1 USB3_MUX_PD      A @SCM_LIB.SCM(SCH_1):USB3_MUX_PD
   2    GND      B @SCM_LIB.SCM(SCH_1):GND

Q_RES_0402LF-100K,1%,1/16W,EMPA  I157  R274
   1 P3V3_AUX      A @SCM_LIB.SCM(SCH_1):P3V3_AUX
   2 DEBUG_PORT_UART_RX      B @SCM_LIB.SCM(SCH_1):DEBUG_PORT_UART_RX

Q_CAP_0402-0.1UF,25V,10%,X7R,CA  I161  C149
   1 P3V3_AUX      A @SCM_LIB.SCM(SCH_1):P3V3_AUX
   2    GND      B @SCM_LIB.SCM(SCH_1):GND

74HC1G126GW-74HC1G126GW,SMLF,IA  I164  U36
   2 DEBUG_PORT_UART_RX      2 @SCM_LIB.SCM(SCH_1):DEBUG_PORT_UART_RX
   4 SPA_SIN_SW_DBG      4 @SCM_LIB.SCM(SCH_1):SPA_SIN_SW_DBG
   5 P3V3_AUX      5 @SCM_LIB.SCM(SCH_1):P3V3_AUX
   1 DEBUG_PORT_PRSNT      1 @SCM_LIB.SCM(SCH_1):DEBUG_PORT_PRSNT
   3    GND    GND @SCM_LIB.SCM(SCH_1):GND

Q_RES_0402LF-100K,1%,1/16W,CHIA  I166  R193
   1 P3V3_AUX      A @SCM_LIB.SCM(SCH_1):P3V3_AUX
   2 SPA_SIN_SW_DBG      B @SCM_LIB.SCM(SCH_1):SPA_SIN_SW_DBG

Q_RES_0402LF-100K,1%,1/16W,EMPA  I170  R219
   1 DEBUG_PORT_UART_TX      A @SCM_LIB.SCM(SCH_1):DEBUG_PORT_UART_TX
   2    GND      B @SCM_LIB.SCM(SCH_1):GND

Q_CAP_0402-0.1UF,25V,10%,X7R,CA  I172  C148
   1 P3V3_AUX      A @SCM_LIB.SCM(SCH_1):P3V3_AUX
   2    GND      B @SCM_LIB.SCM(SCH_1):GND

74HC1G126GW-74HC1G126GW,SMLF,IA  I174  U29
   2 SPA_SOUT_SW_DBG      2 @SCM_LIB.SCM(SCH_1):SPA_SOUT_SW_DBG
   4 DEBUG_PORT_UART_TX      4 @SCM_LIB.SCM(SCH_1):DEBUG_PORT_UART_TX
   5 P3V3_AUX      5 @SCM_LIB.SCM(SCH_1):P3V3_AUX
   1 DEBUG_PORT_PRSNT      1 @SCM_LIB.SCM(SCH_1):DEBUG_PORT_PRSNT
   3    GND    GND @SCM_LIB.SCM(SCH_1):GND

Q_RES_0402LF-20K,1%,1/16W,CHIPA  I184  R205
   1 DEBUG_PORT_PRSNT_R      A @SCM_LIB.SCM(SCH_1):DEBUG_PORT_PRSNT_R
   2    GND      B @SCM_LIB.SCM(SCH_1):GND

Q_CAP_0402-470PF,50V,10%,X7R,TA  I193  C179
   1 P5V_USB_REAR      A @SCM_LIB.SCM(SCH_1):P5V_USB_REAR
   2    GND      B @SCM_LIB.SCM(SCH_1):GND

Q_CAP_0402-470PF,50V,10%,X7R,TA  I194  C178
   1 P5V_USB_REAR      A @SCM_LIB.SCM(SCH_1):P5V_USB_REAR
   2    GND      B @SCM_LIB.SCM(SCH_1):GND

Q_RES_0402LF-0,5%,1/16W,CHIP,CA  I201  R707
   1 FM_DEBUG_PORT_R_PRSNT_N      A @SCM_LIB.SCM(SCH_1):FM_DEBUG_PORT_R_PRSNT_N
   2 FM_DEBUG_PORT_PRSNT_N      B @SCM_LIB.SCM(SCH_1):FM_DEBUG_PORT_PRSNT_N

2N7002A7-2N7002A-7,SMLF,IC,BAMA  I202  Q6
   G DEBUG_PORT_PRSNT      G @SCM_LIB.SCM(SCH_1):DEBUG_PORT_PRSNT
   D FM_DEBUG_PORT_R_PRSNT_N      D @SCM_LIB.SCM(SCH_1):FM_DEBUG_PORT_R_PRSNT_N
   S    GND      S @SCM_LIB.SCM(SCH_1):GND

Q_RES_0402LF-4.7K,1%,1/16W,CHIA  I204  R730
   1 P3V3_AUX      A @SCM_LIB.SCM(SCH_1):P3V3_AUX
   2 FM_DEBUG_PORT_R_PRSNT_N      B @SCM_LIB.SCM(SCH_1):FM_DEBUG_PORT_R_PRSNT_N

PI3PCIE3212ZBEX-PI3PCIE3212ZBEA  I206  U22
  10 P3V3_AUX   VDD2 @SCM_LIB.SCM(SCH_1):P3V3_AUX
   6 P3V3_AUX   VDD1 @SCM_LIB.SCM(SCH_1):P3V3_AUX
   1 P3V3_AUX   VDD0 @SCM_LIB.SCM(SCH_1):P3V3_AUX
   3 USB3_01_MUX_FB_TXP   A0_P @SCM_LIB.SCM(SCH_1):USB3_01_MUX_FB_TXP
   4 USB3_01_MUX_FB_TXN   A0_N @SCM_LIB.SCM(SCH_1):USB3_01_MUX_FB_TXN
   7 USB3_01_MUX_FB_RXP   A1_P @SCM_LIB.SCM(SCH_1):USB3_01_MUX_FB_RXP
   8 USB3_01_MUX_FB_RXN   A1_N @SCM_LIB.SCM(SCH_1):USB3_01_MUX_FB_RXN
   9 DEBUG_PORT_PRSNT    SEL @SCM_LIB.SCM(SCH_1):DEBUG_PORT_PRSNT
  19 USB3_01_TXP_C   B0_P @SCM_LIB.SCM(SCH_1):USB3_01_TXP_C
  18 USB3_01_TXN_C   B0_N @SCM_LIB.SCM(SCH_1):USB3_01_TXN_C
  17 USB3_FPNL_RXP   B1_P @SCM_LIB.SCM(SCH_1):USB3_FPNL_RXP
  16 USB3_FPNL_RXN   B1_N @SCM_LIB.SCM(SCH_1):USB3_FPNL_RXN
  15 DEBUG_PORT_UART_RX   C0_P @SCM_LIB.SCM(SCH_1):DEBUG_PORT_UART_RX
  14 DEBUG_PORT_UART_TX   C0_N @SCM_LIB.SCM(SCH_1):DEBUG_PORT_UART_TX
  13 SMB_DEBUG_AUX_LVC3_USB_R2_SDA   C1_P @SCM_LIB.SCM(SCH_1):SMB_DEBUG_AUX_LVC3_USB_R2_SDA
  12 SMB_DEBUG_AUX_LVC3_USB_R2_SCL   C1_N @SCM_LIB.SCM(SCH_1):SMB_DEBUG_AUX_LVC3_USB_R2_SCL
  TH     NC     TH     NC
  11    GND   GND2 @SCM_LIB.SCM(SCH_1):GND
   5    GND   GND1 @SCM_LIB.SCM(SCH_1):GND
  20    GND   GND0 @SCM_LIB.SCM(SCH_1):GND
   2 USB3_MUX_PD     PD @SCM_LIB.SCM(SCH_1):USB3_MUX_PD

DT1240E04LP7-DT1240E-04LP-7,SMA  I211  U27
   1 USB3_01_FB_TXP    IO1 @SCM_LIB.SCM(SCH_1):USB3_01_FB_TXP
   3    GND   VSS1 @SCM_LIB.SCM(SCH_1):GND
   4 USB3_01_FB_RXP    IO3 @SCM_LIB.SCM(SCH_1):USB3_01_FB_RXP
   6 USB3_01_FB_RXN    NC1 @SCM_LIB.SCM(SCH_1):USB3_01_FB_RXN
   8    GND   VSS2 @SCM_LIB.SCM(SCH_1):GND
   9 USB3_01_FB_TXN    NC3 @SCM_LIB.SCM(SCH_1):USB3_01_FB_TXN
  10 USB3_01_FB_TXP    NC4 @SCM_LIB.SCM(SCH_1):USB3_01_FB_TXP
   2 USB3_01_FB_TXN    IO2 @SCM_LIB.SCM(SCH_1):USB3_01_FB_TXN
   5 USB3_01_FB_RXN    IO4 @SCM_LIB.SCM(SCH_1):USB3_01_FB_RXN
   7 USB3_01_FB_RXP    NC2 @SCM_LIB.SCM(SCH_1):USB3_01_FB_RXP

Q_CAP_C1206-47UF,6.3V,20%,X6S,A  I219  C177
   1 P5V_USB_REAR      A @SCM_LIB.SCM(SCH_1):P5V_USB_REAR
   2    GND      B @SCM_LIB.SCM(SCH_1):GND

Q_CAP_C1206-47UF,6.3V,20%,X6S,A  I220  C327
   1 P5V_USB_REAR      A @SCM_LIB.SCM(SCH_1):P5V_USB_REAR
   2    GND      B @SCM_LIB.SCM(SCH_1):GND

CONN9_GSB3111315HR-CONN9_GSB31A  I221  J2
   1 P5V_USB_REAR   VBUS @SCM_LIB.SCM(SCH_1):P5V_USB_REAR
   4    GND    GND @SCM_LIB.SCM(SCH_1):GND
  G1    GND     G1 @SCM_LIB.SCM(SCH_1):GND
  G2    GND     G2 @SCM_LIB.SCM(SCH_1):GND
   9 USB3_01_FB_TXP  SSTX+ @SCM_LIB.SCM(SCH_1):USB3_01_FB_TXP
   8 USB3_01_FB_TXN  SSTX- @SCM_LIB.SCM(SCH_1):USB3_01_FB_TXN
   2 USB2_01_F_DN     D- @SCM_LIB.SCM(SCH_1):USB2_01_F_DN
   3 USB2_01_F_DP     D+ @SCM_LIB.SCM(SCH_1):USB2_01_F_DP
   6 USB3_01_FB_RXP  SSRX+ @SCM_LIB.SCM(SCH_1):USB3_01_FB_RXP
   7 DEBUG_PORT_PRSNT_R  GND_D @SCM_LIB.SCM(SCH_1):DEBUG_PORT_PRSNT_R
   5 USB3_01_FB_RXN  SSRX- @SCM_LIB.SCM(SCH_1):USB3_01_FB_RXN

Q_RES_0402LF-33.2,1%,1/16W,CHIA  I222  R693
   1 DEBUG_PORT_PRSNT      A @SCM_LIB.SCM(SCH_1):DEBUG_PORT_PRSNT
   2 DEBUG_PORT_PRSNT_R      B @SCM_LIB.SCM(SCH_1):DEBUG_PORT_PRSNT_R


DRAWING: @SCM_LIB.SCM(SCH_1):PAGE30 

Q_RES_0402LF-4.7K,1%,1/16W,CHIA  I146  R67
   1 P3V3_AUX      A @SCM_LIB.SCM(SCH_1):P3V3_AUX
   2 UART_BMC_5_TXD_BUF1_R      B @SCM_LIB.SCM(SCH_1):UART_BMC_5_TXD_BUF1_R

Q_RES_0402LF-33.2,1%,1/16W,CHIA  I147  R104
   1 UART_BMC_5_RXD_BUF_R      A @SCM_LIB.SCM(SCH_1):UART_BMC_5_RXD_BUF_R
   2 UART_BMC_5_RXD_BUF1      B @SCM_LIB.SCM(SCH_1):UART_BMC_5_RXD_BUF1

Q_RES_0402LF-33.2,1%,1/16W,CHIA  I148  R102
   1 UART_BMC_5_TXD_BUF      A @SCM_LIB.SCM(SCH_1):UART_BMC_5_TXD_BUF
   2 UART_BMC_5_TXD_BUF_R      B @SCM_LIB.SCM(SCH_1):UART_BMC_5_TXD_BUF_R

Q_CAP_0402-0.1UF,25V,10%,X7R,CA  I151  C175
   1 P3V3_AUX      A @SCM_LIB.SCM(SCH_1):P3V3_AUX
   2    GND      B @SCM_LIB.SCM(SCH_1):GND

SCONN3_21291035BR2-SCONN3_212-A  I184  J6
   3 UART_BMC_5_RXD_BUF      3 @SCM_LIB.SCM(SCH_1):UART_BMC_5_RXD_BUF
   2    GND      2 @SCM_LIB.SCM(SCH_1):GND
   1 UART_BMC_5_TXD_BUF_R      1 @SCM_LIB.SCM(SCH_1):UART_BMC_5_TXD_BUF_R

Q_RES_0402LF-4.7K,1%,1/16W,EMPA  I192  R737
   1 P3V3_AUX      A @SCM_LIB.SCM(SCH_1):P3V3_AUX
   2 SPA_SIN_SW_BUF      B @SCM_LIB.SCM(SCH_1):SPA_SIN_SW_BUF

Q_RES_0402LF-4.7K,1%,1/16W,EMPA  I195  R742
   1 P3V3_AUX      A @SCM_LIB.SCM(SCH_1):P3V3_AUX
   2 SPA_SOUT_SW_BUF      B @SCM_LIB.SCM(SCH_1):SPA_SOUT_SW_BUF

Q_RES_0402LF-4.7K,1%,1/16W,CHIA  I197  R741
   1 P3V3_AUX      A @SCM_LIB.SCM(SCH_1):P3V3_AUX
   2 UART_BMC_5_RXD_BUF      B @SCM_LIB.SCM(SCH_1):UART_BMC_5_RXD_BUF

Q_RES_0402LF-4.7K,1%,1/16W,CHIA  I221  R758
   1 P3V3_RGM      A @SCM_LIB.SCM(SCH_1):P3V3_RGM
   2 UART_BMC_5_RXD_R      B @SCM_LIB.SCM(SCH_1):UART_BMC_5_RXD_R

Q_RES_0402LF-33.2,1%,1/16W,CHIA  I225  R715
   1 UART_BMC_5_TXD_BUF1      A @SCM_LIB.SCM(SCH_1):UART_BMC_5_TXD_BUF1
   2 UART_BMC_5_TXD_BUF1_R      B @SCM_LIB.SCM(SCH_1):UART_BMC_5_TXD_BUF1_R

Q_RES_0402LF-33.2,1%,1/16W,CHIA  I226  R757
   1 UART_BMC_5_RXD_BUF1_R      A @SCM_LIB.SCM(SCH_1):UART_BMC_5_RXD_BUF1_R
   2 UART_BMC_5_RXD_R      B @SCM_LIB.SCM(SCH_1):UART_BMC_5_RXD_R

Q_CAP_0402-0.1UF,25V,10%,X7R,CA  I229  C268
   1 P3V3_AUX      A @SCM_LIB.SCM(SCH_1):P3V3_AUX
   2    GND      B @SCM_LIB.SCM(SCH_1):GND

Q_RES_0402LF-4.7K,1%,1/16W,CHIA  I231  R72
   1 P3V3_AUX      A @SCM_LIB.SCM(SCH_1):P3V3_AUX
   2 UART_BMC_5_RXD_BUF1      B @SCM_LIB.SCM(SCH_1):UART_BMC_5_RXD_BUF1

Q_RES_0402LF-33.2,1%,1/16W,CHIA  I237  R766
   1 UART_BMC_5_RXD_BUF1      A @SCM_LIB.SCM(SCH_1):UART_BMC_5_RXD_BUF1
   2 UART_BMC_5_RXD_BUF1_SW      B @SCM_LIB.SCM(SCH_1):UART_BMC_5_RXD_BUF1_SW

Q_RES_0402LF-4.7K,1%,1/16W,CHIA  I239  R765
   1 P3V3_AUX      A @SCM_LIB.SCM(SCH_1):P3V3_AUX
   2 UART_BMC_5_TXD_BUF_R      B @SCM_LIB.SCM(SCH_1):UART_BMC_5_TXD_BUF_R

74LVC2G07DW7-74LVC2G07DW-7,SMLA  I246  U24
   1 UART_BMC_5_TXD_BUF1_R     1A @SCM_LIB.SCM(SCH_1):UART_BMC_5_TXD_BUF1_R
   3 UART_BMC_5_RXD_BUF     2A @SCM_LIB.SCM(SCH_1):UART_BMC_5_RXD_BUF
   6 UART_BMC_5_TXD_BUF     1Y @SCM_LIB.SCM(SCH_1):UART_BMC_5_TXD_BUF
   4 UART_BMC_5_RXD_BUF_R     2Y @SCM_LIB.SCM(SCH_1):UART_BMC_5_RXD_BUF_R
   2    GND    GND @SCM_LIB.SCM(SCH_1):GND
   5 P3V3_AUX    VCC @SCM_LIB.SCM(SCH_1):P3V3_AUX

74LVC2G07DW7-74LVC2G07DW-7,SMLA  I247  U47
   1 UART_BMC_5_TXD_R     1A @SCM_LIB.SCM(SCH_1):UART_BMC_5_TXD_R
   3 UART_BMC_5_RXD_BUF1     2A @SCM_LIB.SCM(SCH_1):UART_BMC_5_RXD_BUF1
   6 UART_BMC_5_TXD_BUF1     1Y @SCM_LIB.SCM(SCH_1):UART_BMC_5_TXD_BUF1
   4 UART_BMC_5_RXD_BUF1_R     2Y @SCM_LIB.SCM(SCH_1):UART_BMC_5_RXD_BUF1_R
   2    GND    GND @SCM_LIB.SCM(SCH_1):GND
   5 P3V3_AUX    VCC @SCM_LIB.SCM(SCH_1):P3V3_AUX

FSA3357K8X-FSA3357K8X,SMLF,IC,A  I250  U2
   7 SPA_SOUT_SW_BUF      A @SCM_LIB.SCM(SCH_1):SPA_SOUT_SW_BUF
   4    GND    GND @SCM_LIB.SCM(SCH_1):GND
   3 UART_BMC_1_TXD_R     B2 @SCM_LIB.SCM(SCH_1):UART_BMC_1_TXD_R
   5 FM_UARTSW_LSB_N     S2 @SCM_LIB.SCM(SCH_1):FM_UARTSW_LSB_N
   8 P3V3_AUX    VCC @SCM_LIB.SCM(SCH_1):P3V3_AUX
   2 UART_BMC_5_TXD_BUF1_R     B1 @SCM_LIB.SCM(SCH_1):UART_BMC_5_TXD_BUF1_R
   1 UART_BIC_DBG_TX     B0 @SCM_LIB.SCM(SCH_1):UART_BIC_DBG_TX
   6 FM_UARTSW_MSB_N     S1 @SCM_LIB.SCM(SCH_1):FM_UARTSW_MSB_N

FSA3357K8X-FSA3357K8X,SMLF,IC,A  I251  U3
   7 SPA_SIN_SW_BUF      A @SCM_LIB.SCM(SCH_1):SPA_SIN_SW_BUF
   4    GND    GND @SCM_LIB.SCM(SCH_1):GND
   3 UART_BMC_1_RXD_R     B2 @SCM_LIB.SCM(SCH_1):UART_BMC_1_RXD_R
   5 FM_UARTSW_LSB_N     S2 @SCM_LIB.SCM(SCH_1):FM_UARTSW_LSB_N
   8 P3V3_AUX    VCC @SCM_LIB.SCM(SCH_1):P3V3_AUX
   2 UART_BMC_5_RXD_BUF1_SW     B1 @SCM_LIB.SCM(SCH_1):UART_BMC_5_RXD_BUF1_SW
   1 UART_BIC_DBG_RX     B0 @SCM_LIB.SCM(SCH_1):UART_BIC_DBG_RX
   6 FM_UARTSW_MSB_N     S1 @SCM_LIB.SCM(SCH_1):FM_UARTSW_MSB_N

Q_CAP_0402-0.1UF,25V,10%,X7R,CA  I254  C20
   1 P3V3_AUX      A @SCM_LIB.SCM(SCH_1):P3V3_AUX
   2    GND      B @SCM_LIB.SCM(SCH_1):GND

Q_CAP_0402-0.1UF,25V,10%,X7R,CA  I261  C19
   1 P3V3_AUX      A @SCM_LIB.SCM(SCH_1):P3V3_AUX
   2    GND      B @SCM_LIB.SCM(SCH_1):GND

Q_RES_0402LF-0,5%,1/16W,CHIP,CA  I266  R726
   1 SPA_SIN_SW_BUF_R      A @SCM_LIB.SCM(SCH_1):SPA_SIN_SW_BUF_R
   2 SPA_SIN_SW_BUF      B @SCM_LIB.SCM(SCH_1):SPA_SIN_SW_BUF

Q_RES_0402LF-0,5%,1/16W,CHIP,CA  I267  R39
   1 SPA_SOUT_SW_BUF_R      A @SCM_LIB.SCM(SCH_1):SPA_SOUT_SW_BUF_R
   2 SPA_SOUT_SW_BUF      B @SCM_LIB.SCM(SCH_1):SPA_SOUT_SW_BUF


DRAWING: @SCM_LIB.SCM(SCH_1):PAGE31 

Q_CAP_0402-0.1UF,25V,10%,X7R,CA  I11  C501
   1 P3V3_AUX      A @SCM_LIB.SCM(SCH_1):P3V3_AUX
   2    GND      B @SCM_LIB.SCM(SCH_1):GND

Q_CAP_0402-0.1UF,25V,10%,X7R,CA  I17  C500
   1 P3V3_AUX      A @SCM_LIB.SCM(SCH_1):P3V3_AUX
   2    GND      B @SCM_LIB.SCM(SCH_1):GND

NC7SB3157_SMLF-NC7SB3157P6X,NCA  I23  U50
   1 UART_BIC_DBG_TX_R     B1 @SCM_LIB.SCM(SCH_1):UART_BIC_DBG_TX_R
   2    GND    GND @SCM_LIB.SCM(SCH_1):GND
   3 UART_6_BMC_RXD_R     B0 @SCM_LIB.SCM(SCH_1):UART_6_BMC_RXD_R
   6 FM_BIC_DEBUG_SW_N      S @SCM_LIB.SCM(SCH_1):FM_BIC_DEBUG_SW_N
   5 P3V3_AUX    VCC @SCM_LIB.SCM(SCH_1):P3V3_AUX
   4 UART_BIC_GF_RXD      A @SCM_LIB.SCM(SCH_1):UART_BIC_GF_RXD

NC7SB3157_SMLF-NC7SB3157P6X,NCA  I24  U51
   1 UART_BIC_DBG_RX_R     B1 @SCM_LIB.SCM(SCH_1):UART_BIC_DBG_RX_R
   2    GND    GND @SCM_LIB.SCM(SCH_1):GND
   3 UART_6_BMC_TXD_R     B0 @SCM_LIB.SCM(SCH_1):UART_6_BMC_TXD_R
   6 FM_BIC_DEBUG_SW_N      S @SCM_LIB.SCM(SCH_1):FM_BIC_DEBUG_SW_N
   5 P3V3_AUX    VCC @SCM_LIB.SCM(SCH_1):P3V3_AUX
   4 UART_BIC_GF_TXD      A @SCM_LIB.SCM(SCH_1):UART_BIC_GF_TXD

Q_RES_0402LF-100K,1%,1/16W,CHIA  I25  R538
   1 P3V3_AUX      A @SCM_LIB.SCM(SCH_1):P3V3_AUX
   2 UART_6_BMC_RXD_R      B @SCM_LIB.SCM(SCH_1):UART_6_BMC_RXD_R

NC7SB3157_SMLF-NC7SB3157P6X,NCA  I27  U7
   1 SPA_SOUT_SW_DBG_R     B1 @SCM_LIB.SCM(SCH_1):SPA_SOUT_SW_DBG_R
   2    GND    GND @SCM_LIB.SCM(SCH_1):GND
   3 UART_SYS_DBG_TX_R     B0 @SCM_LIB.SCM(SCH_1):UART_SYS_DBG_TX_R
   6 FM_DBG_SW_N      S @SCM_LIB.SCM(SCH_1):FM_DBG_SW_N
   5 P3V3_AUX    VCC @SCM_LIB.SCM(SCH_1):P3V3_AUX
   4 SPA_SOUT_SW_BUF_R      A @SCM_LIB.SCM(SCH_1):SPA_SOUT_SW_BUF_R

Q_CAP_0402-0.1UF,25V,10%,X7R,CA  I31  C11
   1 P3V3_AUX      A @SCM_LIB.SCM(SCH_1):P3V3_AUX
   2    GND      B @SCM_LIB.SCM(SCH_1):GND

NC7SB3157_SMLF-NC7SB3157P6X,NCA  I38  U20
   1 SPA_SIN_SW_DBG_R     B1 @SCM_LIB.SCM(SCH_1):SPA_SIN_SW_DBG_R
   2    GND    GND @SCM_LIB.SCM(SCH_1):GND
   3 UART_SYS_DBG_RX_R     B0 @SCM_LIB.SCM(SCH_1):UART_SYS_DBG_RX_R
   6 FM_DBG_SW_N      S @SCM_LIB.SCM(SCH_1):FM_DBG_SW_N
   5 P3V3_AUX    VCC @SCM_LIB.SCM(SCH_1):P3V3_AUX
   4 SPA_SIN_SW_BUF_R      A @SCM_LIB.SCM(SCH_1):SPA_SIN_SW_BUF_R

Q_CAP_0402-0.1UF,25V,10%,X7R,CA  I45  C231
   1 P3V3_AUX      A @SCM_LIB.SCM(SCH_1):P3V3_AUX
   2    GND      B @SCM_LIB.SCM(SCH_1):GND

SCONN3_212H9103GBR1-SCONN3_212B  I61  J13
   3    GND      3 @SCM_LIB.SCM(SCH_1):GND
   2 FM_DBG_SW_N      2 @SCM_LIB.SCM(SCH_1):FM_DBG_SW_N
   1 PU_J13_P1      1 @SCM_LIB.SCM(SCH_1):PU_J13_P1

Q_RES_0402LF-0,5%,1/16W,CHIP,CA  I70  R900
   1 UART_BIC_DBG_TX      A @SCM_LIB.SCM(SCH_1):UART_BIC_DBG_TX
   2 UART_BIC_DBG_TX_R      B @SCM_LIB.SCM(SCH_1):UART_BIC_DBG_TX_R

Q_RES_0402LF-0,5%,1/16W,CHIP,CA  I71  R901
   1 UART_6_BMC_RXD      A @SCM_LIB.SCM(SCH_1):UART_6_BMC_RXD
   2 UART_6_BMC_RXD_R      B @SCM_LIB.SCM(SCH_1):UART_6_BMC_RXD_R

Q_RES_0402LF-0,5%,1/16W,CHIP,CA  I72  R902
   1 UART_BIC_DBG_RX      A @SCM_LIB.SCM(SCH_1):UART_BIC_DBG_RX
   2 UART_BIC_DBG_RX_R      B @SCM_LIB.SCM(SCH_1):UART_BIC_DBG_RX_R

Q_RES_0402LF-0,5%,1/16W,CHIP,CA  I73  R903
   1 UART_6_BMC_TXD      A @SCM_LIB.SCM(SCH_1):UART_6_BMC_TXD
   2 UART_6_BMC_TXD_R      B @SCM_LIB.SCM(SCH_1):UART_6_BMC_TXD_R

Q_RES_0402LF-0,5%,1/16W,CHIP,CA  I74  R544
   1 UART_SYS_DBG_TX      A @SCM_LIB.SCM(SCH_1):UART_SYS_DBG_TX
   2 UART_SYS_DBG_TX_R      B @SCM_LIB.SCM(SCH_1):UART_SYS_DBG_TX_R

Q_RES_0402LF-0,5%,1/16W,CHIP,CA  I75  R546
   1 SPA_SOUT_SW_DBG      A @SCM_LIB.SCM(SCH_1):SPA_SOUT_SW_DBG
   2 SPA_SOUT_SW_DBG_R      B @SCM_LIB.SCM(SCH_1):SPA_SOUT_SW_DBG_R

Q_RES_0402LF-0,5%,1/16W,CHIP,CA  I76  R618
   1 UART_SYS_DBG_RX      A @SCM_LIB.SCM(SCH_1):UART_SYS_DBG_RX
   2 UART_SYS_DBG_RX_R      B @SCM_LIB.SCM(SCH_1):UART_SYS_DBG_RX_R

Q_RES_0402LF-100,1%,1/16W,CHIPA  I77  R628
   1 SPA_SIN_SW_DBG      A @SCM_LIB.SCM(SCH_1):SPA_SIN_SW_DBG
   2 SPA_SIN_SW_DBG_R      B @SCM_LIB.SCM(SCH_1):SPA_SIN_SW_DBG_R

Q_RES_0402LF-0,5%,1/16W,CHIP,CA  I78  R629
   1 BMC_CPLD_GPIO_2      A @SCM_LIB.SCM(SCH_1):BMC_CPLD_GPIO_2
   2 FM_DBG_SW_N      B @SCM_LIB.SCM(SCH_1):FM_DBG_SW_N

Q_RES_0402LF-4.7K,1%,1/16W,CHIA  I79  R630
   1 P3V3_AUX      A @SCM_LIB.SCM(SCH_1):P3V3_AUX
   2 PU_J13_P1      B @SCM_LIB.SCM(SCH_1):PU_J13_P1

Q_RES_0402LF-100K,1%,1/16W,CHIA  I80  R396
   1 P3V3_AUX      A @SCM_LIB.SCM(SCH_1):P3V3_AUX
   2 UART_BIC_GF_RXD      B @SCM_LIB.SCM(SCH_1):UART_BIC_GF_RXD


DRAWING: @SCM_LIB.SCM(SCH_1):PAGE32 

Q_CAP_0402-0.1UF,25V,10%,X7R,CA  I21  C217
   1  J7_P1      A @SCM_LIB.SCM(SCH_1):J7_P1
   2    GND      B @SCM_LIB.SCM(SCH_1):GND

Q_CAP_C0402-10UF,6.3V,20%,X6S,A  I22  C215
   1  J7_P1      A @SCM_LIB.SCM(SCH_1):J7_P1
   2    GND      B @SCM_LIB.SCM(SCH_1):GND

Q_RES_0402LF-33.2,1%,1/16W,CHIA  I23  R518
   1 JTAG_SCM_PLD_R1_JTAGEN      A @SCM_LIB.SCM(SCH_1):JTAG_SCM_PLD_R1_JTAGEN
   2 JTAG_SCM_PLD_JTAGEN      B @SCM_LIB.SCM(SCH_1):JTAG_SCM_PLD_JTAGEN

Q_RES_0402LF-33.2,1%,1/16W,CHIA  I78  R223
   1 JTAG_1_BMC_TMS_R      A @SCM_LIB.SCM(SCH_1):JTAG_1_BMC_TMS_R
   2 JTAG_MB_TMS      B @SCM_LIB.SCM(SCH_1):JTAG_MB_TMS

Q_RES_0402LF-33.2,1%,1/16W,CHIA  I80  R222
   1 JTAG_1_BMC_TCK_R      A @SCM_LIB.SCM(SCH_1):JTAG_1_BMC_TCK_R
   2 JTAG_MB_TCK      B @SCM_LIB.SCM(SCH_1):JTAG_MB_TCK

Q_RES_0402LF-33.2,1%,1/16W,CHIA  I81  R221
   1 JTAG_1_BMC_TRST_R      A @SCM_LIB.SCM(SCH_1):JTAG_1_BMC_TRST_R
   2 JTAG_MB_TRST_N      B @SCM_LIB.SCM(SCH_1):JTAG_MB_TRST_N

Q_RES_0402LF-33.2,1%,1/16W,CHIA  I87  R224
   1 JTAG_1_BMC_TDO_R      A @SCM_LIB.SCM(SCH_1):JTAG_1_BMC_TDO_R
   2 JTAG_MB_TDO      B @SCM_LIB.SCM(SCH_1):JTAG_MB_TDO

Q_RES_0402LF-33.2,1%,1/16W,CHIA  I88  R639
   1 JTAG_1_BMC_TDI_R      A @SCM_LIB.SCM(SCH_1):JTAG_1_BMC_TDI_R
   2 JTAG_MB_TDI      B @SCM_LIB.SCM(SCH_1):JTAG_MB_TDI

Q_RES_0402LF-33.2,1%,1/16W,CHIA  I94  R514
   1 JTAG_SCM_PLD_TCK      A @SCM_LIB.SCM(SCH_1):JTAG_SCM_PLD_TCK
   2 JTAG_SCM_CONN_TCK      B @SCM_LIB.SCM(SCH_1):JTAG_SCM_CONN_TCK

Q_RES_0402LF-33.2,1%,1/16W,CHIA  I95  R516
   1 JTAG_SCM_PLD_TDI      A @SCM_LIB.SCM(SCH_1):JTAG_SCM_PLD_TDI
   2 JTAG_SCM_CONN_TDI      B @SCM_LIB.SCM(SCH_1):JTAG_SCM_CONN_TDI

Q_RES_0402LF-33.2,1%,1/16W,CHIA  I96  R515
   1 JTAG_SCM_PLD_TMS      A @SCM_LIB.SCM(SCH_1):JTAG_SCM_PLD_TMS
   2 JTAG_SCM_CONN_TMS      B @SCM_LIB.SCM(SCH_1):JTAG_SCM_CONN_TMS

Q_RES_0402LF-33.2,1%,1/16W,CHIA  I97  R517
   1 JTAG_SCM_PLD_TDO      A @SCM_LIB.SCM(SCH_1):JTAG_SCM_PLD_TDO
   2 JTAG_SCM_CONN_TDO      B @SCM_LIB.SCM(SCH_1):JTAG_SCM_CONN_TDO

Q_RES_0402LF-10K,1%,1/16W,CHIPA  I103  R226
   1 P3V3_AUX      A @SCM_LIB.SCM(SCH_1):P3V3_AUX
   2 JTAG_MB_TDI      B @SCM_LIB.SCM(SCH_1):JTAG_MB_TDI

Q_RES_0402LF-10K,1%,1/16W,CHIPA  I104  R227
   1 P3V3_AUX      A @SCM_LIB.SCM(SCH_1):P3V3_AUX
   2 JTAG_MB_TMS      B @SCM_LIB.SCM(SCH_1):JTAG_MB_TMS

Q_RES_0402LF-10K,1%,1/16W,CHIPA  I105  R230
   1 P3V3_AUX      A @SCM_LIB.SCM(SCH_1):P3V3_AUX
   2 JTAG_MB_TDO      B @SCM_LIB.SCM(SCH_1):JTAG_MB_TDO

Q_RES_0402LF-4.7K,1%,1/16W,EMPA  I106  R229
   1    GND      A @SCM_LIB.SCM(SCH_1):GND
   2 JTAG_MB_TRST_N      B @SCM_LIB.SCM(SCH_1):JTAG_MB_TRST_N

Q_RES_0402LF-10K,1%,1/16W,EMPTA  I107  R228
   1    GND      A @SCM_LIB.SCM(SCH_1):GND
   2 JTAG_MB_TCK      B @SCM_LIB.SCM(SCH_1):JTAG_MB_TCK

Q_RES_0402LF-10K,1%,1/16W,CHIPA  I117  R203
   1 P3V3_RGM      A @SCM_LIB.SCM(SCH_1):P3V3_RGM
   2 JTAG_SCM_TMS      B @SCM_LIB.SCM(SCH_1):JTAG_SCM_TMS

Q_RES_0402LF-10K,1%,1/16W,CHIPA  I119  R523
   1 P3V3_RGM      A @SCM_LIB.SCM(SCH_1):P3V3_RGM
   2 JTAG_SCM_TDO      B @SCM_LIB.SCM(SCH_1):JTAG_SCM_TDO

Q_RES_0402LF-10K,1%,1/16W,CHIPA  I120  R204
   1 P3V3_RGM      A @SCM_LIB.SCM(SCH_1):P3V3_RGM
   2 JTAG_SCM_TDI      B @SCM_LIB.SCM(SCH_1):JTAG_SCM_TDI

Q_RES_0402LF-33.2,1%,1/16W,CHIA  I126  R510
   1 JTAG_SCM_TCK      A @SCM_LIB.SCM(SCH_1):JTAG_SCM_TCK
   2 JTAG_SCM_PLD_TCK      B @SCM_LIB.SCM(SCH_1):JTAG_SCM_PLD_TCK

Q_RES_0402LF-33.2,1%,1/16W,CHIA  I127  R511
   1 JTAG_SCM_TMS      A @SCM_LIB.SCM(SCH_1):JTAG_SCM_TMS
   2 JTAG_SCM_PLD_TMS      B @SCM_LIB.SCM(SCH_1):JTAG_SCM_PLD_TMS

Q_RES_0402LF-33.2,1%,1/16W,CHIA  I128  R513
   1 JTAG_SCM_TDO      A @SCM_LIB.SCM(SCH_1):JTAG_SCM_TDO
   2 JTAG_SCM_PLD_TDO      B @SCM_LIB.SCM(SCH_1):JTAG_SCM_PLD_TDO

Q_RES_0402LF-33.2,1%,1/16W,CHIA  I129  R512
   1 JTAG_SCM_TDI      A @SCM_LIB.SCM(SCH_1):JTAG_SCM_TDI
   2 JTAG_SCM_PLD_TDI      B @SCM_LIB.SCM(SCH_1):JTAG_SCM_PLD_TDI

Q_RES_0402LF-10K,1%,1/16W,EMPTA  I131  R834
   1 P3V3_RGM      A @SCM_LIB.SCM(SCH_1):P3V3_RGM
   2 JTAG_SCM_TCK      B @SCM_LIB.SCM(SCH_1):JTAG_SCM_TCK

CONN8_210HP1080BR1-CONN8_210-HA  I132  J7
   1  J7_P1      1 @SCM_LIB.SCM(SCH_1):J7_P1
   2 JTAG_SCM_CONN_TDO      2 @SCM_LIB.SCM(SCH_1):JTAG_SCM_CONN_TDO
   3 JTAG_SCM_CONN_TDI      3 @SCM_LIB.SCM(SCH_1):JTAG_SCM_CONN_TDI
   4 JTAG_SCM_PLD_R1_JTAGEN      4 @SCM_LIB.SCM(SCH_1):JTAG_SCM_PLD_R1_JTAGEN
   5 TP_PLD_CONN_P5      5 @SCM_LIB.SCM(SCH_1):TP_PLD_CONN_P5
   6 JTAG_SCM_CONN_TMS      6 @SCM_LIB.SCM(SCH_1):JTAG_SCM_CONN_TMS
   7    GND      7 @SCM_LIB.SCM(SCH_1):GND
   8 JTAG_SCM_CONN_TCK      8 @SCM_LIB.SCM(SCH_1):JTAG_SCM_CONN_TCK

Q_RES_0402LF-10K,1%,1/16W,EMPTA  I140  R202
   1    GND      A @SCM_LIB.SCM(SCH_1):GND
   2 JTAG_SCM_TCK      B @SCM_LIB.SCM(SCH_1):JTAG_SCM_TCK

Q_RES_0402LF-4.7K,1%,1/16W,CHIA  I141  R285
   1 JTAG_SCM_PLD_TCK      A @SCM_LIB.SCM(SCH_1):JTAG_SCM_PLD_TCK
   2    GND      B @SCM_LIB.SCM(SCH_1):GND

Q_RES_0402LF-10K,1%,1/16W,CHIPA  I143  R206
   1    GND      A @SCM_LIB.SCM(SCH_1):GND
   2 JTAG_SCM_NTRST      B @SCM_LIB.SCM(SCH_1):JTAG_SCM_NTRST

SCHOTTKY_12-1N5819HW,SMLF,IC,BA  I144  D20
   1 P3V3_AUX      A @SCM_LIB.SCM(SCH_1):P3V3_AUX
   2  J7_P1      C @SCM_LIB.SCM(SCH_1):J7_P1


DRAWING: @SCM_LIB.SCM(SCH_1):PAGE34 

LCMXO3LF2100C5BG256C-LCMXO3LF-A  I1  U25
  D5 VCCIO0 VCCIO0_D5 @SCM_LIB.SCM(SCH_1):VCCIO0
 D12 VCCIO0 VCCIO0_D12 @SCM_LIB.SCM(SCH_1):VCCIO0
  G8 VCCIO0 VCCIO0_G8 @SCM_LIB.SCM(SCH_1):VCCIO0
  G9 VCCIO0 VCCIO0_G9 @SCM_LIB.SCM(SCH_1):VCCIO0
  C4 FM_TPM_PRSNT_0_R_N   PT9A @SCM_LIB.SCM(SCH_1):FM_TPM_PRSNT_0_R_N
  B5 FM_TPM_PRSNT_1_R_N   PT9B @SCM_LIB.SCM(SCH_1):FM_TPM_PRSNT_1_R_N
  B3 IRQ_BMC_CPU_NMI_R   PT9C @SCM_LIB.SCM(SCH_1):IRQ_BMC_CPU_NMI_R
  A4 RST_PLTRST_R1_N  PT10A @SCM_LIB.SCM(SCH_1):RST_PLTRST_R1_N
  C5 PWRGD_PSU_AC_PWROK_PLD  PT10B @SCM_LIB.SCM(SCH_1):PWRGD_PSU_AC_PWROK_PLD
  A5 RST_RSMRST_N  PT11A @SCM_LIB.SCM(SCH_1):RST_RSMRST_N
  B6 FM_JTAG_BMC_MUX_SEL_R2  PT11B @SCM_LIB.SCM(SCH_1):FM_JTAG_BMC_MUX_SEL_R2
  A3 BSM_PRSNT_R1_N  PT11C @SCM_LIB.SCM(SCH_1):BSM_PRSNT_R1_N
  B4 RST_PCA9548_SENSOR_N  PT11D @SCM_LIB.SCM(SCH_1):RST_PCA9548_SENSOR_N
  D6 FM_BMC_DBP_PRESENT_N  PT12A @SCM_LIB.SCM(SCH_1):FM_BMC_DBP_PRESENT_N
  E7 PWRGD_PCH_PWROK  PT12B @SCM_LIB.SCM(SCH_1):PWRGD_PCH_PWROK
  C6 JTAG_SCM_PLD_TDO PT12C||TDO @SCM_LIB.SCM(SCH_1):JTAG_SCM_PLD_TDO
  A6 JTAG_SCM_PLD_TDI PT12D||TDI @SCM_LIB.SCM(SCH_1):JTAG_SCM_PLD_TDI
  B7 IRQ_UV_DETECT_N  PT13A @SCM_LIB.SCM(SCH_1):IRQ_UV_DETECT_N
  C7 RST_BMC_RSTBTN_OUT_N  PT13B @SCM_LIB.SCM(SCH_1):RST_BMC_RSTBTN_OUT_N
  E6 BMC_CPLD_GPIO_2_R2  PT13C @SCM_LIB.SCM(SCH_1):BMC_CPLD_GPIO_2_R2
  D7 FM_ME_BT_DONE  PT13D @SCM_LIB.SCM(SCH_1):FM_ME_BT_DONE
  F7 FM_PCIE_M2_SSD0_PRSNT_N  PT16A @SCM_LIB.SCM(SCH_1):FM_PCIE_M2_SSD0_PRSNT_N
  E8 FM_BIOS_POST_CMPLT_BMC_N  PT16B @SCM_LIB.SCM(SCH_1):FM_BIOS_POST_CMPLT_BMC_N
  A7 JTAG_SCM_PLD_TCK PT16C||TCK @SCM_LIB.SCM(SCH_1):JTAG_SCM_PLD_TCK
  B8 JTAG_SCM_PLD_TMS PT16D||TMS @SCM_LIB.SCM(SCH_1):JTAG_SCM_PLD_TMS
  C8 CLK_25M_OSC_FPGA PT17A||PCLKT0_1 @SCM_LIB.SCM(SCH_1):CLK_25M_OSC_FPGA
  A8 IRQ_BMC_PCH_NMI_R_N PT17B||PCLKC0_1 @SCM_LIB.SCM(SCH_1):IRQ_BMC_PCH_NMI_R_N
  D8 FM_PCH_BMC_THERMTRIP_N  PT17C @SCM_LIB.SCM(SCH_1):FM_PCH_BMC_THERMTRIP_N
  E9 H_CPU1_PROCHOT_LVC1_R_N  PT17D @SCM_LIB.SCM(SCH_1):H_CPU1_PROCHOT_LVC1_R_N
  D9     NC  PT18B     NC
  A9 SMB_BMC_MM16_R3_SCL PT18C||SCL||PCLKT0_0 @SCM_LIB.SCM(SCH_1):SMB_BMC_MM16_R3_SCL
  C9 SMB_BMC_MM16_R3_SDA PT18D||SDA||PCLKC0_0 @SCM_LIB.SCM(SCH_1):SMB_BMC_MM16_R3_SDA
  B9 IRQ_PCH_SCI_WHEA_N  PT19A @SCM_LIB.SCM(SCH_1):IRQ_PCH_SCI_WHEA_N
 A10     NC  PT19B     NC
  F9     NC  PT19C     NC
 E11 TP_PLD_19D  PT19D @SCM_LIB.SCM(SCH_1):TP_PLD_19D
 D10     NC  PT20A     NC
 E10 FM_CPU_MSMI_CATERR_LVT3_PLD_N  PT20B @SCM_LIB.SCM(SCH_1):FM_CPU_MSMI_CATERR_LVT3_PLD_N
 C10 JTAG_SCM_PLD_R_JTAGEN PT20C||JTAGENB @SCM_LIB.SCM(SCH_1):JTAG_SCM_PLD_R_JTAGEN
 B10 PU_PT20D PT20D||PROGRAMN @SCM_LIB.SCM(SCH_1):PU_PT20D
 A11 RST_EXTRST_R_N  PT21A @SCM_LIB.SCM(SCH_1):RST_EXTRST_R_N
 C11 PWRGD_CPUPWRGD_LVC1  PT21B @SCM_LIB.SCM(SCH_1):PWRGD_CPUPWRGD_LVC1
 F10 IRQ_CPU0_VRHOT_N  PT21C @SCM_LIB.SCM(SCH_1):IRQ_CPU0_VRHOT_N
 D11 IRQ_CPU1_VRHOT_N  PT21D @SCM_LIB.SCM(SCH_1):IRQ_CPU1_VRHOT_N
 B11 IRQ_OC_DETECT_N  PT22A @SCM_LIB.SCM(SCH_1):IRQ_OC_DETECT_N
 A12 FM_ADR_COMPLETE  PT22B @SCM_LIB.SCM(SCH_1):FM_ADR_COMPLETE
 B13 IRQ_OC_DETECT_EN_N  PT22C @SCM_LIB.SCM(SCH_1):IRQ_OC_DETECT_EN_N
 A14 SGPIO_CLK_PLD_0  PT22D @SCM_LIB.SCM(SCH_1):SGPIO_CLK_PLD_0
 C12 SGPIO_PLD_DO_0  PT23A @SCM_LIB.SCM(SCH_1):SGPIO_PLD_DO_0
 B12 SGPIO_PLD_LD_0  PT23B @SCM_LIB.SCM(SCH_1):SGPIO_PLD_LD_0
 B14 SGPIO_PLD_DI_0  PT24A @SCM_LIB.SCM(SCH_1):SGPIO_PLD_DI_0
 A15 FM_THERMTRIP_DLY_LVC1_R_N  PT24B @SCM_LIB.SCM(SCH_1):FM_THERMTRIP_DLY_LVC1_R_N
 A13 PU_FPGA_NSTATUS PT24C||INITN @SCM_LIB.SCM(SCH_1):PU_FPGA_NSTATUS
 C13 PU_FPGA_CONFIG_DONE PT24D||DONE @SCM_LIB.SCM(SCH_1):PU_FPGA_CONFIG_DONE
  F8 RST_SRST_PLD_BMC_R2_N  PT18A @SCM_LIB.SCM(SCH_1):RST_SRST_PLD_BMC_R2_N

Q_RES_0402LF-4.7K,1%,1/16W,CHIA  I17  R625
   1 P3V3_AUX      A @SCM_LIB.SCM(SCH_1):P3V3_AUX
   2 RST_RSMRST_N      B @SCM_LIB.SCM(SCH_1):RST_RSMRST_N

Q_RES_0402LF-0,5%,1/16W,CHIP,CA  I35  R571
   1 IRQ_BMC_PCH_NMI_N      A @SCM_LIB.SCM(SCH_1):IRQ_BMC_PCH_NMI_N
   2 IRQ_BMC_PCH_NMI_R_N      B @SCM_LIB.SCM(SCH_1):IRQ_BMC_PCH_NMI_R_N

Q_RES_0402LF-0,5%,1/16W,CHIP,CA  I37  R634
   1 FM_JTAG_BMC_MUX_SEL      A @SCM_LIB.SCM(SCH_1):FM_JTAG_BMC_MUX_SEL
   2 FM_JTAG_BMC_MUX_SEL_R2      B @SCM_LIB.SCM(SCH_1):FM_JTAG_BMC_MUX_SEL_R2

Q_RES_0402LF-10K,1%,1/16W,CHIPA  I115  R809
   1 PU_FPGA_NCONFIG      A @SCM_LIB.SCM(SCH_1):PU_FPGA_NCONFIG
   2 PVCCIO_AUX_PLD      B @SCM_LIB.SCM(SCH_1):PVCCIO_AUX_PLD

Q_RES_0402LF-10K,1%,1/16W,CHIPA  I116  R810
   1 PU_FPGA_NSTATUS      A @SCM_LIB.SCM(SCH_1):PU_FPGA_NSTATUS
   2 PVCCIO_AUX_PLD      B @SCM_LIB.SCM(SCH_1):PVCCIO_AUX_PLD

Q_RES_0402LF-10K,1%,1/16W,CHIPA  I117  R808
   1 PU_FPGA_CONFIG_DONE      A @SCM_LIB.SCM(SCH_1):PU_FPGA_CONFIG_DONE
   2 PVCCIO_AUX_PLD      B @SCM_LIB.SCM(SCH_1):PVCCIO_AUX_PLD

Q_RES_0402LF-4.7K,1%,1/16W,CHIA  I119  R806
   1 P3V3_AUX      A @SCM_LIB.SCM(SCH_1):P3V3_AUX
   2 PU_25M_FPGA_CLK_EN      B @SCM_LIB.SCM(SCH_1):PU_25M_FPGA_CLK_EN

Q_CAP_0402-0.1UF,25V,10%,X7R,CA  I122  C318
   1 P3V3_AUX      A @SCM_LIB.SCM(SCH_1):P3V3_AUX
   2    GND      B @SCM_LIB.SCM(SCH_1):GND

Q_RES_0402LF-33.2,1%,1/16W,CHIA  I126  R807
   1 CLK_25M_OSC_FPGA_R      A @SCM_LIB.SCM(SCH_1):CLK_25M_OSC_FPGA_R
   2 CLK_25M_OSC_FPGA      B @SCM_LIB.SCM(SCH_1):CLK_25M_OSC_FPGA

OSC4_7X25000018-25MHZ,SMLF,MISA  I127  OSC2
   1 PU_25M_FPGA_CLK_EN     OE @SCM_LIB.SCM(SCH_1):PU_25M_FPGA_CLK_EN
   2    GND    GND @SCM_LIB.SCM(SCH_1):GND
   3 CLK_25M_OSC_FPGA_R    OUT @SCM_LIB.SCM(SCH_1):CLK_25M_OSC_FPGA_R
   4 P3V3_AUX    VDD @SCM_LIB.SCM(SCH_1):P3V3_AUX

Q_RES_0402LF-10K,1%,1/16W,CHIPA  I137  R297
   1 PU_PT20D      A @SCM_LIB.SCM(SCH_1):PU_PT20D
   2 VCCIO2      B @SCM_LIB.SCM(SCH_1):VCCIO2

Q_RES_0402LF-0,5%,1/16W,CHIP,CA  I139  R183
   1 P3V3_AUX      A @SCM_LIB.SCM(SCH_1):P3V3_AUX
   2 PVCCIO_AUX_PLD      B @SCM_LIB.SCM(SCH_1):PVCCIO_AUX_PLD

Q_CAP_C0402-1UF,25V,10%,X6S,CHA  I140  C256
   1 PVCCIO_AUX_PLD      A @SCM_LIB.SCM(SCH_1):PVCCIO_AUX_PLD
   2    GND      B @SCM_LIB.SCM(SCH_1):GND

Q_CAP_0402-0.1UF,25V,10%,X7R,CA  I144  C257
   1 PVCCIO_AUX_PLD      A @SCM_LIB.SCM(SCH_1):PVCCIO_AUX_PLD
   2    GND      B @SCM_LIB.SCM(SCH_1):GND

Q_RES_0402LF-0,5%,1/16W,CHIP,CA  I147  R519
   1 BMC_CPLD_GPIO_2      A @SCM_LIB.SCM(SCH_1):BMC_CPLD_GPIO_2
   2 BMC_CPLD_GPIO_2_R2      B @SCM_LIB.SCM(SCH_1):BMC_CPLD_GPIO_2_R2

Q_RES_0402LF-33.2,1%,1/16W,CHIA  I150  R767
   1 FM_TPM_PRSNT_0_N      A @SCM_LIB.SCM(SCH_1):FM_TPM_PRSNT_0_N
   2 FM_TPM_PRSNT_0_R_N      B @SCM_LIB.SCM(SCH_1):FM_TPM_PRSNT_0_R_N

Q_RES_0402LF-0,5%,1/16W,CHIP,CA  I155  R10
   1 RST_SRST_PLD_BMC_R2_N      A @SCM_LIB.SCM(SCH_1):RST_SRST_PLD_BMC_R2_N
   2 RST_SRST_PLD_BMC_R_N      B @SCM_LIB.SCM(SCH_1):RST_SRST_PLD_BMC_R_N

Q_RES_0402LF-33.2,1%,1/16W,CHIA  I156  R123
   1 FM_TPM_PRSNT_1_N      A @SCM_LIB.SCM(SCH_1):FM_TPM_PRSNT_1_N
   2 FM_TPM_PRSNT_1_R_N      B @SCM_LIB.SCM(SCH_1):FM_TPM_PRSNT_1_R_N

Q_RES_0402LF-33.2,1%,1/16W,CHIA  I157  R718
   1 RST_PLTRST_N      A @SCM_LIB.SCM(SCH_1):RST_PLTRST_N
   2 RST_PLTRST_R1_N      B @SCM_LIB.SCM(SCH_1):RST_PLTRST_R1_N

Q_RES_0402LF-33.2,1%,1/16W,CHIA  I158  R837
   1 PWRGD_PSU_AC_PWROK      A @SCM_LIB.SCM(SCH_1):PWRGD_PSU_AC_PWROK
   2 PWRGD_PSU_AC_PWROK_PLD      B @SCM_LIB.SCM(SCH_1):PWRGD_PSU_AC_PWROK_PLD

Q_RES_0402LF-33.2,1%,1/16W,CHIA  I159  R459
   1 BSM_PRSNT_R_N      A @SCM_LIB.SCM(SCH_1):BSM_PRSNT_R_N
   2 BSM_PRSNT_R1_N      B @SCM_LIB.SCM(SCH_1):BSM_PRSNT_R1_N

Q_RES_0402LF-33.2,1%,1/16W,CHIA  I160  R434
   1 SGPIO_CLK_PLD_0      A @SCM_LIB.SCM(SCH_1):SGPIO_CLK_PLD_0
   2 SGPIO_CLK_0      B @SCM_LIB.SCM(SCH_1):SGPIO_CLK_0

Q_RES_0402LF-33.2,1%,1/16W,CHIA  I161  R435
   1 SGPIO_PLD_DO_0      A @SCM_LIB.SCM(SCH_1):SGPIO_PLD_DO_0
   2 SGPIO_DO_0      B @SCM_LIB.SCM(SCH_1):SGPIO_DO_0

Q_RES_0402LF-33.2,1%,1/16W,CHIA  I162  R436
   1 SGPIO_PLD_LD_0      A @SCM_LIB.SCM(SCH_1):SGPIO_PLD_LD_0
   2 SGPIO_LD_0      B @SCM_LIB.SCM(SCH_1):SGPIO_LD_0

Q_RES_0402LF-33.2,1%,1/16W,CHIA  I163  R437
   1 SGPIO_PLD_DI_0      A @SCM_LIB.SCM(SCH_1):SGPIO_PLD_DI_0
   2 SGPIO_DI_0      B @SCM_LIB.SCM(SCH_1):SGPIO_DI_0

Q_RES_0402LF-33.2,1%,1/16W,CHIA  I164  R270
   1 FM_CPU_MSMI_CATERR_LVT3_PLD_N      A @SCM_LIB.SCM(SCH_1):FM_CPU_MSMI_CATERR_LVT3_PLD_N
   2 FM_CPU_MSMI_CATERR_LVT3_N      B @SCM_LIB.SCM(SCH_1):FM_CPU_MSMI_CATERR_LVT3_N

Q_RES_0402LF-0,5%,1/16W,CHIP,CA  I165  R272
   1 SMB_BMC_MM16_R3_SCL      A @SCM_LIB.SCM(SCH_1):SMB_BMC_MM16_R3_SCL
   2 SMB_BMC_MM16_R5_SCL      B @SCM_LIB.SCM(SCH_1):SMB_BMC_MM16_R5_SCL

Q_RES_0402LF-0,5%,1/16W,CHIP,CA  I166  R303
   1 SMB_BMC_MM16_R3_SDA      A @SCM_LIB.SCM(SCH_1):SMB_BMC_MM16_R3_SDA
   2 SMB_BMC_MM16_R5_SDA      B @SCM_LIB.SCM(SCH_1):SMB_BMC_MM16_R5_SDA

Q_RES_0402LF-0,5%,1/16W,CHIP,CA  I167  R397
   1 JTAG_SCM_PLD_R_JTAGEN      A @SCM_LIB.SCM(SCH_1):JTAG_SCM_PLD_R_JTAGEN
   2 JTAG_SCM_PLD_JTAGEN      B @SCM_LIB.SCM(SCH_1):JTAG_SCM_PLD_JTAGEN

Q_RES_0402LF-0,5%,1/16W,CHIP,CA  I168  R447
   1 RST_EXTRST_R_N      A @SCM_LIB.SCM(SCH_1):RST_EXTRST_R_N
   2 RST_EXTRST_N      B @SCM_LIB.SCM(SCH_1):RST_EXTRST_N


DRAWING: @SCM_LIB.SCM(SCH_1):PAGE35 

LCMXO3LF2100C5BG256C-LCMXO3LF-A  I1  U25
 J11     NC  PR10C     NC
 L12 FM_BMC_EN_DET_R  PR10D @SCM_LIB.SCM(SCH_1):FM_BMC_EN_DET_R
 G16 BMC_CPLD_GPIO_12_R2   PR6A @SCM_LIB.SCM(SCH_1):BMC_CPLD_GPIO_12_R2
 H15 BMC_CPLD_GPIO_13_R2   PR6B @SCM_LIB.SCM(SCH_1):BMC_CPLD_GPIO_13_R2
 K11 FM_PCHHOT_R_N  PR12C @SCM_LIB.SCM(SCH_1):FM_PCHHOT_R_N
 L13 FM_BMC_ONCTL_R_N  PR12D @SCM_LIB.SCM(SCH_1):FM_BMC_ONCTL_R_N
 H14     NC PR7A||PCLKT1_0     NC
 H16     NC PR7B||PCLKC1_0     NC
 N15 AC_PWR_BTN_R2_N  PR13C @SCM_LIB.SCM(SCH_1):AC_PWR_BTN_R2_N
 P16     NC  PR13D     NC
 N16 PWRGD_P3V3_AUX_R1  PR14A @SCM_LIB.SCM(SCH_1):PWRGD_P3V3_AUX_R1
 N14 PWRGD_P2V5_AUX_R1  PR14B @SCM_LIB.SCM(SCH_1):PWRGD_P2V5_AUX_R1
 P15     NC  PR14C     NC
 R16 SMB_BMC_ALERT16_R2_N  PR14D @SCM_LIB.SCM(SCH_1):SMB_BMC_ALERT16_R2_N
 M14 PWR_LED_CPLD  PR13A @SCM_LIB.SCM(SCH_1):PWR_LED_CPLD
 M15 PWRGD_P5V_AUX_R1  PR13B @SCM_LIB.SCM(SCH_1):PWRGD_P5V_AUX_R1
 L15     NC  PR12A     NC
 M16     NC  PR12B     NC
 K13 FM_BMC_READY_PLD_N  PR11C @SCM_LIB.SCM(SCH_1):FM_BMC_READY_PLD_N
 K12 FM_BIOS_DEBUG_EN_N  PR11D @SCM_LIB.SCM(SCH_1):FM_BIOS_DEBUG_EN_N
 L16 USB_OC0_REAR_R_N  PR11A @SCM_LIB.SCM(SCH_1):USB_OC0_REAR_R_N
 L14 SMB_BMC_ALERT12_N  PR11B @SCM_LIB.SCM(SCH_1):SMB_BMC_ALERT12_N
 K14 FM_PWR_R_BTN  PR10A @SCM_LIB.SCM(SCH_1):FM_PWR_R_BTN
 K15 PWRGD_SYS_PWROK_PLD  PR10B @SCM_LIB.SCM(SCH_1):PWRGD_SYS_PWROK_PLD
 J15 RST_BMC_HW_R   PR9A @SCM_LIB.SCM(SCH_1):RST_BMC_HW_R
 K16     NC   PR9B     NC
 D14 H_CPU0_MEMTRIP_LVC1_N   PR1A @SCM_LIB.SCM(SCH_1):H_CPU0_MEMTRIP_LVC1_N
 E15 FM_SPD_REMOTE_EN_R   PR1B @SCM_LIB.SCM(SCH_1):FM_SPD_REMOTE_EN_R
 C15 VOL_SEN_ALERT_R   PR1C @SCM_LIB.SCM(SCH_1):VOL_SEN_ALERT_R
 B16 FM_PECI_SEL_N   PR1D @SCM_LIB.SCM(SCH_1):FM_PECI_SEL_N
 D16 H_CPU1_MEMTRIP_LVC1_N   PR2A @SCM_LIB.SCM(SCH_1):H_CPU1_MEMTRIP_LVC1_N
 E14 IRQ_SGPIO_R_N   PR2B @SCM_LIB.SCM(SCH_1):IRQ_SGPIO_R_N
 C16 SMB_BMC_ALERT3_R1_N   PR2C @SCM_LIB.SCM(SCH_1):SMB_BMC_ALERT3_R1_N
 D15 SMB_BMC_ALERT4_R1_N   PR2D @SCM_LIB.SCM(SCH_1):SMB_BMC_ALERT4_R1_N
 F13 SMB_BMC_ALERT9_R1_N   PR3C @SCM_LIB.SCM(SCH_1):SMB_BMC_ALERT9_R1_N
 G12 SMB_BMC_ALERT10_R1_N   PR3D @SCM_LIB.SCM(SCH_1):SMB_BMC_ALERT10_R1_N
 F12 TP_PLD_L3   PR4C @SCM_LIB.SCM(SCH_1):TP_PLD_L3
 G13 RST_BMC_SELF_HW_R2   PR4D @SCM_LIB.SCM(SCH_1):RST_BMC_SELF_HW_R2
 E16 RST_SGPIO_RESET_R_N   PR3A @SCM_LIB.SCM(SCH_1):RST_SGPIO_RESET_R_N
 F15 BMC_CPLD_GPIO_7_R2   PR3B @SCM_LIB.SCM(SCH_1):BMC_CPLD_GPIO_7_R2
 G11 FM_SLPS3_GF_R_N   PR5C @SCM_LIB.SCM(SCH_1):FM_SLPS3_GF_R_N
 H12 RST_ROT_CPU_R_N   PR5D @SCM_LIB.SCM(SCH_1):RST_ROT_CPU_R_N
 F14 BMC_CPLD_GPIO_8_R2   PR4A @SCM_LIB.SCM(SCH_1):BMC_CPLD_GPIO_8_R2
 F16     NC   PR4B     NC
 H13 FM_ESPI_PLD_R_EN   PR6C @SCM_LIB.SCM(SCH_1):FM_ESPI_PLD_R_EN
 J12 FM_THROTTLE_R_N   PR6D @SCM_LIB.SCM(SCH_1):FM_THROTTLE_R_N
 J16 FM_PMBUS_ALERT_EN   PR7C @SCM_LIB.SCM(SCH_1):FM_PMBUS_ALERT_EN
 J14 H_CPU0_PROCHOT_LVC1_R_N   PR7D @SCM_LIB.SCM(SCH_1):H_CPU0_PROCHOT_LVC1_R_N
 H11 RST_MB_STBY_R_N   PR9C @SCM_LIB.SCM(SCH_1):RST_MB_STBY_R_N
 J13 FM_ADR_TRIGGER_N   PR9D @SCM_LIB.SCM(SCH_1):FM_ADR_TRIGGER_N
 G15     NC   PR5A     NC
 G14     NC   PR5B     NC
 M13 VCCIO1 VCCIO1_M13 @SCM_LIB.SCM(SCH_1):VCCIO1
 J10 VCCIO1 VCCIO1_J10 @SCM_LIB.SCM(SCH_1):VCCIO1
 E13 VCCIO1 VCCIO1_E13 @SCM_LIB.SCM(SCH_1):VCCIO1
 H10 VCCIO1 VCCIO1_H10 @SCM_LIB.SCM(SCH_1):VCCIO1

Q_RES_0402LF-0,5%,1/16W,CHIP,CA  I2  R453
   1 SMB_BMC_ALERT3_N      A @SCM_LIB.SCM(SCH_1):SMB_BMC_ALERT3_N
   2 SMB_BMC_ALERT3_R1_N      B @SCM_LIB.SCM(SCH_1):SMB_BMC_ALERT3_R1_N

Q_RES_0402LF-0,5%,1/16W,CHIP,CA  I3  R454
   1 SMB_BMC_ALERT4_N      A @SCM_LIB.SCM(SCH_1):SMB_BMC_ALERT4_N
   2 SMB_BMC_ALERT4_R1_N      B @SCM_LIB.SCM(SCH_1):SMB_BMC_ALERT4_R1_N

Q_RES_0402LF-0,5%,1/16W,CHIP,CA  I4  R456
   1 SMB_BMC_ALERT9_N      A @SCM_LIB.SCM(SCH_1):SMB_BMC_ALERT9_N
   2 SMB_BMC_ALERT9_R1_N      B @SCM_LIB.SCM(SCH_1):SMB_BMC_ALERT9_R1_N

Q_RES_0402LF-0,5%,1/16W,CHIP,CA  I5  R457
   1 SMB_BMC_ALERT10_N      A @SCM_LIB.SCM(SCH_1):SMB_BMC_ALERT10_N
   2 SMB_BMC_ALERT10_R1_N      B @SCM_LIB.SCM(SCH_1):SMB_BMC_ALERT10_R1_N

Q_RES_0402LF-0,5%,1/16W,CHIP,CA  I76  R574
   1 SMB_BMC_ALERT16_N      A @SCM_LIB.SCM(SCH_1):SMB_BMC_ALERT16_N
   2 SMB_BMC_ALERT16_R2_N      B @SCM_LIB.SCM(SCH_1):SMB_BMC_ALERT16_R2_N

Q_RES_0402LF-0,5%,1/16W,CHIP,CA  I80  R51
   1 H_CPU0_PROCHOT_LVC1_N      A @SCM_LIB.SCM(SCH_1):H_CPU0_PROCHOT_LVC1_N
   2 H_CPU0_PROCHOT_LVC1_R_N      B @SCM_LIB.SCM(SCH_1):H_CPU0_PROCHOT_LVC1_R_N

Q_RES_0402LF-0,5%,1/16W,CHIP,CA  I88  R271
   1 RST_BMC_SELF_HW      A @SCM_LIB.SCM(SCH_1):RST_BMC_SELF_HW
   2 RST_BMC_SELF_HW_R2      B @SCM_LIB.SCM(SCH_1):RST_BMC_SELF_HW_R2

Q_RES_0402LF-0,5%,1/16W,CHIP,CA  I95  R320
   1 PWRGD_P2V5_AUX_R1      A @SCM_LIB.SCM(SCH_1):PWRGD_P2V5_AUX_R1
   2 PWRGD_P2V5_AUX      B @SCM_LIB.SCM(SCH_1):PWRGD_P2V5_AUX

Q_RES_0402LF-0,5%,1/16W,CHIP,CA  I98  R318
   1 PWRGD_P3V3_AUX_R1      A @SCM_LIB.SCM(SCH_1):PWRGD_P3V3_AUX_R1
   2 PWRGD_P3V3_AUX      B @SCM_LIB.SCM(SCH_1):PWRGD_P3V3_AUX

Q_RES_0402LF-0,5%,1/16W,CHIP,CA  I99  R317
   1 PWR_LED_CPLD      A @SCM_LIB.SCM(SCH_1):PWR_LED_CPLD
   2 PWR_LED      B @SCM_LIB.SCM(SCH_1):PWR_LED

Q_RES_0402LF-0,5%,1/16W,CHIP,CA  I100  R432
   1 FM_PWR_R_BTN      A @SCM_LIB.SCM(SCH_1):FM_PWR_R_BTN
   2 FM_PWR_BTN      B @SCM_LIB.SCM(SCH_1):FM_PWR_BTN

Q_RES_0402LF-0,5%,1/16W,EMPTY,A  I131  R463
   1 AC_PWR_BTN_R1_N      A @SCM_LIB.SCM(SCH_1):AC_PWR_BTN_R1_N
   2 AC_PWR_BTN_R2_N      B @SCM_LIB.SCM(SCH_1):AC_PWR_BTN_R2_N

Q_RES_0402LF-4.7K,1%,1/16W,EMPA  I136  R472
   1 P3V3_AUX      A @SCM_LIB.SCM(SCH_1):P3V3_AUX
   2 AC_PWR_BTN_R1_N      B @SCM_LIB.SCM(SCH_1):AC_PWR_BTN_R1_N

Q_RES_0402LF-33.2,1%,1/16W,CHIA  I137  R773
   1 FM_SLPS3_GF_N      A @SCM_LIB.SCM(SCH_1):FM_SLPS3_GF_N
   2 FM_SLPS3_GF_R_N      B @SCM_LIB.SCM(SCH_1):FM_SLPS3_GF_R_N

Q_RES_0402LF-33.2,1%,1/16W,CHIA  I138  R825
   1 RST_ROT_CPU_N      A @SCM_LIB.SCM(SCH_1):RST_ROT_CPU_N
   2 RST_ROT_CPU_R_N      B @SCM_LIB.SCM(SCH_1):RST_ROT_CPU_R_N

Q_RES_0402LF-33.2,1%,1/16W,CHIA  I139  R833
   1 FM_ESPI_PLD_EN      A @SCM_LIB.SCM(SCH_1):FM_ESPI_PLD_EN
   2 FM_ESPI_PLD_R_EN      B @SCM_LIB.SCM(SCH_1):FM_ESPI_PLD_R_EN

Q_RES_0402LF-33.2,1%,1/16W,CHIA  I140  R769
   1 FM_THROTTLE_N      A @SCM_LIB.SCM(SCH_1):FM_THROTTLE_N
   2 FM_THROTTLE_R_N      B @SCM_LIB.SCM(SCH_1):FM_THROTTLE_R_N

Q_RES_0402LF-33.2,1%,1/16W,CHIA  I141  R263
   1 RST_MB_STBY_N      A @SCM_LIB.SCM(SCH_1):RST_MB_STBY_N
   2 RST_MB_STBY_R_N      B @SCM_LIB.SCM(SCH_1):RST_MB_STBY_R_N

Q_RES_0402LF-33.2,1%,1/16W,CHIA  I142  R841
   1 PWRGD_SYS_PWROK_PLD      A @SCM_LIB.SCM(SCH_1):PWRGD_SYS_PWROK_PLD
   2 PWRGD_SYS_PWROK      B @SCM_LIB.SCM(SCH_1):PWRGD_SYS_PWROK

Q_RES_0402LF-33.2,1%,1/16W,CHIA  I143  R638
   1 RST_BMC_HW_R      A @SCM_LIB.SCM(SCH_1):RST_BMC_HW_R
   2 RST_BMC_HW      B @SCM_LIB.SCM(SCH_1):RST_BMC_HW

Q_RES_0402LF-33.2,1%,1/16W,CHIA  I144  R536
   1 BMC_CPLD_GPIO_12_R2      A @SCM_LIB.SCM(SCH_1):BMC_CPLD_GPIO_12_R2
   2 BMC_CPLD_GPIO_12      B @SCM_LIB.SCM(SCH_1):BMC_CPLD_GPIO_12

Q_RES_0402LF-33.2,1%,1/16W,CHIA  I145  R537
   1 BMC_CPLD_GPIO_13_R2      A @SCM_LIB.SCM(SCH_1):BMC_CPLD_GPIO_13_R2
   2 BMC_CPLD_GPIO_13      B @SCM_LIB.SCM(SCH_1):BMC_CPLD_GPIO_13

Q_RES_0402LF-33.2,1%,1/16W,EMPA  I146  R531
   1 BMC_CPLD_GPIO_8_R2      A @SCM_LIB.SCM(SCH_1):BMC_CPLD_GPIO_8_R2
   2 BMC_CPLD_GPIO_8      B @SCM_LIB.SCM(SCH_1):BMC_CPLD_GPIO_8

Q_RES_0402LF-33.2,1%,1/16W,EMPA  I147  R526
   1 BMC_CPLD_GPIO_7_R2      A @SCM_LIB.SCM(SCH_1):BMC_CPLD_GPIO_7_R2
   2 BMC_CPLD_GPIO_7      B @SCM_LIB.SCM(SCH_1):BMC_CPLD_GPIO_7

Q_RES_0402LF-33.2,1%,1/16W,CHIA  I148  R691
   1 RST_SGPIO_RESET_R_N      A @SCM_LIB.SCM(SCH_1):RST_SGPIO_RESET_R_N
   2 RST_SGPIO_RESET_N      B @SCM_LIB.SCM(SCH_1):RST_SGPIO_RESET_N

Q_RES_0402LF-33.2,1%,1/16W,CHIA  I149  R690
   1 IRQ_SGPIO_R_N      A @SCM_LIB.SCM(SCH_1):IRQ_SGPIO_R_N
   2 IRQ_SGPIO_N      B @SCM_LIB.SCM(SCH_1):IRQ_SGPIO_N

Q_DIODE_SMLF-SDMK0340L-7-F,EMPA  I150  D23
   1 PWRGD_P5V_AUX      1 @SCM_LIB.SCM(SCH_1):PWRGD_P5V_AUX
   2 PWRGD_P5V_AUX_R1      2 @SCM_LIB.SCM(SCH_1):PWRGD_P5V_AUX_R1

Q_RES_0402LF-4.7K,1%,1/16W,CHIA  I151  R886
   1 P3V3_AUX      A @SCM_LIB.SCM(SCH_1):P3V3_AUX
   2 PWRGD_P5V_AUX_R1      B @SCM_LIB.SCM(SCH_1):PWRGD_P5V_AUX_R1


DRAWING: @SCM_LIB.SCM(SCH_1):PAGE36 

LCMXO3LF2100C5BG256C-LCMXO3LF-A  I1  U25
  M7 CLK_GEN2_BMC_RC_OE_N   PB9C @SCM_LIB.SCM(SCH_1):CLK_GEN2_BMC_RC_OE_N
  N7 IRQ_SML0_ALERT_R_N   PB9D @SCM_LIB.SCM(SCH_1):IRQ_SML0_ALERT_R_N
  M6 BMC_MONITER  PB11C @SCM_LIB.SCM(SCH_1):BMC_MONITER
  L8 FM_PFR_DSW_PWROK_N  PB11D @SCM_LIB.SCM(SCH_1):FM_PFR_DSW_PWROK_N
  T7 RST_PFR_OVR_RTC_R PB11A||PCLKT2_0 @SCM_LIB.SCM(SCH_1):RST_PFR_OVR_RTC_R
  R8 NC_FM_PFR_UPDATE_N PB11B||PCLKC2_0 @SCM_LIB.SCM(SCH_1):NC_FM_PFR_UPDATE_N
  P8 GPU_FPGA_RST_N  PB12A @SCM_LIB.SCM(SCH_1):GPU_FPGA_RST_N
  T8 FM_JTAG_TCK_MUX_BMC_SEL  PB12B @SCM_LIB.SCM(SCH_1):FM_JTAG_TCK_MUX_BMC_SEL
  N8 CLK_BUF1_GPU_FPGA_OE_R_N  PB12C @SCM_LIB.SCM(SCH_1):CLK_BUF1_GPU_FPGA_OE_R_N
  L9 FM_BMC_CPU_FBRK_OUT_R_N  PB12D @SCM_LIB.SCM(SCH_1):FM_BMC_CPU_FBRK_OUT_R_N
  M8 PWRGD_P1V8_AUX_R1  PB16C @SCM_LIB.SCM(SCH_1):PWRGD_P1V8_AUX_R1
  N9 PWRGD_P3V3_RGM_R1  PB16D @SCM_LIB.SCM(SCH_1):PWRGD_P3V3_RGM_R1
  T9 PWRGD_P1V2_AUX_R1 PB16A||PCLKT2_1 @SCM_LIB.SCM(SCH_1):PWRGD_P1V2_AUX_R1
  P9 PWRGD_P1V0_AUX_R1 PB16B||PCLKC2_1 @SCM_LIB.SCM(SCH_1):PWRGD_P1V0_AUX_R1
  R9     NC  PB18A     NC
 T10     NC  PB18B     NC
  M9 FM_UARTSW_LSB_R_N  PB18C @SCM_LIB.SCM(SCH_1):FM_UARTSW_LSB_R_N
 L10 FM_UARTSW_MSB_R_N  PB18D @SCM_LIB.SCM(SCH_1):FM_UARTSW_MSB_R_N
 N10     NC  PB19C     NC
 M11     NC  PB19D     NC
 P10     NC  PB19A     NC
 R10     NC  PB19B     NC
 T11     NC  PB21A     NC
 P11     NC  PB21B     NC
 M10 PU_FPGA_NCONFIG  PB21C @SCM_LIB.SCM(SCH_1):PU_FPGA_NCONFIG
 N11     NC  PB21D     NC
 R13     NC  PB22C     NC
 T14     NC  PB22D     NC
 R11     NC  PB22A     NC
 T12     NC  PB22B     NC
 P12     NC  PB24A     NC
 T13     NC  PB24B     NC
 R12 PU_PB25A PB25A||SN @SCM_LIB.SCM(SCH_1):PU_PB25A
 P13     NC PB25B||SI||SISPI     NC
 T15 SMB_BMC_MM16_R4_SCL  PB25C @SCM_LIB.SCM(SCH_1):SMB_BMC_MM16_R4_SCL
 R14 SMB_BMC_MM16_R4_SDA  PB25D @SCM_LIB.SCM(SCH_1):SMB_BMC_MM16_R4_SDA
  P4 FM_P12V_HSC_ENABLE_R2   PB3A @SCM_LIB.SCM(SCH_1):FM_P12V_HSC_ENABLE_R2
  T4     NC   PB3B     NC
  T2 FM_SOL_UART_CH_SEL_R2   PB3C @SCM_LIB.SCM(SCH_1):FM_SOL_UART_CH_SEL_R2
  R3 PWRGD_DSW_PWROK_R2   PB3D @SCM_LIB.SCM(SCH_1):PWRGD_DSW_PWROK_R2
  R5 FM_DEBUG_PORT_R2_PRSNT_N PB5A||CSSPIN @SCM_LIB.SCM(SCH_1):FM_DEBUG_PORT_R2_PRSNT_N
  P5 TP_PLD_C13   PB5B @SCM_LIB.SCM(SCH_1):TP_PLD_C13
  T3 RST_WDTRST_PLD_R2_N   PB6C @SCM_LIB.SCM(SCH_1):RST_WDTRST_PLD_R2_N
  R4 FM_BMC_SUSACK_R2_N   PB6D @SCM_LIB.SCM(SCH_1):FM_BMC_SUSACK_R2_N
  T5 IRQ_PCH_TPM_SPI_R2_N   PB6A @SCM_LIB.SCM(SCH_1):IRQ_PCH_TPM_SPI_R2_N
  R6 FM_BMC_CRASHLOG_TRIG_R2_N   PB6B @SCM_LIB.SCM(SCH_1):FM_BMC_CRASHLOG_TRIG_R2_N
  N6 FM_BMC_DEBUG_SW_R2_N   PB8C @SCM_LIB.SCM(SCH_1):FM_BMC_DEBUG_SW_R2_N
  L7 NC_FM_PFR_NO_SERVICE_ACT_N   PB8D @SCM_LIB.SCM(SCH_1):NC_FM_PFR_NO_SERVICE_ACT_N
  P6 FM_HDD_LED_N PB8A||MCLK||CCLK @SCM_LIB.SCM(SCH_1):FM_HDD_LED_N
  T6 FM_PCH_BEEP_LED PB8B||SO||SPISO @SCM_LIB.SCM(SCH_1):FM_PCH_BEEP_LED
  R7 GPU_NVS_PWR_BRAKE_R_N   PB9A @SCM_LIB.SCM(SCH_1):GPU_NVS_PWR_BRAKE_R_N
  P7 GPU_WP_HW_CTRL_R_N   PB9B @SCM_LIB.SCM(SCH_1):GPU_WP_HW_CTRL_R_N
  K8 VCCIO2 VCCIO2_K8 @SCM_LIB.SCM(SCH_1):VCCIO2
  K9 VCCIO2 VCCIO2_K9 @SCM_LIB.SCM(SCH_1):VCCIO2
 N12 VCCIO2 VCCIO2_N12 @SCM_LIB.SCM(SCH_1):VCCIO2
  N5 VCCIO2 VCCIO2_N5 @SCM_LIB.SCM(SCH_1):VCCIO2

Q_RES_0402LF-0,5%,1/16W,CHIP,CA  I2  R575
   1 FM_P12V_HSC_ENABLE      A @SCM_LIB.SCM(SCH_1):FM_P12V_HSC_ENABLE
   2 FM_P12V_HSC_ENABLE_R2      B @SCM_LIB.SCM(SCH_1):FM_P12V_HSC_ENABLE_R2

Q_RES_0402LF-0,5%,1/16W,CHIP,CA  I3  R577
   1 FM_SOL_UART_CH_SEL      A @SCM_LIB.SCM(SCH_1):FM_SOL_UART_CH_SEL
   2 FM_SOL_UART_CH_SEL_R2      B @SCM_LIB.SCM(SCH_1):FM_SOL_UART_CH_SEL_R2

Q_RES_0402LF-0,5%,1/16W,CHIP,CA  I7  R579
   1 FM_DEBUG_PORT_PRSNT_N      A @SCM_LIB.SCM(SCH_1):FM_DEBUG_PORT_PRSNT_N
   2 FM_DEBUG_PORT_R2_PRSNT_N      B @SCM_LIB.SCM(SCH_1):FM_DEBUG_PORT_R2_PRSNT_N

Q_RES_0402LF-0,5%,1/16W,CHIP,CA  I8  R578
   1 PWRGD_DSW_PWROK      A @SCM_LIB.SCM(SCH_1):PWRGD_DSW_PWROK
   2 PWRGD_DSW_PWROK_R2      B @SCM_LIB.SCM(SCH_1):PWRGD_DSW_PWROK_R2

Q_RES_0402LF-0,5%,1/16W,CHIP,CA  I9  R747
   1 FM_BMC_CRASHLOG_TRIG_N      A @SCM_LIB.SCM(SCH_1):FM_BMC_CRASHLOG_TRIG_N
   2 FM_BMC_CRASHLOG_TRIG_R2_N      B @SCM_LIB.SCM(SCH_1):FM_BMC_CRASHLOG_TRIG_R2_N

Q_RES_0402LF-0,5%,1/16W,CHIP,CA  I10  R746
   1 IRQ_PCH_TPM_SPI_N      A @SCM_LIB.SCM(SCH_1):IRQ_PCH_TPM_SPI_N
   2 IRQ_PCH_TPM_SPI_R2_N      B @SCM_LIB.SCM(SCH_1):IRQ_PCH_TPM_SPI_R2_N

Q_RES_0402LF-0,5%,1/16W,CHIP,CA  I33  R321
   1 PWRGD_P1V8_AUX_R1      A @SCM_LIB.SCM(SCH_1):PWRGD_P1V8_AUX_R1
   2 PWRGD_P1V8_AUX      B @SCM_LIB.SCM(SCH_1):PWRGD_P1V8_AUX

Q_RES_0402LF-0,5%,1/16W,CHIP,CA  I34  R323
   1 PWRGD_P1V2_AUX_R1      A @SCM_LIB.SCM(SCH_1):PWRGD_P1V2_AUX_R1
   2 PWRGD_P1V2_AUX      B @SCM_LIB.SCM(SCH_1):PWRGD_P1V2_AUX

Q_RES_0402LF-0,5%,1/16W,CHIP,CA  I35  R322
   1 PWRGD_P3V3_RGM_R1      A @SCM_LIB.SCM(SCH_1):PWRGD_P3V3_RGM_R1
   2 PWRGD_P3V3_RGM      B @SCM_LIB.SCM(SCH_1):PWRGD_P3V3_RGM

Q_RES_0402LF-0,5%,1/16W,CHIP,CA  I36  R379
   1 PWRGD_P1V0_AUX_R1      A @SCM_LIB.SCM(SCH_1):PWRGD_P1V0_AUX_R1
   2 PWRGD_P1V0_AUX      B @SCM_LIB.SCM(SCH_1):PWRGD_P1V0_AUX

Q_RES_0402LF-0,5%,1/16W,CHIP,CA  I42  R898
   1 FM_UARTSW_LSB_R_N      A @SCM_LIB.SCM(SCH_1):FM_UARTSW_LSB_R_N
   2 FM_UARTSW_LSB_N      B @SCM_LIB.SCM(SCH_1):FM_UARTSW_LSB_N

Q_RES_0402LF-0,5%,1/16W,CHIP,CA  I43  R899
   1 FM_UARTSW_MSB_R_N      A @SCM_LIB.SCM(SCH_1):FM_UARTSW_MSB_R_N
   2 FM_UARTSW_MSB_N      B @SCM_LIB.SCM(SCH_1):FM_UARTSW_MSB_N

Q_RES_0402LF-0,5%,1/16W,CHIP,CA  I46  R220
   1 FM_BMC_UARTSW_MSB_N      A @SCM_LIB.SCM(SCH_1):FM_BMC_UARTSW_MSB_N
   2 FM_UARTSW_MSB_N      B @SCM_LIB.SCM(SCH_1):FM_UARTSW_MSB_N

Q_RES_0402LF-0,5%,1/16W,CHIP,CA  I47  R134
   1 FM_BMC_UARTSW_LSB_N      A @SCM_LIB.SCM(SCH_1):FM_BMC_UARTSW_LSB_N
   2 FM_UARTSW_LSB_N      B @SCM_LIB.SCM(SCH_1):FM_UARTSW_LSB_N

Q_RES_0402LF-10K,1%,1/16W,CHIPA  I50  R288
   1 VCCIO2      A @SCM_LIB.SCM(SCH_1):VCCIO2
   2 PU_PB25A      B @SCM_LIB.SCM(SCH_1):PU_PB25A

Q_RES_0402LF-0,5%,1/16W,CHIP,CA  I57  R114
   1 SMB_BMC_MM16_R4_SDA      A @SCM_LIB.SCM(SCH_1):SMB_BMC_MM16_R4_SDA
   2 SMB_BMC_MM16_R5_SDA      B @SCM_LIB.SCM(SCH_1):SMB_BMC_MM16_R5_SDA

Q_RES_0402LF-0,5%,1/16W,CHIP,CA  I58  R105
   1 SMB_BMC_MM16_R4_SCL      A @SCM_LIB.SCM(SCH_1):SMB_BMC_MM16_R4_SCL
   2 SMB_BMC_MM16_R5_SCL      B @SCM_LIB.SCM(SCH_1):SMB_BMC_MM16_R5_SCL

Q_RES_0402LF-0,5%,1/16W,CHIP,CA  I78  R748
   1 PU_FPGA_NCONFIG      A @SCM_LIB.SCM(SCH_1):PU_FPGA_NCONFIG
   2 RST_ROT_CPU_N      B @SCM_LIB.SCM(SCH_1):RST_ROT_CPU_N

Q_RES_0402LF-33.2,1%,1/16W,CHIA  I80  R635
   1 RST_WDTRST_PLD_N      A @SCM_LIB.SCM(SCH_1):RST_WDTRST_PLD_N
   2 RST_WDTRST_PLD_R2_N      B @SCM_LIB.SCM(SCH_1):RST_WDTRST_PLD_R2_N

Q_RES_0402LF-33.2,1%,1/16W,CHIA  I81  R445
   1 FM_BMC_SUSACK_N      A @SCM_LIB.SCM(SCH_1):FM_BMC_SUSACK_N
   2 FM_BMC_SUSACK_R2_N      B @SCM_LIB.SCM(SCH_1):FM_BMC_SUSACK_R2_N

Q_RES_0402LF-33.2,1%,1/16W,CHIA  I82  R750
   1 FM_BMC_DEBUG_SW_N      A @SCM_LIB.SCM(SCH_1):FM_BMC_DEBUG_SW_N
   2 FM_BMC_DEBUG_SW_R2_N      B @SCM_LIB.SCM(SCH_1):FM_BMC_DEBUG_SW_R2_N


DRAWING: @SCM_LIB.SCM(SCH_1):PAGE37 

LCMXO3LF2100C5BG256C-LCMXO3LF-A  I1  U25
  L1     NC  PL11A     NC
  L3     NC  PL11B     NC
  K4     NC  PL11C     NC
  L5     NC  PL11D     NC
  K5     NC  PL12C     NC
  L4     NC  PL12D     NC
  L2     NC PL12A||PCLKT3_0     NC
  M1     NC PL12B||PCLKC3_0     NC
  M2     NC  PL14A     NC
  N3     NC  PL14B     NC
  R1     NC  PL14C     NC
  P2     NC  PL14D     NC
  M4 VCCIO3 VCCIO3 @SCM_LIB.SCM(SCH_1):VCCIO3
  N2     NC  PL13C     NC
  P1     NC  PL13D     NC
  M3     NC  PL13A     NC
  N1     NC  PL13B     NC


DRAWING: @SCM_LIB.SCM(SCH_1):PAGE38 

LCMXO3LF2100C5BG256C-LCMXO3LF-A  I1  U25
  G1     NC   PL6A     NC
  H2     NC   PL6B     NC
  H4     NC   PL6C     NC
  J6     NC   PL6D     NC
  H3     NC   PL7A     NC
  H1     NC   PL7B     NC
  J1     NC PL7C||PCLKT4_0     NC
  J3     NC PL7D||PCLKC4_0     NC
  J5     NC  PL10C     NC
  K6     NC  PL10D     NC
  K3     NC  PL10A     NC
  K2     NC  PL10B     NC
  J2     NC   PL9A     NC
  K1     NC   PL9B     NC
  H5     NC   PL9C     NC
  J4     NC   PL9D     NC
  H7 VCCIO4 VCCIO4_H7 @SCM_LIB.SCM(SCH_1):VCCIO4
  J7 VCCIO4 VCCIO4_J7 @SCM_LIB.SCM(SCH_1):VCCIO4


DRAWING: @SCM_LIB.SCM(SCH_1):PAGE39 

LCMXO3LF2100C5BG256C-LCMXO3LF-A  I1  U25
  B1     NC   PL1C     NC
  C2     NC   PL1D     NC
  D3     NC PL1A||L_GPLLT_FB     NC
  D1     NC PL1B||L_GPLLC_FB     NC
  E2     NC PL2A||L_GPLLT_IN     NC
  E3     NC PL2B||L_GPLLC_IN     NC
  C1     NC   PL2C     NC
  D2     NC   PL2D     NC
  E1     NC PL3A||PCLKT5_0     NC
  F2     NC PL3B||PCLKC5_0     NC
  F4     NC   PL3C     NC
  G6     NC   PL3D     NC
  G2     NC   PL5A     NC
  G3     NC   PL5B     NC
  F5     NC   PL5C     NC
  H6     NC   PL5D     NC
  E4 VCCIO5 VCCIO5 @SCM_LIB.SCM(SCH_1):VCCIO5
  G5     NC   PL4C     NC
  G4     NC   PL4D     NC
  F3     NC   PL4A     NC
  F1     NC   PL4B     NC


DRAWING: @SCM_LIB.SCM(SCH_1):PAGE40 

LCMXO3LF2100C5BG256C-LCMXO3LF-A  I1  U25
  B2    GND GND_B2 @SCM_LIB.SCM(SCH_1):GND
 B15    GND GND_B15 @SCM_LIB.SCM(SCH_1):GND
  C3    GND GND_C3 @SCM_LIB.SCM(SCH_1):GND
 C14    GND GND_C14 @SCM_LIB.SCM(SCH_1):GND
  D4    GND GND_D4 @SCM_LIB.SCM(SCH_1):GND
 D13    GND GND_D13 @SCM_LIB.SCM(SCH_1):GND
  E5    GND GND_E5 @SCM_LIB.SCM(SCH_1):GND
 E12    GND GND_E12 @SCM_LIB.SCM(SCH_1):GND
  F6    GND GND_F6 @SCM_LIB.SCM(SCH_1):GND
 F11    GND GND_F11 @SCM_LIB.SCM(SCH_1):GND
  H8    GND GND_H8 @SCM_LIB.SCM(SCH_1):GND
  H9    GND GND_H9 @SCM_LIB.SCM(SCH_1):GND
  J8    GND GND_J8 @SCM_LIB.SCM(SCH_1):GND
  J9    GND GND_J9 @SCM_LIB.SCM(SCH_1):GND
  L6    GND GND_L6 @SCM_LIB.SCM(SCH_1):GND
 L11    GND GND_L11 @SCM_LIB.SCM(SCH_1):GND
  M5    GND GND_M5 @SCM_LIB.SCM(SCH_1):GND
 M12    GND GND_M12 @SCM_LIB.SCM(SCH_1):GND
  N4    GND GND_N4 @SCM_LIB.SCM(SCH_1):GND
 N13    GND GND_N13 @SCM_LIB.SCM(SCH_1):GND
  P3    GND GND_P3 @SCM_LIB.SCM(SCH_1):GND
 P14    GND GND_P14 @SCM_LIB.SCM(SCH_1):GND
  R2    GND GND_R2 @SCM_LIB.SCM(SCH_1):GND
 R15    GND GND_R15 @SCM_LIB.SCM(SCH_1):GND
  A2     NC    NC1     NC
 T16 PVCCA_AUX_PLD VCC_T16 @SCM_LIB.SCM(SCH_1):PVCCA_AUX_PLD
  T1 PVCCA_AUX_PLD VCC_T1 @SCM_LIB.SCM(SCH_1):PVCCA_AUX_PLD
 K10 PVCCA_AUX_PLD VCC_K10 @SCM_LIB.SCM(SCH_1):PVCCA_AUX_PLD
  K7 PVCCA_AUX_PLD VCC_K7 @SCM_LIB.SCM(SCH_1):PVCCA_AUX_PLD
 G10 PVCCA_AUX_PLD VCC_G10 @SCM_LIB.SCM(SCH_1):PVCCA_AUX_PLD
  G7 PVCCA_AUX_PLD VCC_G7 @SCM_LIB.SCM(SCH_1):PVCCA_AUX_PLD
 A16 PVCCA_AUX_PLD VCC_A16 @SCM_LIB.SCM(SCH_1):PVCCA_AUX_PLD
  A1 PVCCA_AUX_PLD VCC_A1 @SCM_LIB.SCM(SCH_1):PVCCA_AUX_PLD


DRAWING: @SCM_LIB.SCM(SCH_1):PAGE41 

Q_CAP_0402-0.1UF,25V,10%,X7R,CA  I1  C242
   1 VCCIO0      A @SCM_LIB.SCM(SCH_1):VCCIO0
   2    GND      B @SCM_LIB.SCM(SCH_1):GND

Q_CAP_C0402-1UF,25V,10%,X6S,CHA  I8  C166
   1 VCCIO0      A @SCM_LIB.SCM(SCH_1):VCCIO0
   2    GND      B @SCM_LIB.SCM(SCH_1):GND

Q_RES_0402LF-0,5%,1/16W,CHIP,CA  I71  R305
   1 P3V3_AUX      A @SCM_LIB.SCM(SCH_1):P3V3_AUX
   2 VCCIO0      B @SCM_LIB.SCM(SCH_1):VCCIO0

Q_RES_0402LF-0,5%,1/16W,CHIP,CA  I72  R525
   1 P3V3_AUX      A @SCM_LIB.SCM(SCH_1):P3V3_AUX
   2 VCCIO1      B @SCM_LIB.SCM(SCH_1):VCCIO1

Q_RES_0402LF-0,5%,1/16W,CHIP,CA  I73  R304
   1 P3V3_AUX      A @SCM_LIB.SCM(SCH_1):P3V3_AUX
   2 VCCIO2      B @SCM_LIB.SCM(SCH_1):VCCIO2

Q_RES_0402LF-0,5%,1/16W,CHIP,CA  I74  R308
   1 P3V3_AUX      A @SCM_LIB.SCM(SCH_1):P3V3_AUX
   2 VCCIO3      B @SCM_LIB.SCM(SCH_1):VCCIO3

Q_RES_0402LF-0,5%,1/16W,CHIP,CA  I75  R301
   1 P3V3_AUX      A @SCM_LIB.SCM(SCH_1):P3V3_AUX
   2 VCCIO5      B @SCM_LIB.SCM(SCH_1):VCCIO5

Q_RES_0402LF-0,5%,1/16W,CHIP,CA  I76  R307
   1 P3V3_AUX      A @SCM_LIB.SCM(SCH_1):P3V3_AUX
   2 VCCIO4      B @SCM_LIB.SCM(SCH_1):VCCIO4

Q_CAP_0402-0.1UF,25V,10%,X7R,CA  I77  C247
   1 VCCIO0      A @SCM_LIB.SCM(SCH_1):VCCIO0
   2    GND      B @SCM_LIB.SCM(SCH_1):GND

Q_CAP_0402-0.1UF,25V,10%,X7R,CA  I78  C189
   1 VCCIO0      A @SCM_LIB.SCM(SCH_1):VCCIO0
   2    GND      B @SCM_LIB.SCM(SCH_1):GND

Q_CAP_0402-0.1UF,25V,10%,X7R,CA  I79  C261
   1 VCCIO0      A @SCM_LIB.SCM(SCH_1):VCCIO0
   2    GND      B @SCM_LIB.SCM(SCH_1):GND

Q_CAP_0402-0.1UF,25V,10%,X7R,CA  I80  C167
   1 VCCIO1      A @SCM_LIB.SCM(SCH_1):VCCIO1
   2    GND      B @SCM_LIB.SCM(SCH_1):GND

Q_CAP_0402-0.1UF,25V,10%,X7R,CA  I81  C243
   1 VCCIO1      A @SCM_LIB.SCM(SCH_1):VCCIO1
   2    GND      B @SCM_LIB.SCM(SCH_1):GND

Q_CAP_0402-0.1UF,25V,10%,X7R,CA  I82  C254
   1 VCCIO1      A @SCM_LIB.SCM(SCH_1):VCCIO1
   2    GND      B @SCM_LIB.SCM(SCH_1):GND

Q_CAP_0402-0.1UF,25V,10%,X7R,CA  I83  C141
   1 VCCIO1      A @SCM_LIB.SCM(SCH_1):VCCIO1
   2    GND      B @SCM_LIB.SCM(SCH_1):GND

Q_CAP_0402-0.1UF,25V,10%,X7R,CA  I84  C187
   1 VCCIO2      A @SCM_LIB.SCM(SCH_1):VCCIO2
   2    GND      B @SCM_LIB.SCM(SCH_1):GND

Q_CAP_0402-0.1UF,25V,10%,X7R,CA  I85  C245
   1 VCCIO2      A @SCM_LIB.SCM(SCH_1):VCCIO2
   2    GND      B @SCM_LIB.SCM(SCH_1):GND

Q_CAP_0402-0.1UF,25V,10%,X7R,CA  I86  C188
   1 VCCIO2      A @SCM_LIB.SCM(SCH_1):VCCIO2
   2    GND      B @SCM_LIB.SCM(SCH_1):GND

Q_CAP_0402-0.1UF,25V,10%,X7R,CA  I87  C260
   1 VCCIO2      A @SCM_LIB.SCM(SCH_1):VCCIO2
   2    GND      B @SCM_LIB.SCM(SCH_1):GND

Q_CAP_0402-0.1UF,25V,10%,X7R,CA  I88  C152
   1 VCCIO3      A @SCM_LIB.SCM(SCH_1):VCCIO3
   2    GND      B @SCM_LIB.SCM(SCH_1):GND

Q_CAP_0402-0.1UF,25V,10%,X7R,CA  I89  C160
   1 VCCIO5      A @SCM_LIB.SCM(SCH_1):VCCIO5
   2    GND      B @SCM_LIB.SCM(SCH_1):GND

Q_CAP_0402-0.1UF,25V,10%,X7R,CA  I90  C220
   1 VCCIO4      A @SCM_LIB.SCM(SCH_1):VCCIO4
   2    GND      B @SCM_LIB.SCM(SCH_1):GND

Q_CAP_0402-0.1UF,25V,10%,X7R,CA  I91  C162
   1 VCCIO4      A @SCM_LIB.SCM(SCH_1):VCCIO4
   2    GND      B @SCM_LIB.SCM(SCH_1):GND

Q_CAP_C0402-1UF,25V,10%,X6S,CHA  I92  C164
   1 VCCIO1      A @SCM_LIB.SCM(SCH_1):VCCIO1
   2    GND      B @SCM_LIB.SCM(SCH_1):GND

Q_CAP_C0402-1UF,25V,10%,X6S,CHA  I93  C165
   1 VCCIO2      A @SCM_LIB.SCM(SCH_1):VCCIO2
   2    GND      B @SCM_LIB.SCM(SCH_1):GND

Q_CAP_C0402-1UF,25V,10%,X6S,CHA  I94  C216
   1 VCCIO3      A @SCM_LIB.SCM(SCH_1):VCCIO3
   2    GND      B @SCM_LIB.SCM(SCH_1):GND

Q_CAP_C0402-1UF,25V,10%,X6S,CHA  I95  C218
   1 VCCIO5      A @SCM_LIB.SCM(SCH_1):VCCIO5
   2    GND      B @SCM_LIB.SCM(SCH_1):GND

Q_CAP_C0402-1UF,25V,10%,X6S,CHA  I96  C195
   1 VCCIO4      A @SCM_LIB.SCM(SCH_1):VCCIO4
   2    GND      B @SCM_LIB.SCM(SCH_1):GND

Q_CAP_C0402-1UF,25V,10%,X6S,CHA  I99  C145
   1 P3V3_AUX      A @SCM_LIB.SCM(SCH_1):P3V3_AUX
   2    GND      B @SCM_LIB.SCM(SCH_1):GND

Q_CAP_C0603-10UF,16V,20%,X6S,CA  I101  C194
   1 P3V3_AUX      A @SCM_LIB.SCM(SCH_1):P3V3_AUX
   2    GND      B @SCM_LIB.SCM(SCH_1):GND

Q_INDUCTOR_SMLF-BLM18EG121SN1DA  I107  L19
   2 PVCCA_AUX_PLD      2 @SCM_LIB.SCM(SCH_1):PVCCA_AUX_PLD
   1 P3V3_AUX      1 @SCM_LIB.SCM(SCH_1):P3V3_AUX

Q_CAP_C0402-1UF,25V,10%,X6S,CHA  I108  C176
   1 PVCCA_AUX_PLD      A @SCM_LIB.SCM(SCH_1):PVCCA_AUX_PLD
   2    GND      B @SCM_LIB.SCM(SCH_1):GND

Q_CAP_0402-0.1UF,25V,10%,X7R,CA  I109  C193
   1 PVCCA_AUX_PLD      A @SCM_LIB.SCM(SCH_1):PVCCA_AUX_PLD
   2    GND      B @SCM_LIB.SCM(SCH_1):GND

Q_CAP_0402-0.1UF,25V,10%,X7R,CA  I115  C250
   1 PVCCA_AUX_PLD      A @SCM_LIB.SCM(SCH_1):PVCCA_AUX_PLD
   2    GND      B @SCM_LIB.SCM(SCH_1):GND

Q_CAP_0402-0.1UF,25V,10%,X7R,CA  I116  C190
   1 PVCCA_AUX_PLD      A @SCM_LIB.SCM(SCH_1):PVCCA_AUX_PLD
   2    GND      B @SCM_LIB.SCM(SCH_1):GND

Q_CAP_0402-0.1UF,25V,10%,X7R,CA  I117  C263
   1 PVCCA_AUX_PLD      A @SCM_LIB.SCM(SCH_1):PVCCA_AUX_PLD
   2    GND      B @SCM_LIB.SCM(SCH_1):GND

Q_CAP_0402-0.1UF,25V,10%,X7R,CA  I118  C269
   1 PVCCA_AUX_PLD      A @SCM_LIB.SCM(SCH_1):PVCCA_AUX_PLD
   2    GND      B @SCM_LIB.SCM(SCH_1):GND

Q_CAP_0402-0.1UF,25V,10%,X7R,CA  I119  C266
   1 PVCCA_AUX_PLD      A @SCM_LIB.SCM(SCH_1):PVCCA_AUX_PLD
   2    GND      B @SCM_LIB.SCM(SCH_1):GND

Q_CAP_C0603-10UF,16V,20%,X6S,CA  I122  C163
   1 PVCCA_AUX_PLD      A @SCM_LIB.SCM(SCH_1):PVCCA_AUX_PLD
   2    GND      B @SCM_LIB.SCM(SCH_1):GND

Q_CAP_C0402-0.01UF,50V,10%,EMPA  I123  C286
   1 PVCCA_AUX_PLD      A @SCM_LIB.SCM(SCH_1):PVCCA_AUX_PLD
   2    GND      B @SCM_LIB.SCM(SCH_1):GND

Q_CAP_C0402-0.01UF,50V,10%,EMPA  I124  C285
   1 VCCIO2      A @SCM_LIB.SCM(SCH_1):VCCIO2
   2    GND      B @SCM_LIB.SCM(SCH_1):GND

Q_CAP_C0402-0.01UF,50V,10%,EMPA  I125  C281
   1 VCCIO1      A @SCM_LIB.SCM(SCH_1):VCCIO1
   2    GND      B @SCM_LIB.SCM(SCH_1):GND

Q_CAP_C0402-0.01UF,50V,10%,EMPA  I126  C283
   1 VCCIO0      A @SCM_LIB.SCM(SCH_1):VCCIO0
   2    GND      B @SCM_LIB.SCM(SCH_1):GND


DRAWING: @SCM_LIB.SCM(SCH_1):PAGE42 

Q_RES_0402LF-4.7K,1%,1/16W,CHIA  I7  R627
   1 P3V3_AUX      A @SCM_LIB.SCM(SCH_1):P3V3_AUX
   2 PWRGD_DSW_PWROK      B @SCM_LIB.SCM(SCH_1):PWRGD_DSW_PWROK

Q_RES_0402LF-4.7K,1%,1/16W,CHIA  I13  R621
   1 P3V3_AUX      A @SCM_LIB.SCM(SCH_1):P3V3_AUX
   2 FM_P12V_HSC_ENABLE      B @SCM_LIB.SCM(SCH_1):FM_P12V_HSC_ENABLE

Q_RES_0402LF-4.7K,1%,1/16W,CHIA  I27  R608
   1 P3V3_AUX      A @SCM_LIB.SCM(SCH_1):P3V3_AUX
   2 BMC_CPLD_GPIO_13      B @SCM_LIB.SCM(SCH_1):BMC_CPLD_GPIO_13

Q_RES_0402LF-4.7K,1%,1/16W,CHIA  I29  R607
   1 P3V3_AUX      A @SCM_LIB.SCM(SCH_1):P3V3_AUX
   2 BMC_CPLD_GPIO_12      B @SCM_LIB.SCM(SCH_1):BMC_CPLD_GPIO_12

Q_RES_0402LF-4.7K,1%,1/16W,EMPA  I37  R595
   1 P3V3_AUX      A @SCM_LIB.SCM(SCH_1):P3V3_AUX
   2 BMC_CPLD_GPIO_8      B @SCM_LIB.SCM(SCH_1):BMC_CPLD_GPIO_8

Q_RES_0402LF-4.7K,1%,1/16W,EMPA  I39  R593
   1 P3V3_AUX      A @SCM_LIB.SCM(SCH_1):P3V3_AUX
   2 BMC_CPLD_GPIO_7      B @SCM_LIB.SCM(SCH_1):BMC_CPLD_GPIO_7

Q_RES_0402LF-4.7K,1%,1/16W,EMPA  I53  R641
   1 P3V3_AUX      A @SCM_LIB.SCM(SCH_1):P3V3_AUX
   2 RST_BMC_SELF_HW_R2      B @SCM_LIB.SCM(SCH_1):RST_BMC_SELF_HW_R2

Q_RES_0402LF-4.7K,1%,1/16W,EMPA  I56  R640
   1 P3V3_AUX      A @SCM_LIB.SCM(SCH_1):P3V3_AUX
   2 FM_JTAG_BMC_MUX_SEL      B @SCM_LIB.SCM(SCH_1):FM_JTAG_BMC_MUX_SEL

Q_RES_0402LF-100K,1%,1/16W,CHIA  I58  R642
   1    GND      A @SCM_LIB.SCM(SCH_1):GND
   2 FM_JTAG_BMC_MUX_SEL      B @SCM_LIB.SCM(SCH_1):FM_JTAG_BMC_MUX_SEL

Q_RES_0402LF-4.7K,1%,1/16W,CHIA  I61  R749
   1 P3V3_AUX      A @SCM_LIB.SCM(SCH_1):P3V3_AUX
   2 FM_BMC_CRASHLOG_TRIG_N      B @SCM_LIB.SCM(SCH_1):FM_BMC_CRASHLOG_TRIG_N

Q_RES_0402LF-4.7K,1%,1/16W,CHIA  I63  R835
   1 P3V3_AUX      A @SCM_LIB.SCM(SCH_1):P3V3_AUX
   2 FM_ADR_TRIGGER_N      B @SCM_LIB.SCM(SCH_1):FM_ADR_TRIGGER_N

Q_RES_0402LF-4.7K,1%,1/16W,CHIA  I65  R319
   1 P3V3_AUX      A @SCM_LIB.SCM(SCH_1):P3V3_AUX
   2 BMC_ID_BEEP_SEL      B @SCM_LIB.SCM(SCH_1):BMC_ID_BEEP_SEL

Q_RES_0402LF-4.7K,1%,1/16W,CHIA  I67  R586
   1 P3V3_AUX      A @SCM_LIB.SCM(SCH_1):P3V3_AUX
   2 BMC_CPLD_GPIO_2      B @SCM_LIB.SCM(SCH_1):BMC_CPLD_GPIO_2


DRAWING: @SCM_LIB.SCM(SCH_1):PAGE44 

IDTQS3VH257PAG_SMLF-IDTQS3VH25A  I271  U30
   4 SPI_PCH_MUXED_IO0     YA @SCM_LIB.SCM(SCH_1):SPI_PCH_MUXED_IO0
   7 SPI_PCH_MUXED_IO3     YB @SCM_LIB.SCM(SCH_1):SPI_PCH_MUXED_IO3
   9 SPI_PCH_MUXED_CLK     YC @SCM_LIB.SCM(SCH_1):SPI_PCH_MUXED_CLK
  12 TP_BIOS_MUX0_PIN12     YD @SCM_LIB.SCM(SCH_1):TP_BIOS_MUX0_PIN12
   1 FM_BMC_BIOS_MUX_CS_SPI_R_SEL_0      S @SCM_LIB.SCM(SCH_1):FM_BMC_BIOS_MUX_CS_SPI_R_SEL_0
  15 PD_BIOS_MUX_EN_N     E* @SCM_LIB.SCM(SCH_1):PD_BIOS_MUX_EN_N
   2 SPI_SYS_MUX_MOSI   I_0A @SCM_LIB.SCM(SCH_1):SPI_SYS_MUX_MOSI
   3 SPI_BMC_BIOS_ROM_R_MOSI   I_1A @SCM_LIB.SCM(SCH_1):SPI_BMC_BIOS_ROM_R_MOSI
   6 SPI_BMC_BIOS_ROM_R_IO3   I_1B @SCM_LIB.SCM(SCH_1):SPI_BMC_BIOS_ROM_R_IO3
   5 SPI_SYS_MUX_HOLD_IO3   I_0B @SCM_LIB.SCM(SCH_1):SPI_SYS_MUX_HOLD_IO3
  10 SPI_BMC_BIOS_ROM_R_CLK   I_1C @SCM_LIB.SCM(SCH_1):SPI_BMC_BIOS_ROM_R_CLK
  11 SPI_SYS_MUX_CLK   I_0C @SCM_LIB.SCM(SCH_1):SPI_SYS_MUX_CLK
  14 TP_BIOS_MUX0_PIN14   I_0D @SCM_LIB.SCM(SCH_1):TP_BIOS_MUX0_PIN14
  13 TP_BIOS_MUX0_PIN13   I_1D @SCM_LIB.SCM(SCH_1):TP_BIOS_MUX0_PIN13
   8    GND    GND @SCM_LIB.SCM(SCH_1):GND
  16 P3V3_AUX    VCC @SCM_LIB.SCM(SCH_1):P3V3_AUX

Q_CAP_0402-0.1UF,25V,10%,X7R,CA  I278  C255
   1 P3V3_AUX      A @SCM_LIB.SCM(SCH_1):P3V3_AUX
   2    GND      B @SCM_LIB.SCM(SCH_1):GND

Q_CAP_0402-0.1UF,25V,10%,X7R,CA  I292  C146
   1 P3V3_AUX      A @SCM_LIB.SCM(SCH_1):P3V3_AUX
   2    GND      B @SCM_LIB.SCM(SCH_1):GND

IDTQS3VH257PAG_SMLF-IDTQS3VH25A  I296  U21
   4 SPI_PCH_MUXED_IO2     YA @SCM_LIB.SCM(SCH_1):SPI_PCH_MUXED_IO2
   7 SPI_PCH_MUXED_IO1     YB @SCM_LIB.SCM(SCH_1):SPI_PCH_MUXED_IO1
   9 SPI_PCH_MUXED_CS0_N     YC @SCM_LIB.SCM(SCH_1):SPI_PCH_MUXED_CS0_N
  12 TP_BIOS_MUX1_PIN12     YD @SCM_LIB.SCM(SCH_1):TP_BIOS_MUX1_PIN12
   1 FM_BMC_BIOS_MUX_CS_SPI_R_SEL_0      S @SCM_LIB.SCM(SCH_1):FM_BMC_BIOS_MUX_CS_SPI_R_SEL_0
  15 PD_BIOS_MUX_EN_N     E* @SCM_LIB.SCM(SCH_1):PD_BIOS_MUX_EN_N
   2 SPI_SYS_MUX_WP_IO2   I_0A @SCM_LIB.SCM(SCH_1):SPI_SYS_MUX_WP_IO2
   3 SPI_BMC_BIOS_ROM_R_IO2   I_1A @SCM_LIB.SCM(SCH_1):SPI_BMC_BIOS_ROM_R_IO2
   6 SPI_BMC_BIOS_ROM_R_MISO   I_1B @SCM_LIB.SCM(SCH_1):SPI_BMC_BIOS_ROM_R_MISO
   5 SPI_SYS_MUX_MISO   I_0B @SCM_LIB.SCM(SCH_1):SPI_SYS_MUX_MISO
  10 SPI_BMC_BIOS_SOURCE_CS0_N   I_1C @SCM_LIB.SCM(SCH_1):SPI_BMC_BIOS_SOURCE_CS0_N
  11 SPI_PCH_SECURE_CS0_N   I_0C @SCM_LIB.SCM(SCH_1):SPI_PCH_SECURE_CS0_N
  14 TP_BIOS_MUX1_PIN14   I_0D @SCM_LIB.SCM(SCH_1):TP_BIOS_MUX1_PIN14
  13 TP_BIOS_MUX1_PIN13   I_1D @SCM_LIB.SCM(SCH_1):TP_BIOS_MUX1_PIN13
   8    GND    GND @SCM_LIB.SCM(SCH_1):GND
  16 P3V3_AUX    VCC @SCM_LIB.SCM(SCH_1):P3V3_AUX

Q_RES_0402LF-10K,1%,1/16W,CHIPA  I311  R866
   1 FM_BMC_BIOS_MUX_CS_SPI_R_SEL_0      A @SCM_LIB.SCM(SCH_1):FM_BMC_BIOS_MUX_CS_SPI_R_SEL_0
   2    GND      B @SCM_LIB.SCM(SCH_1):GND

Q_RES_0402LF-2K,1%,1/16W,CHIP,A  I313  R467
   1 PD_BIOS_MUX_EN_N      A @SCM_LIB.SCM(SCH_1):PD_BIOS_MUX_EN_N
   2    GND      B @SCM_LIB.SCM(SCH_1):GND

Q_RES_0402LF-4.7K,1%,1/16W,EMPA  I315  R870
   1 P3V3_AUX      A @SCM_LIB.SCM(SCH_1):P3V3_AUX
   2 PD_BIOS_MUX_EN_N      B @SCM_LIB.SCM(SCH_1):PD_BIOS_MUX_EN_N

Q_RES_0402LF-33.2,1%,1/16W,CHIA  I330  R175
   1 SPI_BMC_BIOS_ROM_MOSI      A @SCM_LIB.SCM(SCH_1):SPI_BMC_BIOS_ROM_MOSI
   2 SPI_BMC_BIOS_ROM_R_MOSI      B @SCM_LIB.SCM(SCH_1):SPI_BMC_BIOS_ROM_R_MOSI

Q_RES_0402LF-33.2,1%,1/16W,CHIA  I331  R174
   1 SPI_BMC_BIOS_ROM_CLK      A @SCM_LIB.SCM(SCH_1):SPI_BMC_BIOS_ROM_CLK
   2 SPI_BMC_BIOS_ROM_R_CLK      B @SCM_LIB.SCM(SCH_1):SPI_BMC_BIOS_ROM_R_CLK

Q_RES_0402LF-33.2,1%,1/16W,CHIA  I332  R176
   1 SPI_BMC_BIOS_ROM_MISO      A @SCM_LIB.SCM(SCH_1):SPI_BMC_BIOS_ROM_MISO
   2 SPI_BMC_BIOS_ROM_R_MISO      B @SCM_LIB.SCM(SCH_1):SPI_BMC_BIOS_ROM_R_MISO

Q_RES_0402LF-33.2,1%,1/16W,CHIA  I333  R724
   1 SPI_BMC_BIOS_ROM_IO2      A @SCM_LIB.SCM(SCH_1):SPI_BMC_BIOS_ROM_IO2
   2 SPI_BMC_BIOS_ROM_R_IO2      B @SCM_LIB.SCM(SCH_1):SPI_BMC_BIOS_ROM_R_IO2

Q_RES_0402LF-33.2,1%,1/16W,CHIA  I334  R725
   1 SPI_BMC_BIOS_ROM_IO3      A @SCM_LIB.SCM(SCH_1):SPI_BMC_BIOS_ROM_IO3
   2 SPI_BMC_BIOS_ROM_R_IO3      B @SCM_LIB.SCM(SCH_1):SPI_BMC_BIOS_ROM_R_IO3

Q_RES_0402LF-0,5%,1/16W,CHIP,CA  I336  R728
   1 SPI_BMC_BIOS_CS0_N      A @SCM_LIB.SCM(SCH_1):SPI_BMC_BIOS_CS0_N
   2 SPI_BMC_BIOS_SOURCE_CS0_N      B @SCM_LIB.SCM(SCH_1):SPI_BMC_BIOS_SOURCE_CS0_N

Q_RES_0402LF-33.2,1%,1/16W,CHIA  I339  R859
   1 SPI_SYS_R_CLK      A @SCM_LIB.SCM(SCH_1):SPI_SYS_R_CLK
   2 SPI_SYS_MUX_CLK      B @SCM_LIB.SCM(SCH_1):SPI_SYS_MUX_CLK

Q_RES_0402LF-33.2,1%,1/16W,CHIA  I342  R864
   1 SPI_SYS_CS0_N      A @SCM_LIB.SCM(SCH_1):SPI_SYS_CS0_N
   2 SPI_PCH_SECURE_CS0_N      B @SCM_LIB.SCM(SCH_1):SPI_PCH_SECURE_CS0_N

Q_RES_0402LF-33.2,1%,1/16W,CHIA  I360  R594
   1 SPI_TPM_CS_N      A @SCM_LIB.SCM(SCH_1):SPI_TPM_CS_N
   2 SPI_TPM_CS_R_N      B @SCM_LIB.SCM(SCH_1):SPI_TPM_CS_R_N

Q_RES_0402LF-22,1%,1/16W,CHIP,A  I362  R860
   1 SPI_SYS_R_MOSI      A @SCM_LIB.SCM(SCH_1):SPI_SYS_R_MOSI
   2 SPI_SYS_MUX_MOSI      B @SCM_LIB.SCM(SCH_1):SPI_SYS_MUX_MOSI

Q_RES_0402LF-22,1%,1/16W,CHIP,A  I363  R861
   1 SPI_SYS_R_MISO      A @SCM_LIB.SCM(SCH_1):SPI_SYS_R_MISO
   2 SPI_SYS_MUX_MISO      B @SCM_LIB.SCM(SCH_1):SPI_SYS_MUX_MISO

Q_RES_0402LF-22,1%,1/16W,CHIP,A  I364  R862
   1 SPI_SYS_WP_R_IO2      A @SCM_LIB.SCM(SCH_1):SPI_SYS_WP_R_IO2
   2 SPI_SYS_MUX_WP_IO2      B @SCM_LIB.SCM(SCH_1):SPI_SYS_MUX_WP_IO2

Q_RES_0402LF-22,1%,1/16W,CHIP,A  I365  R863
   1 SPI_SYS_HOLD_R_IO3      A @SCM_LIB.SCM(SCH_1):SPI_SYS_HOLD_R_IO3
   2 SPI_SYS_MUX_HOLD_IO3      B @SCM_LIB.SCM(SCH_1):SPI_SYS_MUX_HOLD_IO3

Q_RES_0402LF-68.1,1%,1/16W,CHIA  I366  R852
   1 FM_BMC_MUX_CS_SPI_SEL_0      A @SCM_LIB.SCM(SCH_1):FM_BMC_MUX_CS_SPI_SEL_0
   2 FM_BMC_BIOS_MUX_CS_SPI_R_SEL_0      B @SCM_LIB.SCM(SCH_1):FM_BMC_BIOS_MUX_CS_SPI_R_SEL_0


DRAWING: @SCM_LIB.SCM(SCH_1):PAGE45 

Q_RES_0402LF-33.2,1%,1/16W,CHIA  I19  R486
   1 SPI_PCH_MUXED_IO3      A @SCM_LIB.SCM(SCH_1):SPI_PCH_MUXED_IO3
   2 SPI_PCH_IO3_FLASH_R1      B @SCM_LIB.SCM(SCH_1):SPI_PCH_IO3_FLASH_R1

Q_RES_0402LF-33.2,1%,1/16W,CHIA  I20  R485
   1 SPI_PCH_MUXED_CS0_N      A @SCM_LIB.SCM(SCH_1):SPI_PCH_MUXED_CS0_N
   2 SPI_PCH_CS0_FLASH_R1_N      B @SCM_LIB.SCM(SCH_1):SPI_PCH_CS0_FLASH_R1_N

Q_RES_0402LF-33.2,1%,1/16W,CHIA  I21  R484
   1 SPI_PCH_MUXED_IO1      A @SCM_LIB.SCM(SCH_1):SPI_PCH_MUXED_IO1
   2 SPI_PCH_IO1_FLASH_R1      B @SCM_LIB.SCM(SCH_1):SPI_PCH_IO1_FLASH_R1

Q_RES_0402LF-33.2,1%,1/16W,CHIA  I22  R482
   1 SPI_PCH_MUXED_IO0      A @SCM_LIB.SCM(SCH_1):SPI_PCH_MUXED_IO0
   2 SPI_PCH_IO0_FLASH_R1      B @SCM_LIB.SCM(SCH_1):SPI_PCH_IO0_FLASH_R1

Q_RES_0402LF-33.2,1%,1/16W,CHIA  I23  R483
   1 SPI_PCH_MUXED_IO2      A @SCM_LIB.SCM(SCH_1):SPI_PCH_MUXED_IO2
   2 SPI_PCH_IO2_FLASH_R1      B @SCM_LIB.SCM(SCH_1):SPI_PCH_IO2_FLASH_R1

Q_RES_0402LF-33.2,1%,1/16W,CHIA  I24  R481
   1 SPI_PCH_MUXED_CLK      A @SCM_LIB.SCM(SCH_1):SPI_PCH_MUXED_CLK
   2 SPI_PCH_CLK_FLASH_R1      B @SCM_LIB.SCM(SCH_1):SPI_PCH_CLK_FLASH_R1

Q_RES_0402LF-4.7K,1%,1/16W,CHIA  I33  R488
   1 P3V3_AUX      A @SCM_LIB.SCM(SCH_1):P3V3_AUX
   2 SPI_PCH_IO2_FLASH_R1      B @SCM_LIB.SCM(SCH_1):SPI_PCH_IO2_FLASH_R1

Q_RES_0402LF-4.7K,1%,1/16W,CHIA  I34  R490
   1 P3V3_AUX      A @SCM_LIB.SCM(SCH_1):P3V3_AUX
   2 SPI_PCH_CS0_FLASH_R1_N      B @SCM_LIB.SCM(SCH_1):SPI_PCH_CS0_FLASH_R1_N

Q_RES_0402LF-4.7K,1%,1/16W,CHIA  I35  R492
   1 P3V3_AUX      A @SCM_LIB.SCM(SCH_1):P3V3_AUX
   2 SPI_PCH_IO3_FLASH_R1      B @SCM_LIB.SCM(SCH_1):SPI_PCH_IO3_FLASH_R1

Q_CAP_C0402-1UF,25V,10%,X6S,CHA  I42  C244
   1 P3V3_AUX      A @SCM_LIB.SCM(SCH_1):P3V3_AUX
   2    GND      B @SCM_LIB.SCM(SCH_1):GND

Q_CAP_C0402-0.01UF,50V,10%,X7RA  I45  C246
   1 P3V3_AUX      A @SCM_LIB.SCM(SCH_1):P3V3_AUX
   2    GND      B @SCM_LIB.SCM(SCH_1):GND

Q_RES_0402LF-4.7K,1%,1/16W,EMPA  I48  R496
   1 P3V3_AUX      A @SCM_LIB.SCM(SCH_1):P3V3_AUX
   2 RST_SPI_PCH_FLASH_R1_N      B @SCM_LIB.SCM(SCH_1):RST_SPI_PCH_FLASH_R1_N

Q_RES_0402LF-4.7K,1%,1/16W,EMPA  I51  R487
   1 SPI_PCH_CS0_FLASH_R1_N      A @SCM_LIB.SCM(SCH_1):SPI_PCH_CS0_FLASH_R1_N
   2    GND      B @SCM_LIB.SCM(SCH_1):GND

SCONN16_ACASPI006P06-SCONN16_AA  I53  J40
   2 P3V3_AUX    VCC @SCM_LIB.SCM(SCH_1):P3V3_AUX
   1 SPI_PCH_IO3_FLASH_R1 HOLD_N @SCM_LIB.SCM(SCH_1):SPI_PCH_IO3_FLASH_R1
   7 SPI_PCH_CS0_FLASH_R1_N   CS_N @SCM_LIB.SCM(SCH_1):SPI_PCH_CS0_FLASH_R1_N
   9 SPI_PCH_IO2_FLASH_R1   WP_N @SCM_LIB.SCM(SCH_1):SPI_PCH_IO2_FLASH_R1
  15 SPI_PCH_IO0_FLASH_R1     DI @SCM_LIB.SCM(SCH_1):SPI_PCH_IO0_FLASH_R1
  16 SPI_PCH_CLK_FLASH_R1    CLK @SCM_LIB.SCM(SCH_1):SPI_PCH_CLK_FLASH_R1
  10    GND    GND @SCM_LIB.SCM(SCH_1):GND
   8 SPI_PCH_IO1_FLASH_R1     DO @SCM_LIB.SCM(SCH_1):SPI_PCH_IO1_FLASH_R1
   3 RST_SPI_PCH_FLASH_R1_N    NC0 @SCM_LIB.SCM(SCH_1):RST_SPI_PCH_FLASH_R1_N
   4 TP_J40_4    NC1 @SCM_LIB.SCM(SCH_1):TP_J40_4
   5 TP_J40_5    NC2 @SCM_LIB.SCM(SCH_1):TP_J40_5
   6 TP_J40_6    NC3 @SCM_LIB.SCM(SCH_1):TP_J40_6
  11 TP_J40_11    NC4 @SCM_LIB.SCM(SCH_1):TP_J40_11
  12 TP_J40_12    NC6 @SCM_LIB.SCM(SCH_1):TP_J40_12
  13 TP_J40_13    NC7 @SCM_LIB.SCM(SCH_1):TP_J40_13
  14 TP_J40_14    NC8 @SCM_LIB.SCM(SCH_1):TP_J40_14

MX25L51245GMI10G-MX25L51245GMIA  I54  U17
   1 SPI_PCH_IO3_FLASH_R1 NC_SIO3 @SCM_LIB.SCM(SCH_1):SPI_PCH_IO3_FLASH_R1
   2 P3V3_AUX    VCC @SCM_LIB.SCM(SCH_1):P3V3_AUX
   3 RST_SPI_PCH_FLASH_R1_N RESET# @SCM_LIB.SCM(SCH_1):RST_SPI_PCH_FLASH_R1_N
   4 TP_J40_4    NC1 @SCM_LIB.SCM(SCH_1):TP_J40_4
   5 TP_J40_5   DNU1 @SCM_LIB.SCM(SCH_1):TP_J40_5
   6 TP_J40_6   DNU2 @SCM_LIB.SCM(SCH_1):TP_J40_6
   7 SPI_PCH_CS0_FLASH_R1_N    CS# @SCM_LIB.SCM(SCH_1):SPI_PCH_CS0_FLASH_R1_N
   8 SPI_PCH_IO1_FLASH_R1 SO_SIO1 @SCM_LIB.SCM(SCH_1):SPI_PCH_IO1_FLASH_R1
   9 SPI_PCH_IO2_FLASH_R1 WP#_SIO2 @SCM_LIB.SCM(SCH_1):SPI_PCH_IO2_FLASH_R1
  10    GND    GND @SCM_LIB.SCM(SCH_1):GND
  11 TP_J40_11   DNU3 @SCM_LIB.SCM(SCH_1):TP_J40_11
  12 TP_J40_12   DNU4 @SCM_LIB.SCM(SCH_1):TP_J40_12
  13 TP_J40_13    NC2 @SCM_LIB.SCM(SCH_1):TP_J40_13
  14 TP_J40_14    NC3 @SCM_LIB.SCM(SCH_1):TP_J40_14
  15 SPI_PCH_IO0_FLASH_R1 SI_SIO0 @SCM_LIB.SCM(SCH_1):SPI_PCH_IO0_FLASH_R1
  16 SPI_PCH_CLK_FLASH_R1   SCLK @SCM_LIB.SCM(SCH_1):SPI_PCH_CLK_FLASH_R1


DRAWING: @SCM_LIB.SCM(SCH_1):PAGE46 

SCONN11_9192031111LF-SCONN11_9A  I56  J5
   1 SPI_SYS_R1_CLK      1 @SCM_LIB.SCM(SCH_1):SPI_SYS_R1_CLK
   3 SPI_SYS_R1_MOSI      3 @SCM_LIB.SCM(SCH_1):SPI_SYS_R1_MOSI
   4 SPI_SYS_R1_MISO      4 @SCM_LIB.SCM(SCH_1):SPI_SYS_R1_MISO
   5 SPI_TPM_CS_N_R      5 @SCM_LIB.SCM(SCH_1):SPI_TPM_CS_N_R
   2 RST_PLTRST_TPM_N      2 @SCM_LIB.SCM(SCH_1):RST_PLTRST_TPM_N
  G1    GND     G1 @SCM_LIB.SCM(SCH_1):GND
  G2    GND     G2 @SCM_LIB.SCM(SCH_1):GND
   6 SMB_PCH_TPM_SDA      6 @SCM_LIB.SCM(SCH_1):SMB_PCH_TPM_SDA
   7 P3V3_AUX      7 @SCM_LIB.SCM(SCH_1):P3V3_AUX
   8 FM_TPM_PRSNT_0_N      8 @SCM_LIB.SCM(SCH_1):FM_TPM_PRSNT_0_N
   9 IRQ_PCH_TPM_SPI_R_N      9 @SCM_LIB.SCM(SCH_1):IRQ_PCH_TPM_SPI_R_N
  10 SMB_PCH_TPM_SCL     10 @SCM_LIB.SCM(SCH_1):SMB_PCH_TPM_SCL
  11    GND     11 @SCM_LIB.SCM(SCH_1):GND

Q_RES_0402LF-33.2,1%,1/16W,CHIA  I58  R501
   1 SPI_SYS_R1_CLK      A @SCM_LIB.SCM(SCH_1):SPI_SYS_R1_CLK
   2 SPI_SYS_R_CLK      B @SCM_LIB.SCM(SCH_1):SPI_SYS_R_CLK

Q_RES_0402LF-0,5%,1/16W,CHIP,CA  I60  R503
   1 RST_PLTRST_TPM_N      A @SCM_LIB.SCM(SCH_1):RST_PLTRST_TPM_N
   2 RST_PLTRST_N      B @SCM_LIB.SCM(SCH_1):RST_PLTRST_N

Q_RES_0402LF-0,5%,1/16W,CHIP,CA  I65  R500
   1 SPI_TPM_CS_N_R      A @SCM_LIB.SCM(SCH_1):SPI_TPM_CS_N_R
   2 SPI_TPM_CS_R_N      B @SCM_LIB.SCM(SCH_1):SPI_TPM_CS_R_N

Q_CAP_0402-0.1UF,25V,10%,X7R,CA  I67  C249
   1 P3V3_AUX      A @SCM_LIB.SCM(SCH_1):P3V3_AUX
   2    GND      B @SCM_LIB.SCM(SCH_1):GND

Q_CAP_C0402-10UF,6.3V,20%,X6S,A  I69  C248
   1 P3V3_AUX      A @SCM_LIB.SCM(SCH_1):P3V3_AUX
   2    GND      B @SCM_LIB.SCM(SCH_1):GND

Q_RES_0402LF-0,5%,1/16W,CHIP,CA  I74  R505
   1 IRQ_PCH_TPM_SPI_N      A @SCM_LIB.SCM(SCH_1):IRQ_PCH_TPM_SPI_N
   2 IRQ_PCH_TPM_SPI_R_N      B @SCM_LIB.SCM(SCH_1):IRQ_PCH_TPM_SPI_R_N

Q_RES_0402LF-10K,1%,1/16W,CHIPA  I75  R464
   1 P3V3_AUX      A @SCM_LIB.SCM(SCH_1):P3V3_AUX
   2 FM_TPM_PRSNT_0_N      B @SCM_LIB.SCM(SCH_1):FM_TPM_PRSNT_0_N

Q_RES_0402LF-10K,1%,1/16W,CHIPA  I78  R497
   1 P3V3_AUX      A @SCM_LIB.SCM(SCH_1):P3V3_AUX
   2 IRQ_PCH_TPM_SPI_N      B @SCM_LIB.SCM(SCH_1):IRQ_PCH_TPM_SPI_N

Q_RES_0402LF-10K,1%,1/16W,CHIPA  I98  R59
   1 P3V3_AUX      A @SCM_LIB.SCM(SCH_1):P3V3_AUX
   2 IRQ_TPM_SPI_N      B @SCM_LIB.SCM(SCH_1):IRQ_TPM_SPI_N

Q_CAP_0402-0.1UF,25V,10%,X7R,CA  I102  C144
   1 P3V3_AUX      A @SCM_LIB.SCM(SCH_1):P3V3_AUX
   2    GND      B @SCM_LIB.SCM(SCH_1):GND

Q_RES_0402LF-10K,1%,1/16W,CHIPA  I104  R50
   1 P3V3_AUX      A @SCM_LIB.SCM(SCH_1):P3V3_AUX
   2 FM_TPM_PRSNT_1_N      B @SCM_LIB.SCM(SCH_1):FM_TPM_PRSNT_1_N

Q_RES_0402LF-0,5%,1/16W,CHIP,CA  I105  R113
   1 IRQ_TPM_SPI_N      A @SCM_LIB.SCM(SCH_1):IRQ_TPM_SPI_N
   2 IRQ_BMC_TPM_SPI_R_N      B @SCM_LIB.SCM(SCH_1):IRQ_BMC_TPM_SPI_R_N

Q_RES_0402LF-33.2,1%,1/16W,CHIA  I106  R47
   1 SMB_BMC_TPM_MM16_SCL      A @SCM_LIB.SCM(SCH_1):SMB_BMC_TPM_MM16_SCL
   2 SMB_BMC_MM16_R5_SCL      B @SCM_LIB.SCM(SCH_1):SMB_BMC_MM16_R5_SCL

Q_CAP_C0402-10UF,6.3V,20%,X6S,A  I108  C143
   1 P3V3_AUX      A @SCM_LIB.SCM(SCH_1):P3V3_AUX
   2    GND      B @SCM_LIB.SCM(SCH_1):GND

SCONN11_9192031111LF-SCONN11_9A  I113  J10
   1 SPI_BMC_TPM_CLK_R      1 @SCM_LIB.SCM(SCH_1):SPI_BMC_TPM_CLK_R
   3 SPI_BMC_TPM_MOSI_R      3 @SCM_LIB.SCM(SCH_1):SPI_BMC_TPM_MOSI_R
   4 SPI_BMC_TPM_MISO_R      4 @SCM_LIB.SCM(SCH_1):SPI_BMC_TPM_MISO_R
   5 SPI_BMC_TPM_CS2_N_R      5 @SCM_LIB.SCM(SCH_1):SPI_BMC_TPM_CS2_N_R
   2 RST_BMC_EXTRST_R3_N      2 @SCM_LIB.SCM(SCH_1):RST_BMC_EXTRST_R3_N
  G1    GND     G1 @SCM_LIB.SCM(SCH_1):GND
  G2    GND     G2 @SCM_LIB.SCM(SCH_1):GND
   6 SMB_BMC_TPM_MM16_SDA      6 @SCM_LIB.SCM(SCH_1):SMB_BMC_TPM_MM16_SDA
   7 P3V3_AUX      7 @SCM_LIB.SCM(SCH_1):P3V3_AUX
   8 FM_TPM_PRSNT_1_N      8 @SCM_LIB.SCM(SCH_1):FM_TPM_PRSNT_1_N
   9 IRQ_BMC_TPM_SPI_R_N      9 @SCM_LIB.SCM(SCH_1):IRQ_BMC_TPM_SPI_R_N
  10 SMB_BMC_TPM_MM16_SCL     10 @SCM_LIB.SCM(SCH_1):SMB_BMC_TPM_MM16_SCL
  11    GND     11 @SCM_LIB.SCM(SCH_1):GND

Q_RES_0402LF-0,5%,1/16W,CHIP,CA  I114  R109
   1 SPI_BMC_TPM_CLK_R      A @SCM_LIB.SCM(SCH_1):SPI_BMC_TPM_CLK_R
   2 SPI_BMC_TPM_CLK      B @SCM_LIB.SCM(SCH_1):SPI_BMC_TPM_CLK

Q_RES_0402LF-0,5%,1/16W,CHIP,CA  I115  R97
   1 SPI_BMC_TPM_MOSI_R      A @SCM_LIB.SCM(SCH_1):SPI_BMC_TPM_MOSI_R
   2 SPI_BMC_TPM_MOSI      B @SCM_LIB.SCM(SCH_1):SPI_BMC_TPM_MOSI

Q_RES_0402LF-0,5%,1/16W,CHIP,CA  I116  R110
   1 RST_BMC_EXTRST_R3_N      A @SCM_LIB.SCM(SCH_1):RST_BMC_EXTRST_R3_N
   2 RST_BMC_EXTRST_R2_N      B @SCM_LIB.SCM(SCH_1):RST_BMC_EXTRST_R2_N

Q_RES_0402LF-33.2,1%,1/16W,CHIA  I117  R33
   1 SMB_BMC_MM16_R5_SDA      A @SCM_LIB.SCM(SCH_1):SMB_BMC_MM16_R5_SDA
   2 SMB_BMC_TPM_MM16_SDA      B @SCM_LIB.SCM(SCH_1):SMB_BMC_TPM_MM16_SDA

Q_RES_0402LF-0,5%,1/16W,CHIP,CA  I119  R98
   1 SPI_BMC_TPM_MISO_R      A @SCM_LIB.SCM(SCH_1):SPI_BMC_TPM_MISO_R
   2 SPI_BMC_TPM_MISO      B @SCM_LIB.SCM(SCH_1):SPI_BMC_TPM_MISO

Q_RES_0402LF-10K,1%,1/16W,CHIPA  I132  R136
   1 P3V3_AUX      A @SCM_LIB.SCM(SCH_1):P3V3_AUX
   2 SMB_PCH_TPM_SCL      B @SCM_LIB.SCM(SCH_1):SMB_PCH_TPM_SCL

Q_RES_0402LF-10K,1%,1/16W,CHIPA  I134  R126
   1 SMB_PCH_TPM_SDA      A @SCM_LIB.SCM(SCH_1):SMB_PCH_TPM_SDA
   2 P3V3_AUX      B @SCM_LIB.SCM(SCH_1):P3V3_AUX

Q_RES_0402LF-22,1%,1/16W,CHIP,A  I136  R499
   1 SPI_SYS_R_MISO      A @SCM_LIB.SCM(SCH_1):SPI_SYS_R_MISO
   2 SPI_SYS_R1_MISO      B @SCM_LIB.SCM(SCH_1):SPI_SYS_R1_MISO

Q_RES_0402LF-22,1%,1/16W,CHIP,A  I137  R498
   1 SPI_SYS_R_MOSI      A @SCM_LIB.SCM(SCH_1):SPI_SYS_R_MOSI
   2 SPI_SYS_R1_MOSI      B @SCM_LIB.SCM(SCH_1):SPI_SYS_R1_MOSI

Q_RES_0402LF-4.7K,1%,1/16W,EMPB  I139  R408
   1 P3V3_AUX      A @SCM_LIB.SCM(SCH_1):P3V3_AUX
   2 SPI_BMC_TPM_CLK      B @SCM_LIB.SCM(SCH_1):SPI_BMC_TPM_CLK

Q_RES_0402LF-4.7K,1%,1/16W,EMPB  I140  R414
   1 P3V3_AUX      A @SCM_LIB.SCM(SCH_1):P3V3_AUX
   2 SPI_BMC_TPM_MISO      B @SCM_LIB.SCM(SCH_1):SPI_BMC_TPM_MISO

Q_RES_0402LF-33.2,1%,1/16W,CHIA  I147  R100
   1 SPI_BMC_TPM_CS2_N_R      A @SCM_LIB.SCM(SCH_1):SPI_BMC_TPM_CS2_N_R
   2 SPI_BMC_TPM_CS2_R_N      B @SCM_LIB.SCM(SCH_1):SPI_BMC_TPM_CS2_R_N


DRAWING: @SCM_LIB.SCM(SCH_1):PAGE47 

Q_LED_SMLF-LED_RED,19-217/R6C-A  I5  D7
   A LED_POSTCODE_7_R      A @SCM_LIB.SCM(SCH_1):LED_POSTCODE_7_R
   C    GND      C @SCM_LIB.SCM(SCH_1):GND

Q_LED_SMLF-LED_GREEN,19-213/GVA  I7  D0
   A LED_POSTCODE_0_R      A @SCM_LIB.SCM(SCH_1):LED_POSTCODE_0_R
   C    GND      C @SCM_LIB.SCM(SCH_1):GND

Q_LED_SMLF-LED_GREEN,19-213/GVA  I9  D1
   A LED_POSTCODE_1_R      A @SCM_LIB.SCM(SCH_1):LED_POSTCODE_1_R
   C    GND      C @SCM_LIB.SCM(SCH_1):GND

Q_LED_SMLF-LED_RED,19-217/R6C-A  I10  D4
   A LED_POSTCODE_4_R      A @SCM_LIB.SCM(SCH_1):LED_POSTCODE_4_R
   C    GND      C @SCM_LIB.SCM(SCH_1):GND

Q_LED_SMLF-LED_GREEN,19-213/GVA  I11  D2
   A LED_POSTCODE_2_R      A @SCM_LIB.SCM(SCH_1):LED_POSTCODE_2_R
   C    GND      C @SCM_LIB.SCM(SCH_1):GND

Q_LED_SMLF-LED_RED,19-217/R6C-A  I12  D5
   A LED_POSTCODE_5_R      A @SCM_LIB.SCM(SCH_1):LED_POSTCODE_5_R
   C    GND      C @SCM_LIB.SCM(SCH_1):GND

Q_LED_SMLF-LED_GREEN,19-213/GVA  I13  D3
   A LED_POSTCODE_3_R      A @SCM_LIB.SCM(SCH_1):LED_POSTCODE_3_R
   C    GND      C @SCM_LIB.SCM(SCH_1):GND

Q_LED_SMLF-LED_RED,19-217/R6C-A  I14  D6
   A LED_POSTCODE_6_R      A @SCM_LIB.SCM(SCH_1):LED_POSTCODE_6_R
   C    GND      C @SCM_LIB.SCM(SCH_1):GND

Q_RES_0402LF-750,1%,1/16W,CHIPA  I18  R597
   1 LED_POSTCODE_7      A @SCM_LIB.SCM(SCH_1):LED_POSTCODE_7
   2 LED_POSTCODE_7_R      B @SCM_LIB.SCM(SCH_1):LED_POSTCODE_7_R

Q_RES_0402LF-750,1%,1/16W,CHIPA  I20  R598
   1 LED_POSTCODE_6      A @SCM_LIB.SCM(SCH_1):LED_POSTCODE_6
   2 LED_POSTCODE_6_R      B @SCM_LIB.SCM(SCH_1):LED_POSTCODE_6_R

Q_RES_0402LF-750,1%,1/16W,CHIPA  I23  R599
   1 LED_POSTCODE_5      A @SCM_LIB.SCM(SCH_1):LED_POSTCODE_5
   2 LED_POSTCODE_5_R      B @SCM_LIB.SCM(SCH_1):LED_POSTCODE_5_R

Q_RES_0402LF-750,1%,1/16W,CHIPA  I25  R600
   1 LED_POSTCODE_4      A @SCM_LIB.SCM(SCH_1):LED_POSTCODE_4
   2 LED_POSTCODE_4_R      B @SCM_LIB.SCM(SCH_1):LED_POSTCODE_4_R

Q_RES_0402LF-750,1%,1/16W,CHIPA  I31  R601
   1 LED_POSTCODE_3      A @SCM_LIB.SCM(SCH_1):LED_POSTCODE_3
   2 LED_POSTCODE_3_R      B @SCM_LIB.SCM(SCH_1):LED_POSTCODE_3_R

Q_RES_0402LF-750,1%,1/16W,CHIPA  I33  R602
   1 LED_POSTCODE_2      A @SCM_LIB.SCM(SCH_1):LED_POSTCODE_2
   2 LED_POSTCODE_2_R      B @SCM_LIB.SCM(SCH_1):LED_POSTCODE_2_R

Q_RES_0402LF-750,1%,1/16W,CHIPA  I35  R603
   1 LED_POSTCODE_1      A @SCM_LIB.SCM(SCH_1):LED_POSTCODE_1
   2 LED_POSTCODE_1_R      B @SCM_LIB.SCM(SCH_1):LED_POSTCODE_1_R

Q_RES_0402LF-750,1%,1/16W,CHIPA  I37  R604
   1 LED_POSTCODE_0      A @SCM_LIB.SCM(SCH_1):LED_POSTCODE_0
   2 LED_POSTCODE_0_R      B @SCM_LIB.SCM(SCH_1):LED_POSTCODE_0_R

Q_RES_0402LF-0,5%,1/16W,CHIP,CA  I48  R669
   1 LED_POSTCODE_7      A @SCM_LIB.SCM(SCH_1):LED_POSTCODE_7
   2 LED_POSTCODE_7_R1      B @SCM_LIB.SCM(SCH_1):LED_POSTCODE_7_R1

Q_RES_0402LF-0,5%,1/16W,CHIP,CA  I50  R674
   1 LED_POSTCODE_6      A @SCM_LIB.SCM(SCH_1):LED_POSTCODE_6
   2 LED_POSTCODE_6_R1      B @SCM_LIB.SCM(SCH_1):LED_POSTCODE_6_R1

Q_RES_0402LF-0,5%,1/16W,CHIP,CA  I52  R676
   1 LED_POSTCODE_5      A @SCM_LIB.SCM(SCH_1):LED_POSTCODE_5
   2 LED_POSTCODE_5_R1      B @SCM_LIB.SCM(SCH_1):LED_POSTCODE_5_R1

Q_RES_0402LF-0,5%,1/16W,CHIP,CA  I54  R695
   1 LED_POSTCODE_4      A @SCM_LIB.SCM(SCH_1):LED_POSTCODE_4
   2 LED_POSTCODE_4_R1      B @SCM_LIB.SCM(SCH_1):LED_POSTCODE_4_R1

Q_RES_0402LF-0,5%,1/16W,CHIP,CA  I56  R696
   1 LED_POSTCODE_3      A @SCM_LIB.SCM(SCH_1):LED_POSTCODE_3
   2 LED_POSTCODE_3_R1      B @SCM_LIB.SCM(SCH_1):LED_POSTCODE_3_R1

Q_RES_0402LF-0,5%,1/16W,CHIP,CA  I58  R697
   1 LED_POSTCODE_2      A @SCM_LIB.SCM(SCH_1):LED_POSTCODE_2
   2 LED_POSTCODE_2_R1      B @SCM_LIB.SCM(SCH_1):LED_POSTCODE_2_R1

Q_RES_0402LF-0,5%,1/16W,CHIP,CA  I60  R698
   1 LED_POSTCODE_1      A @SCM_LIB.SCM(SCH_1):LED_POSTCODE_1
   2 LED_POSTCODE_1_R1      B @SCM_LIB.SCM(SCH_1):LED_POSTCODE_1_R1

Q_RES_0402LF-0,5%,1/16W,CHIP,CA  I62  R700
   1 LED_POSTCODE_0      A @SCM_LIB.SCM(SCH_1):LED_POSTCODE_0
   2 LED_POSTCODE_0_R1      B @SCM_LIB.SCM(SCH_1):LED_POSTCODE_0_R1


DRAWING: @SCM_LIB.SCM(SCH_1):PAGE49 

MC74VHC1G32DTT1G-MC74VHC1G32DTA  I5  U9
   4 ID_LED_BUF  OUT_Y @SCM_LIB.SCM(SCH_1):ID_LED_BUF
   1 BEEP_LED   IN_B @SCM_LIB.SCM(SCH_1):BEEP_LED
   2 FM_ID_R_LED   IN_A @SCM_LIB.SCM(SCH_1):FM_ID_R_LED
   3    GND    GND @SCM_LIB.SCM(SCH_1):GND
   5 P3V3_AUX    VCC @SCM_LIB.SCM(SCH_1):P3V3_AUX

MOSFET_NCH_DUAL-PJT138K,SMLF,IA  I6  Q9
   1    GND     S1 @SCM_LIB.SCM(SCH_1):GND
   2 ID_LED_BUF     G1 @SCM_LIB.SCM(SCH_1):ID_LED_BUF
   6 ID_LED_D_P3V3_AUX     D1 @SCM_LIB.SCM(SCH_1):ID_LED_D_P3V3_AUX

Q_RES_0402LF-10K,1%,1/16W,CHIPA  I8  R306
   1 BEEP_LED      A @SCM_LIB.SCM(SCH_1):BEEP_LED
   2    GND      B @SCM_LIB.SCM(SCH_1):GND

74LVC1G126SE7-74LVC1G126SE-7,SA  I11  U8
   2 PCH_BEEP_LED      A @SCM_LIB.SCM(SCH_1):PCH_BEEP_LED
   4 BEEP_LED      Y @SCM_LIB.SCM(SCH_1):BEEP_LED
   5 P3V3_AUX    VCC @SCM_LIB.SCM(SCH_1):P3V3_AUX
   3    GND    GND @SCM_LIB.SCM(SCH_1):GND
   1 BMC_ID_BEEP_SEL     OE @SCM_LIB.SCM(SCH_1):BMC_ID_BEEP_SEL

Q_CAP_0402-0.1UF,25V,10%,X7R,CA  I13  C274
   1 P3V3_AUX      A @SCM_LIB.SCM(SCH_1):P3V3_AUX
   2    GND      B @SCM_LIB.SCM(SCH_1):GND

Q_RES_0402LF-8.2K,5%,1/16W,CHIA  I22  R839
   1 PWR_LED      A @SCM_LIB.SCM(SCH_1):PWR_LED
   2    GND      B @SCM_LIB.SCM(SCH_1):GND

MOSFET_DUAL_6P-2N7002KDW,SMLF,A  I24  Q12
   2 PWR_LED     G1 @SCM_LIB.SCM(SCH_1):PWR_LED
   5 HDD_LED_N     G2 @SCM_LIB.SCM(SCH_1):HDD_LED_N
   1    GND     S1 @SCM_LIB.SCM(SCH_1):GND
   4    GND     S2 @SCM_LIB.SCM(SCH_1):GND
   6 PWR_LED_BUF_N     D1 @SCM_LIB.SCM(SCH_1):PWR_LED_BUF_N
   3 HDD_LED_BUF     D2 @SCM_LIB.SCM(SCH_1):HDD_LED_BUF

Q_RES_0402LF-8.2K,5%,1/16W,EMPA  I26  R619
   1 HDD_LED_N      A @SCM_LIB.SCM(SCH_1):HDD_LED_N
   2    GND      B @SCM_LIB.SCM(SCH_1):GND

Q_RES_0402LF-33.2,1%,1/16W,CHIA  I34  R812
   1 PWR_LED_BUF_N      A @SCM_LIB.SCM(SCH_1):PWR_LED_BUF_N
   2 PWR_LED_BUF_N_R      B @SCM_LIB.SCM(SCH_1):PWR_LED_BUF_N_R

Q_RES_0402LF-33.2,1%,1/16W,CHIA  I35  R813
   1 HDD_LED_BUF      A @SCM_LIB.SCM(SCH_1):HDD_LED_BUF
   2 HDD_LED_BUF_R      B @SCM_LIB.SCM(SCH_1):HDD_LED_BUF_R

Q_RES_0402LF-10K,1%,1/16W,CHIPA  I36  R814
   1 P5V_AUX      A @SCM_LIB.SCM(SCH_1):P5V_AUX
   2 PWR_LED_BUF_N_R      B @SCM_LIB.SCM(SCH_1):PWR_LED_BUF_N_R

Q_CAP_0402-470PF,50V,10%,X7R,TA  I37  C324
   1 HDD_LED_BUF_R      A @SCM_LIB.SCM(SCH_1):HDD_LED_BUF_R
   2    GND      B @SCM_LIB.SCM(SCH_1):GND

Q_CAP_0402-470PF,50V,10%,X7R,TA  I38  C326
   1 PWR_LED_BUF_N_R      A @SCM_LIB.SCM(SCH_1):PWR_LED_BUF_N_R
   2    GND      B @SCM_LIB.SCM(SCH_1):GND

Q_RES_0402LF-10K,1%,1/16W,CHIPA  I40  R815
   1 P5V_AUX      A @SCM_LIB.SCM(SCH_1):P5V_AUX
   2 HDD_LED_BUF_R      B @SCM_LIB.SCM(SCH_1):HDD_LED_BUF_R

Q_CAP_0402-0.1UF,25V,10%,X7R,CA  I43  C321
   1 PWR_LED_P5V_AUX      A @SCM_LIB.SCM(SCH_1):PWR_LED_P5V_AUX
   2    GND      B @SCM_LIB.SCM(SCH_1):GND

Q_CAP_0402-0.1UF,25V,10%,X7R,CA  I45  C197
   1 HDD_LED_P5V_AUX      A @SCM_LIB.SCM(SCH_1):HDD_LED_P5V_AUX
   2    GND      B @SCM_LIB.SCM(SCH_1):GND

Q_LED_SMLF-LED_BLUE,LTST-C281TA  I50  D19
   A P3V3_AUX      A @SCM_LIB.SCM(SCH_1):P3V3_AUX
   C FM_UARTSW_MSB_R1_N      C @SCM_LIB.SCM(SCH_1):FM_UARTSW_MSB_R1_N

Q_LED_SMLF-LED_BLUE,LTST-C281TA  I51  D18
   A P3V3_AUX      A @SCM_LIB.SCM(SCH_1):P3V3_AUX
   C FM_UARTSW_LSB_R1_N      C @SCM_LIB.SCM(SCH_1):FM_UARTSW_LSB_R1_N

Q_RES_0402LF-220,1%,1/16W,CHIPA  I59  R568
   1 PWR_LED_P5V_AUX      A @SCM_LIB.SCM(SCH_1):PWR_LED_P5V_AUX
   2 P5V_AUX      B @SCM_LIB.SCM(SCH_1):P5V_AUX

Q_RES_0402LF-220,1%,1/16W,CHIPA  I60  R569
   1 HDD_LED_P5V_AUX      A @SCM_LIB.SCM(SCH_1):HDD_LED_P5V_AUX
   2 P5V_AUX      B @SCM_LIB.SCM(SCH_1):P5V_AUX

Q_CAP_0402-0.1UF,25V,10%,X7R,CA  I75  C276
   1 P3V3_AUX      A @SCM_LIB.SCM(SCH_1):P3V3_AUX
   2    GND      B @SCM_LIB.SCM(SCH_1):GND

Q_RES_0402LF-220,1%,1/16W,CHIPA  I79  R43
   1 ID_LED_P3V3_AUX      A @SCM_LIB.SCM(SCH_1):ID_LED_P3V3_AUX
   2 P3V3_AUX      B @SCM_LIB.SCM(SCH_1):P3V3_AUX

Q_RES_0402LF-75,1%,1/16W,CHIP,A  I88  R283
   1 FM_UARTSW_LSB_N      A @SCM_LIB.SCM(SCH_1):FM_UARTSW_LSB_N
   2 FM_UARTSW_LSB_R1_N      B @SCM_LIB.SCM(SCH_1):FM_UARTSW_LSB_R1_N

Q_RES_0402LF-75,1%,1/16W,CHIP,A  I89  R284
   1 FM_UARTSW_MSB_N      A @SCM_LIB.SCM(SCH_1):FM_UARTSW_MSB_N
   2 FM_UARTSW_MSB_R1_N      B @SCM_LIB.SCM(SCH_1):FM_UARTSW_MSB_R1_N

Q_RES_0402LF-33.2,1%,1/16W,CHIA  I92  R390
   1 FM_ID_LED      A @SCM_LIB.SCM(SCH_1):FM_ID_LED
   2 FM_ID_R_LED      B @SCM_LIB.SCM(SCH_1):FM_ID_R_LED

Q_LED_THLF-LED_BLUE,HV-312470/A  I94  D14
   A PWR_LED_P5V_AUX      A @SCM_LIB.SCM(SCH_1):PWR_LED_P5V_AUX
   C PWR_LED_BUF_N_R      C @SCM_LIB.SCM(SCH_1):PWR_LED_BUF_N_R

Q_LED_THLF-LED_BLUE,HV-312470/A  I95  D15
   A HDD_LED_P5V_AUX      A @SCM_LIB.SCM(SCH_1):HDD_LED_P5V_AUX
   C HDD_LED_BUF_R      C @SCM_LIB.SCM(SCH_1):HDD_LED_BUF_R

Q_LED_THLF-LED_YELLOW,LTL-R42FA  I97  D13
   A ID_LED_P3V3_AUX      A @SCM_LIB.SCM(SCH_1):ID_LED_P3V3_AUX
   C ID_LED_D_P3V3_AUX      C @SCM_LIB.SCM(SCH_1):ID_LED_D_P3V3_AUX


DRAWING: @SCM_LIB.SCM(SCH_1):PAGE50 

Q_CAP_0402-0.1UF,25V,10%,X7R,CA  I43  C200
   1 P3V3_AUX      A @SCM_LIB.SCM(SCH_1):P3V3_AUX
   2    GND      B @SCM_LIB.SCM(SCH_1):GND

Q_CAP_C0402-1UF,25V,10%,X6S,CHA  I44  C198
   1 REAR_PWR_BTN_N      A @SCM_LIB.SCM(SCH_1):REAR_PWR_BTN_N
   2    GND      B @SCM_LIB.SCM(SCH_1):GND

74LVC1G17GW-74LVC1G17GW,SMLF,IA  I49  U32
   5 P3V3_AUX    VCC @SCM_LIB.SCM(SCH_1):P3V3_AUX
   2 REAR_ID_RST_BTN_N      A @SCM_LIB.SCM(SCH_1):REAR_ID_RST_BTN_N
   3    GND    GND @SCM_LIB.SCM(SCH_1):GND
   4 ID_RST_BTN_BMC_N      Y @SCM_LIB.SCM(SCH_1):ID_RST_BTN_BMC_N
   1 TP_ID_BUF     NC @SCM_LIB.SCM(SCH_1):TP_ID_BUF

Q_CAP_0402-0.1UF,25V,10%,X7R,CA  I51  C201
   1 P3V3_AUX      A @SCM_LIB.SCM(SCH_1):P3V3_AUX
   2    GND      B @SCM_LIB.SCM(SCH_1):GND

Q_CAP_C0402-1UF,25V,10%,X6S,CHA  I55  C199
   1 REAR_ID_RST_BTN_N      A @SCM_LIB.SCM(SCH_1):REAR_ID_RST_BTN_N
   2    GND      B @SCM_LIB.SCM(SCH_1):GND

Q_RES_0402LF-8.2K,5%,1/16W,CHIA  I82  R504
   1 P3V3_AUX      A @SCM_LIB.SCM(SCH_1):P3V3_AUX
   2 REAR_ID_RST_BTN_N      B @SCM_LIB.SCM(SCH_1):REAR_ID_RST_BTN_N

Q_RES_0402LF-8.2K,5%,1/16W,CHIA  I89  R768
   1 P3V3_AUX      A @SCM_LIB.SCM(SCH_1):P3V3_AUX
   2 REAR_PWR_BTN_N      B @SCM_LIB.SCM(SCH_1):REAR_PWR_BTN_N

74LVC1G07GW-74LVC1G07GW,SMLF,IA  I151  U31
   5 P3V3_AUX    VCC @SCM_LIB.SCM(SCH_1):P3V3_AUX
   2 REAR_PWR_BTN_N      A @SCM_LIB.SCM(SCH_1):REAR_PWR_BTN_N
   3    GND    GND @SCM_LIB.SCM(SCH_1):GND
   4 PWR_BTN_BMC_N      Y @SCM_LIB.SCM(SCH_1):PWR_BTN_BMC_N
   1 TP_PWR_BUF     NC @SCM_LIB.SCM(SCH_1):TP_PWR_BUF

Q_RES_0402LF-0,5%,1/16W,CHIP,CA  I152  R734
   1 REAR_PWR_BTN_N      A @SCM_LIB.SCM(SCH_1):REAR_PWR_BTN_N
   2 FM_DEBUG_PWR_BTN_N      B @SCM_LIB.SCM(SCH_1):FM_DEBUG_PWR_BTN_N

Q_RES_0402LF-0,5%,1/16W,CHIP,CA  I154  R733
   1 REAR_ID_RST_BTN_N      A @SCM_LIB.SCM(SCH_1):REAR_ID_RST_BTN_N
   2 FM_DEBUG_RST_BTN_N      B @SCM_LIB.SCM(SCH_1):FM_DEBUG_RST_BTN_N

BAS70057F-BAS70-05-7-F,SMLF,ICA  I161  U48
   2 P3V3_AUX      A @SCM_LIB.SCM(SCH_1):P3V3_AUX
   1 P3V_BAT_R      B @SCM_LIB.SCM(SCH_1):P3V_BAT_R
   3 P3V3_RTC_AUX      C @SCM_LIB.SCM(SCH_1):P3V3_RTC_AUX

Q_CAP_C0402-1UF,25V,10%,X6S,CHA  I165  C196
   1 P3V3_RTC_AUX      A @SCM_LIB.SCM(SCH_1):P3V3_RTC_AUX
   2    GND      B @SCM_LIB.SCM(SCH_1):GND

SW_PUSHBUTTON4P_12_G34_H2-SW4SA  I204  SW7
   1    GND      1 @SCM_LIB.SCM(SCH_1):GND
   2 REAR_ID_RST_BTN_N      2 @SCM_LIB.SCM(SCH_1):REAR_ID_RST_BTN_N
   3    GND      3 @SCM_LIB.SCM(SCH_1):GND
   4    GND      4 @SCM_LIB.SCM(SCH_1):GND

Q_RES_0402LF-220,1%,1/16W,CHIPA  I210  R80
   1 LED_D22_R      A @SCM_LIB.SCM(SCH_1):LED_D22_R
   2 P5V_AUX      B @SCM_LIB.SCM(SCH_1):P5V_AUX

Q_CAP_0402-0.1UF,25V,10%,X7R,CA  I212  C27
   1 LED_D22_R      A @SCM_LIB.SCM(SCH_1):LED_D22_R
   2    GND      B @SCM_LIB.SCM(SCH_1):GND

MOSFET_NCH_DUAL-PJT138K,SMLF,IA  I218  Q13
   1    GND     S1 @SCM_LIB.SCM(SCH_1):GND
   2 PWRGD_P1V0_AUX_DELAY     G1 @SCM_LIB.SCM(SCH_1):PWRGD_P1V0_AUX_DELAY
   6 LED_D22_R1     D1 @SCM_LIB.SCM(SCH_1):LED_D22_R1

Q_RES_0402LF-316,1%,1/16W,CHIPA  I222  R107
   1 LED_D21_R3      A @SCM_LIB.SCM(SCH_1):LED_D21_R3
   2 LED_D21_R2      B @SCM_LIB.SCM(SCH_1):LED_D21_R2

Q_RES_0402LF-316,1%,1/16W,CHIPA  I224  R286
   1 LED_D21_R2      A @SCM_LIB.SCM(SCH_1):LED_D21_R2
   2 LED_D21_R1      B @SCM_LIB.SCM(SCH_1):LED_D21_R1

Q_RES_0402LF-316,1%,1/16W,CHIPA  I225  R389
   1 LED_D21_R1      A @SCM_LIB.SCM(SCH_1):LED_D21_R1
   2 P12V_AUX      B @SCM_LIB.SCM(SCH_1):P12V_AUX

74LVC1G07GW-74LVC1G07GW,SMLF,EA  I227  U16
   5 P3V3_AUX    VCC @SCM_LIB.SCM(SCH_1):P3V3_AUX
   2 REAR_AC_PWR_BTN_N      A @SCM_LIB.SCM(SCH_1):REAR_AC_PWR_BTN_N
   3    GND    GND @SCM_LIB.SCM(SCH_1):GND
   4 AC_PWR_BTN_R1_N      Y @SCM_LIB.SCM(SCH_1):AC_PWR_BTN_R1_N
   1 NC_U16_P1     NC @SCM_LIB.SCM(SCH_1):NC_U16_P1

Q_CAP_0402-0.1UF,25V,10%,EMPTYA  I232  C29
   1 P3V3_AUX      A @SCM_LIB.SCM(SCH_1):P3V3_AUX
   2    GND      B @SCM_LIB.SCM(SCH_1):GND

Q_RES_0402LF-8.2K,5%,1/16W,EMPA  I235  R391
   1 P3V3_AUX      A @SCM_LIB.SCM(SCH_1):P3V3_AUX
   2 REAR_AC_PWR_BTN_N      B @SCM_LIB.SCM(SCH_1):REAR_AC_PWR_BTN_N

Q_CAP_C0402-1UF,25V,10%,EMPTY,A  I236  C28
   1 REAR_AC_PWR_BTN_N      A @SCM_LIB.SCM(SCH_1):REAR_AC_PWR_BTN_N
   2    GND      B @SCM_LIB.SCM(SCH_1):GND

Q_RES_0402LF-0,5%,1/16W,EMPTY,A  I241  R470
   1 REAR_AC_PWR_BTN      A @SCM_LIB.SCM(SCH_1):REAR_AC_PWR_BTN
   2 REAR_AC_PWR_BTN_N      B @SCM_LIB.SCM(SCH_1):REAR_AC_PWR_BTN_N

Q_RES_0402LF-0,5%,1/16W,CHIP,CA  I242  R471
   1 REAR_AC_PWR_BTN      A @SCM_LIB.SCM(SCH_1):REAR_AC_PWR_BTN
   2 AC_PWR_BTN_N      B @SCM_LIB.SCM(SCH_1):AC_PWR_BTN_N

DIODE_BIDIRECTIONAL-UCLAMP0511A  I244  D10
   A REAR_AC_PWR_BTN      A @SCM_LIB.SCM(SCH_1):REAR_AC_PWR_BTN
   C    GND      C @SCM_LIB.SCM(SCH_1):GND

Q_CAP_0402-0.1UF,25V,10%,X7R,CA  I246  C181
   1 REAR_AC_PWR_BTN      A @SCM_LIB.SCM(SCH_1):REAR_AC_PWR_BTN
   2    GND      B @SCM_LIB.SCM(SCH_1):GND

74LVC1G07GW-74LVC1G07GW,SMLF,IA  I278  U57
   5 P3V3_AUX    VCC @SCM_LIB.SCM(SCH_1):P3V3_AUX
   2 REAR_AC_PWR_BMC_BTN_N      A @SCM_LIB.SCM(SCH_1):REAR_AC_PWR_BMC_BTN_N
   3    GND    GND @SCM_LIB.SCM(SCH_1):GND
   4 AC_PWR_BMC_BTN_N      Y @SCM_LIB.SCM(SCH_1):AC_PWR_BMC_BTN_N
   1 NC_U57_P1     NC @SCM_LIB.SCM(SCH_1):NC_U57_P1

Q_CAP_0402-0.1UF,25V,10%,X7R,CA  I281  C336
   1 P3V3_AUX      A @SCM_LIB.SCM(SCH_1):P3V3_AUX
   2    GND      B @SCM_LIB.SCM(SCH_1):GND

Q_RES_0402LF-8.2K,5%,1/16W,EMPA  I284  R883
   1 P3V3_AUX      A @SCM_LIB.SCM(SCH_1):P3V3_AUX
   2 REAR_AC_PWR_BMC_BTN_N      B @SCM_LIB.SCM(SCH_1):REAR_AC_PWR_BMC_BTN_N

Q_CAP_C0402-1UF,25V,10%,X6S,CHA  I285  C335
   1 REAR_AC_PWR_BMC_BTN_N      A @SCM_LIB.SCM(SCH_1):REAR_AC_PWR_BMC_BTN_N
   2    GND      B @SCM_LIB.SCM(SCH_1):GND

Q_RES_0402LF-0,5%,1/16W,CHIP,CA  I286  R882
   1 REAR_AC_PWR_BTN      A @SCM_LIB.SCM(SCH_1):REAR_AC_PWR_BTN
   2 REAR_AC_PWR_BMC_BTN_N      B @SCM_LIB.SCM(SCH_1):REAR_AC_PWR_BMC_BTN_N

SW_PUSHBUTTON4P_12_G34_H2-SW4SA  I292  SW6
   1    GND      1 @SCM_LIB.SCM(SCH_1):GND
   2 REAR_PWR_BTN_N      2 @SCM_LIB.SCM(SCH_1):REAR_PWR_BTN_N
   3    GND      3 @SCM_LIB.SCM(SCH_1):GND
   4    GND      4 @SCM_LIB.SCM(SCH_1):GND

SW_PUSHBUTTON4P_12_G34_H2-SW4SA  I293  SW8
   1    GND      1 @SCM_LIB.SCM(SCH_1):GND
   2 REAR_AC_PWR_BTN      2 @SCM_LIB.SCM(SCH_1):REAR_AC_PWR_BTN
   3    GND      3 @SCM_LIB.SCM(SCH_1):GND
   4    GND      4 @SCM_LIB.SCM(SCH_1):GND

Q_LED_THLF-LED_BLUE,HV-312470/A  I294  D21
   A LED_D21_R3      A @SCM_LIB.SCM(SCH_1):LED_D21_R3
   C    GND      C @SCM_LIB.SCM(SCH_1):GND

Q_LED_THLF-LED_BLUE,HV-312470/A  I295  D22
   A LED_D22_R      A @SCM_LIB.SCM(SCH_1):LED_D22_R
   C LED_D22_R1      C @SCM_LIB.SCM(SCH_1):LED_D22_R1


DRAWING: @SCM_LIB.SCM(SCH_1):PAGE51 

Q_CAP_0402-0.1UF,25V,10%,X7R,CA  I1  PC205
   1 EN_P5V_AUX      A @SCM_LIB.SCM(SCH_1):EN_P5V_AUX
   2    GND      B @SCM_LIB.SCM(SCH_1):GND

Q_RES_0402LF-100K,1%,1/16W,CHIA  I3  PR522
   1 EN_P5V_AUX      A @SCM_LIB.SCM(SCH_1):EN_P5V_AUX
   2    GND      B @SCM_LIB.SCM(SCH_1):GND

Q_RES_0402LF-681K,1%,1/16W,CHIA  I4  PR521
   1 P12V_AUX      A @SCM_LIB.SCM(SCH_1):P12V_AUX
   2 EN_P5V_AUX      B @SCM_LIB.SCM(SCH_1):EN_P5V_AUX

Q_RES_0402LF-20.5K,1%,1/16W,CHA  I9  PR525
   1 P5V_AUX_CS      A @SCM_LIB.SCM(SCH_1):P5V_AUX_CS
   2    GND      B @SCM_LIB.SCM(SCH_1):GND

Q_CAP_C0402-1UF,25V,10%,X6S,CHA  I13  PC208
   1 P5V_AUX_VCC      A @SCM_LIB.SCM(SCH_1):P5V_AUX_VCC
   2    GND      B @SCM_LIB.SCM(SCH_1):GND

Q_RES_0402LF-10K,1%,1/16W,CHIPA  I21  PR241
   1 P5V_AUX_VCC      A @SCM_LIB.SCM(SCH_1):P5V_AUX_VCC
   2 PWRGD_P5V_AUX_R      B @SCM_LIB.SCM(SCH_1):PWRGD_P5V_AUX_R

Q_CAP_0402-0.1UF,25V,10%,X7R,CA  I22  PC271
   1 P5V_AUX_REF      A @SCM_LIB.SCM(SCH_1):P5V_AUX_REF
   2    GND      B @SCM_LIB.SCM(SCH_1):GND

Q_CAP_0402-0.22UF,16V,10%,X7R,A  I23  PC216
   1 SW_P5V_AUX_BST      A @SCM_LIB.SCM(SCH_1):SW_P5V_AUX_BST
   2 SW_P5V_AUX_SW      B @SCM_LIB.SCM(SCH_1):SW_P5V_AUX_SW

Q_RES_0402LF-12.4K,1%,1/16W,CHA  I26  PR526
   1 P5V_AUX_FB      A @SCM_LIB.SCM(SCH_1):P5V_AUX_FB
   2    GND      B @SCM_LIB.SCM(SCH_1):GND

Q_CAP_C0402-68PF,50V,5%,COG,CHA  I27  PC272
   1 P5V_AUX_FB      A @SCM_LIB.SCM(SCH_1):P5V_AUX_FB
   2 P5V_AUX      B @SCM_LIB.SCM(SCH_1):P5V_AUX

Q_INDUCTOR_SMLF-4.7UH,IND,CV-4A  I28  PL34
   2 P5V_AUX      2 @SCM_LIB.SCM(SCH_1):P5V_AUX
   1 SW_P5V_AUX_SW      1 @SCM_LIB.SCM(SCH_1):SW_P5V_AUX_SW

Q_RES_0402LF-91K,1%,1/16W,CHIPA  I30  PR527
   1 P5V_AUX_FB      A @SCM_LIB.SCM(SCH_1):P5V_AUX_FB
   2 P5V_AUX      B @SCM_LIB.SCM(SCH_1):P5V_AUX

Q_CAP_0402-0.1UF,25V,10%,X7R,CA  I31  PC212
   1 P5V_AUX      A @SCM_LIB.SCM(SCH_1):P5V_AUX
   2    GND      B @SCM_LIB.SCM(SCH_1):GND

Q_CAP_C0805-22UF,10V,20%,X6S,CA  I32  PC213
   1 P5V_AUX      A @SCM_LIB.SCM(SCH_1):P5V_AUX
   2    GND      B @SCM_LIB.SCM(SCH_1):GND

Q_CAP_C0805-22UF,10V,20%,X6S,CA  I33  PC214
   1 P5V_AUX      A @SCM_LIB.SCM(SCH_1):P5V_AUX
   2    GND      B @SCM_LIB.SCM(SCH_1):GND

Q_CAP_C0805-22UF,10V,20%,X6S,CA  I36  PC215
   1 P5V_AUX      A @SCM_LIB.SCM(SCH_1):P5V_AUX
   2    GND      B @SCM_LIB.SCM(SCH_1):GND

Q_CAP_C0805-22UF,10V,20%,X6S,CA  I37  PC217
   1 P5V_AUX      A @SCM_LIB.SCM(SCH_1):P5V_AUX
   2    GND      B @SCM_LIB.SCM(SCH_1):GND

Q_INDUCTOR_SMLF-BLM18SN220TN1DA  I39  PL4
   2 SW_P5V_AUX_FLT      2 @SCM_LIB.SCM(SCH_1):SW_P5V_AUX_FLT
   1 P12V_AUX      1 @SCM_LIB.SCM(SCH_1):P12V_AUX

MPQ8633AGLEC807Z-MPQ8633AGLE-CA  I42  PU38
  10 SW_P5V_AUX_FLT   VIN1 @SCM_LIB.SCM(SCH_1):SW_P5V_AUX_FLT
   9 PWRGD_P5V_AUX_R  PGOOD @SCM_LIB.SCM(SCH_1):PWRGD_P5V_AUX_R
11_18    GND   PGND @SCM_LIB.SCM(SCH_1):GND
   8 EN_P5V_AUX     EN @SCM_LIB.SCM(SCH_1):EN_P5V_AUX
   1 SW_P5V_AUX_BST    BST @SCM_LIB.SCM(SCH_1):SW_P5V_AUX_BST
   7 P5V_AUX_FB     FB @SCM_LIB.SCM(SCH_1):P5V_AUX_FB
   2    GND   AGND @SCM_LIB.SCM(SCH_1):GND
  19 P5V_AUX_VCC    VCC @SCM_LIB.SCM(SCH_1):P5V_AUX_VCC
   6    GND   RGND @SCM_LIB.SCM(SCH_1):GND
  20 SW_P5V_AUX_SW     SW @SCM_LIB.SCM(SCH_1):SW_P5V_AUX_SW
   5 P5V_AUX_REF TRK_REF @SCM_LIB.SCM(SCH_1):P5V_AUX_REF
   4    GND   MODE @SCM_LIB.SCM(SCH_1):GND
   3 P5V_AUX_CS     CS @SCM_LIB.SCM(SCH_1):P5V_AUX_CS
  21 SW_P5V_AUX_FLT   VIN2 @SCM_LIB.SCM(SCH_1):SW_P5V_AUX_FLT

Q_RES_0402LF-100K,1%,1/16W,EMPA  I43  PR245
   1 PWRGD_P5V_AUX_R      A @SCM_LIB.SCM(SCH_1):PWRGD_P5V_AUX_R
   2    GND      B @SCM_LIB.SCM(SCH_1):GND

Q_CAP_0402-0.1UF,25V,10%,X7R,CA  I45  PC210
   1 SW_P5V_AUX_FLT      A @SCM_LIB.SCM(SCH_1):SW_P5V_AUX_FLT
   2    GND      B @SCM_LIB.SCM(SCH_1):GND

Q_CAP_C0805-22UF,16V,20%,X6S,CA  I47  PC206
   1 SW_P5V_AUX_FLT      A @SCM_LIB.SCM(SCH_1):SW_P5V_AUX_FLT
   2    GND      B @SCM_LIB.SCM(SCH_1):GND

Q_CAP_C0805-22UF,16V,20%,X6S,CA  I48  PC207
   1 SW_P5V_AUX_FLT      A @SCM_LIB.SCM(SCH_1):SW_P5V_AUX_FLT
   2    GND      B @SCM_LIB.SCM(SCH_1):GND

Q_CAP_C0402-0.001UF,50V,10%,EMA  I49  C150
   1 PWRGD_P5V_AUX_R      A @SCM_LIB.SCM(SCH_1):PWRGD_P5V_AUX_R
   2    GND      B @SCM_LIB.SCM(SCH_1):GND

Q_RES_0402LF-0,5%,1/16W,CHIP,CA  I51  R292
   1 PWRGD_P5V_AUX_R      A @SCM_LIB.SCM(SCH_1):PWRGD_P5V_AUX_R
   2 PWRGD_P5V_AUX      B @SCM_LIB.SCM(SCH_1):PWRGD_P5V_AUX

Q_CAP_0402-0.1UF,25V,10%,X7R,CA  I52  C241
   1 P12V_AUX      A @SCM_LIB.SCM(SCH_1):P12V_AUX
   2    GND      B @SCM_LIB.SCM(SCH_1):GND

Q_RES_0402LF-0,5%,1/16W,EMPTY,A  I54  R868
   1 PWRGD_P5V_AUX_R      A @SCM_LIB.SCM(SCH_1):PWRGD_P5V_AUX_R
   2 EN_P3V3_R1      B @SCM_LIB.SCM(SCH_1):EN_P3V3_R1

AP2205W57-AP2205-W5-7,SMLF,IC,A  I56  U56
   5 P3V3_LDO   VOUT @SCM_LIB.SCM(SCH_1):P3V3_LDO
   4 U56_ADJ_1 ADJ||NC @SCM_LIB.SCM(SCH_1):U56_ADJ_1
   1 P12V_AUX    VIN @SCM_LIB.SCM(SCH_1):P12V_AUX
   2    GND    GND @SCM_LIB.SCM(SCH_1):GND
   3 P12V_AUX     EN @SCM_LIB.SCM(SCH_1):P12V_AUX

Q_RES_0402LF-10K,1%,1/16W,CHIPA  I57  R677
   1 U56_ADJ_1      A @SCM_LIB.SCM(SCH_1):U56_ADJ_1
   2    GND      B @SCM_LIB.SCM(SCH_1):GND

Q_CAP_C0402-1UF,25V,10%,X6S,CHA  I60  C226
   1 P12V_AUX      A @SCM_LIB.SCM(SCH_1):P12V_AUX
   2    GND      B @SCM_LIB.SCM(SCH_1):GND

Q_RES_0402LF-16.9K,1%,1/16W,CHA  I62  R631
   1 P3V3_LDO      A @SCM_LIB.SCM(SCH_1):P3V3_LDO
   2 U56_ADJ_1      B @SCM_LIB.SCM(SCH_1):U56_ADJ_1

Q_CAP_C0402-2.2UF,10V,10%,X6S,A  I68  C227
   1 P3V3_LDO      A @SCM_LIB.SCM(SCH_1):P3V3_LDO
   2    GND      B @SCM_LIB.SCM(SCH_1):GND


DRAWING: @SCM_LIB.SCM(SCH_1):PAGE52 

Q_CAP_C0402-1UF,25V,10%,X6S,CHA  I9  PC221
   1 P3V3_AUX_VCC      A @SCM_LIB.SCM(SCH_1):P3V3_AUX_VCC
   2    GND      B @SCM_LIB.SCM(SCH_1):GND

Q_CAP_0402-0.1UF,25V,10%,X7R,CA  I11  PC223
   1 SW_P3V3_AUX_FLT      A @SCM_LIB.SCM(SCH_1):SW_P3V3_AUX_FLT
   2    GND      B @SCM_LIB.SCM(SCH_1):GND

Q_RES_0402LF-10K,1%,1/16W,CHIPA  I13  PR242
   1 P3V3_AUX      A @SCM_LIB.SCM(SCH_1):P3V3_AUX
   2 PWRGD_P3V3_AUX_R      B @SCM_LIB.SCM(SCH_1):PWRGD_P3V3_AUX_R

Q_CAP_0402-0.22UF,16V,10%,X7R,A  I15  PC224
   1 SW_P3V3_AUX_BST      A @SCM_LIB.SCM(SCH_1):SW_P3V3_AUX_BST
   2 SW_P3V3_AUX_SW      B @SCM_LIB.SCM(SCH_1):SW_P3V3_AUX_SW

Q_RES_0402LF-12.4K,1%,1/16W,CHA  I17  PR530
   1    GND      A @SCM_LIB.SCM(SCH_1):GND
   2 P3V3_AUX_FB_RC      B @SCM_LIB.SCM(SCH_1):P3V3_AUX_FB_RC

Q_CAP_0402-0.1UF,25V,10%,X7R,CA  I23  PC225
   1 P3V3_AUX      A @SCM_LIB.SCM(SCH_1):P3V3_AUX
   2    GND      B @SCM_LIB.SCM(SCH_1):GND

Q_RES_0402LF-56K,1%,1/16W,CHIPA  I25  PR534
   1 P3V3_AUX_FB_RC      A @SCM_LIB.SCM(SCH_1):P3V3_AUX_FB_RC
   2 P3V3_AUX      B @SCM_LIB.SCM(SCH_1):P3V3_AUX

Q_INDUCTOR_SMLF-BLM18SN220TN1DA  I32  PL19
   2 SW_P3V3_AUX_FLT      2 @SCM_LIB.SCM(SCH_1):SW_P3V3_AUX_FLT
   1 P12V_AUX      1 @SCM_LIB.SCM(SCH_1):P12V_AUX

Q_CAP_C0805-22UF,10V,20%,X6S,CA  I35  PC226
   1 P3V3_AUX      A @SCM_LIB.SCM(SCH_1):P3V3_AUX
   2    GND      B @SCM_LIB.SCM(SCH_1):GND

Q_CAP_C0805-22UF,10V,20%,X6S,CA  I36  PC227
   1 P3V3_AUX      A @SCM_LIB.SCM(SCH_1):P3V3_AUX
   2    GND      B @SCM_LIB.SCM(SCH_1):GND

Q_CAP_C0805-22UF,10V,20%,X6S,CA  I37  PC228
   1 P3V3_AUX      A @SCM_LIB.SCM(SCH_1):P3V3_AUX
   2    GND      B @SCM_LIB.SCM(SCH_1):GND

Q_CAP_C0805-22UF,10V,20%,X6S,CA  I38  PC229
   1 P3V3_AUX      A @SCM_LIB.SCM(SCH_1):P3V3_AUX
   2    GND      B @SCM_LIB.SCM(SCH_1):GND

Q_CAP_0402-0.1UF,25V,10%,X7R,CA  I63  C240
   1 P3V3_AUX      A @SCM_LIB.SCM(SCH_1):P3V3_AUX
   2    GND      B @SCM_LIB.SCM(SCH_1):GND

Q_CAP_0402-0.1UF,25V,10%,X7R,CA  I66  C251
   1 P3V3_RGM      A @SCM_LIB.SCM(SCH_1):P3V3_RGM
   2    GND      B @SCM_LIB.SCM(SCH_1):GND

Q_CAP_C0402-1UF,25V,10%,EMPTY,A  I73  C252
   1 PWRGD_P3V3_RGM_R      A @SCM_LIB.SCM(SCH_1):PWRGD_P3V3_RGM_R
   2    GND      B @SCM_LIB.SCM(SCH_1):GND

AP22811AW57-AP22811AW5-7,SMLF,A  I79  U14
   1 P3V3_RGM    OUT @SCM_LIB.SCM(SCH_1):P3V3_RGM
   2    GND    GND @SCM_LIB.SCM(SCH_1):GND
   4 EN_P3V3_RGM_R     EN @SCM_LIB.SCM(SCH_1):EN_P3V3_RGM_R
   3 TP_U14_FLAG_N   FLG# @SCM_LIB.SCM(SCH_1):TP_U14_FLAG_N
   5 P3V3_AUX     IN @SCM_LIB.SCM(SCH_1):P3V3_AUX

Q_CAP_C0805-22UF,16V,20%,X6S,CA  I80  PC219
   1 SW_P3V3_AUX_FLT      A @SCM_LIB.SCM(SCH_1):SW_P3V3_AUX_FLT
   2    GND      B @SCM_LIB.SCM(SCH_1):GND

Q_CAP_C0805-22UF,16V,20%,X6S,CA  I81  PC218
   1 SW_P3V3_AUX_FLT      A @SCM_LIB.SCM(SCH_1):SW_P3V3_AUX_FLT
   2    GND      B @SCM_LIB.SCM(SCH_1):GND

MPQ8626GDZ-MPQ8626GD-Z,SMLF,ICA  I82  PU1
   3 SW_P3V3_AUX_FLT    VIN @SCM_LIB.SCM(SCH_1):SW_P3V3_AUX_FLT
   9 PWRGD_P3V3_AUX_R  PGOOD @SCM_LIB.SCM(SCH_1):PWRGD_P3V3_AUX_R
  14    GND  PGND2 @SCM_LIB.SCM(SCH_1):GND
   5 PWRGD_EN_P3V3_R     EN @SCM_LIB.SCM(SCH_1):PWRGD_EN_P3V3_R
  10 SW_P3V3_AUX_BST_R    BST @SCM_LIB.SCM(SCH_1):SW_P3V3_AUX_BST_R
   6 P3V3_AUX_FB_RC     FB @SCM_LIB.SCM(SCH_1):P3V3_AUX_FB_RC
   7    GND   AGND @SCM_LIB.SCM(SCH_1):GND
  13 P3V3_AUX_VCC    VCC @SCM_LIB.SCM(SCH_1):P3V3_AUX_VCC
   1    GND  PGND1 @SCM_LIB.SCM(SCH_1):GND
  11 SW_P3V3_AUX_SW    SW2 @SCM_LIB.SCM(SCH_1):SW_P3V3_AUX_SW
   8 P3V3_AUX_REF TRK_REF @SCM_LIB.SCM(SCH_1):P3V3_AUX_REF
  12 P3V3_AUX_MODE   MODE @SCM_LIB.SCM(SCH_1):P3V3_AUX_MODE
   4 P3V3_AUX_CS     CS @SCM_LIB.SCM(SCH_1):P3V3_AUX_CS
   2 SW_P3V3_AUX_SW    SW1 @SCM_LIB.SCM(SCH_1):SW_P3V3_AUX_SW

Q_CAP_0402-3300PF,50V,10%,X7R,A  I86  PC273
   1 P3V3_AUX_REF      A @SCM_LIB.SCM(SCH_1):P3V3_AUX_REF
   2    GND      B @SCM_LIB.SCM(SCH_1):GND

Q_RES_0402LF-5.49K,1%,1/16W,CHA  I87  PR276
   1    GND      A @SCM_LIB.SCM(SCH_1):GND
   2 P3V3_AUX_CS      B @SCM_LIB.SCM(SCH_1):P3V3_AUX_CS

Q_RES_0402LF-60.4K,1%,1/16W,CHA  I88  PR532
   1    GND      A @SCM_LIB.SCM(SCH_1):GND
   2 P3V3_AUX_MODE      B @SCM_LIB.SCM(SCH_1):P3V3_AUX_MODE

Q_CAP_0402-100PF,50V,5%,NPO,CHA  I91  PC239
   1 P3V3_AUX_FB_RC      A @SCM_LIB.SCM(SCH_1):P3V3_AUX_FB_RC
   2 P3V3_AUX      B @SCM_LIB.SCM(SCH_1):P3V3_AUX

Q_INDUCTOR_SMLF-3.3UH/6A,IND,CA  I92  PL35
   2 P3V3_AUX      2 @SCM_LIB.SCM(SCH_1):P3V3_AUX
   1 SW_P3V3_AUX_SW      1 @SCM_LIB.SCM(SCH_1):SW_P3V3_AUX_SW

Q_CAP_C0402-0.001UF,50V,10%,EMA  I93  C151
   1 PWRGD_P3V3_AUX_R      A @SCM_LIB.SCM(SCH_1):PWRGD_P3V3_AUX_R
   2    GND      B @SCM_LIB.SCM(SCH_1):GND

Q_RES_0402LF-0,5%,1/16W,CHIP,CA  I95  R293
   1 PWRGD_P3V3_AUX_R      A @SCM_LIB.SCM(SCH_1):PWRGD_P3V3_AUX_R
   2 PWRGD_P3V3_AUX      B @SCM_LIB.SCM(SCH_1):PWRGD_P3V3_AUX

Q_RES_0402LF-0,5%,1/16W,CHIP,CA  I96  R99
   1 PWRGD_P3V3_RGM_R      A @SCM_LIB.SCM(SCH_1):PWRGD_P3V3_RGM_R
   2 PWRGD_P3V3_RGM      B @SCM_LIB.SCM(SCH_1):PWRGD_P3V3_RGM

Q_RES_0402LF-0,5%,1/16W,CHIP,CA  I97  R381
   1 EN_P3V3      A @SCM_LIB.SCM(SCH_1):EN_P3V3
   2 PWRGD_EN_P3V3_R      B @SCM_LIB.SCM(SCH_1):PWRGD_EN_P3V3_R

Q_CAP_0402-0.1UF,25V,10%,X7R,CA  I101  C262
   1 P12V_AUX      A @SCM_LIB.SCM(SCH_1):P12V_AUX
   2    GND      B @SCM_LIB.SCM(SCH_1):GND

Q_CAP_C0805-22UF,16V,20%,X6S,CA  I102  C265
   1 SW_P3V3_AUX_FLT      A @SCM_LIB.SCM(SCH_1):SW_P3V3_AUX_FLT
   2    GND      B @SCM_LIB.SCM(SCH_1):GND

MC74VHC1G32DTT1G-MC74VHC1G32DTA  I104  U42
   4 EN_P3V3  OUT_Y @SCM_LIB.SCM(SCH_1):EN_P3V3
   1 PWRGD_P5V_AUX   IN_B @SCM_LIB.SCM(SCH_1):PWRGD_P5V_AUX
   2 PWRGD_P1V8_AUX   IN_A @SCM_LIB.SCM(SCH_1):PWRGD_P1V8_AUX
   3    GND    GND @SCM_LIB.SCM(SCH_1):GND
   5 P3V3_LDO    VCC @SCM_LIB.SCM(SCH_1):P3V3_LDO

Q_CAP_0402-0.1UF,25V,10%,X7R,CA  I107  C297
   1 P3V3_LDO      A @SCM_LIB.SCM(SCH_1):P3V3_LDO
   2    GND      B @SCM_LIB.SCM(SCH_1):GND

74LVC1G08GW_SM-74LVC1G08GW,IC,A  I114  U18
   1 PWRGD_P5V_AUX      B @SCM_LIB.SCM(SCH_1):PWRGD_P5V_AUX
   2 PWRGD_P1V8_AUX_R2      A @SCM_LIB.SCM(SCH_1):PWRGD_P1V8_AUX_R2
   4 EN_P3V3_RGM      Y @SCM_LIB.SCM(SCH_1):EN_P3V3_RGM
   5 P3V3_LDO    VCC @SCM_LIB.SCM(SCH_1):P3V3_LDO
   3    GND    GND @SCM_LIB.SCM(SCH_1):GND

Q_CAP_0402-0.1UF,25V,10%,X7R,CA  I119  C296
   1 P3V3_LDO      A @SCM_LIB.SCM(SCH_1):P3V3_LDO
   2    GND      B @SCM_LIB.SCM(SCH_1):GND

Q_CAP_C0402-1UF,25V,10%,X6S,CHA  I125  C305
   1 PWRGD_P1V8_AUX_R2      A @SCM_LIB.SCM(SCH_1):PWRGD_P1V8_AUX_R2
   2    GND      B @SCM_LIB.SCM(SCH_1):GND

Q_RES_0402LF-100,1%,1/16W,CHIPA  I127  R529
   1 PWRGD_P1V8_AUX      A @SCM_LIB.SCM(SCH_1):PWRGD_P1V8_AUX
   2 PWRGD_P1V8_AUX_R2      B @SCM_LIB.SCM(SCH_1):PWRGD_P1V8_AUX_R2

Q_RES_0402LF-0,5%,1/16W,EMPTY,A  I137  R871
   1 EN_P3V3_R1      A @SCM_LIB.SCM(SCH_1):EN_P3V3_R1
   2 PWRGD_EN_P3V3_R      B @SCM_LIB.SCM(SCH_1):PWRGD_EN_P3V3_R

Q_RES_0402LF-0,5%,1/16W,EMPTY,A  I139  R869
   1 PWRGD_P1V8_AUX_R3      A @SCM_LIB.SCM(SCH_1):PWRGD_P1V8_AUX_R3
   2 EN_P3V3_RGM_R      B @SCM_LIB.SCM(SCH_1):EN_P3V3_RGM_R

Q_RES_0402LF-0,5%,1/16W,EMPTY,A  I141  R872
   1 PWRGD_P3V3_RGM_R      A @SCM_LIB.SCM(SCH_1):PWRGD_P3V3_RGM_R
   2 PWRGD_P3V3_RGM_R3      B @SCM_LIB.SCM(SCH_1):PWRGD_P3V3_RGM_R3

Q_RES_0402LF-2.2K,5%,1/16W,CHIA  I145  R709
   1 P3V3_RGM      A @SCM_LIB.SCM(SCH_1):P3V3_RGM
   2 PWRGD_P3V3_RGM_R      B @SCM_LIB.SCM(SCH_1):PWRGD_P3V3_RGM_R

Q_RES_0402LF-2.2,1%,1/16W,CHIPA  I146  R415
   1 SW_P3V3_AUX_BST_R      A @SCM_LIB.SCM(SCH_1):SW_P3V3_AUX_BST_R
   2 SW_P3V3_AUX_BST      B @SCM_LIB.SCM(SCH_1):SW_P3V3_AUX_BST

Q_RES_0402LF-100,1%,1/16W,CHIPA  I147  R380
   1 EN_P3V3_RGM      A @SCM_LIB.SCM(SCH_1):EN_P3V3_RGM
   2 EN_P3V3_RGM_R      B @SCM_LIB.SCM(SCH_1):EN_P3V3_RGM_R


DRAWING: @SCM_LIB.SCM(SCH_1):PAGE53 

Q_RES_0402LF-0,5%,1/16W,CHIP,CA  I58  R35
   1 PWRGD_P2V5_AUX      A @SCM_LIB.SCM(SCH_1):PWRGD_P2V5_AUX
   2 PWRGD_P2V5_AUX_R      B @SCM_LIB.SCM(SCH_1):PWRGD_P2V5_AUX_R

RT9059GQW-RT9059GQW,SMLF,IC,ALA  I60  U39
   5 PWRGD_P2V5_AUX_R  PGOOD @SCM_LIB.SCM(SCH_1):PWRGD_P2V5_AUX_R
   6 PWRGD_P3V3_AUX_R2     EN @SCM_LIB.SCM(SCH_1):PWRGD_P3V3_AUX_R2
   4 U39_ADJ    ADJ @SCM_LIB.SCM(SCH_1):U39_ADJ
   1 P2V5_AUX  VOUT1 @SCM_LIB.SCM(SCH_1):P2V5_AUX
   7 P3V3_AUX   VIN1 @SCM_LIB.SCM(SCH_1):P3V3_AUX
  10 P5V_AUX    VDD @SCM_LIB.SCM(SCH_1):P5V_AUX
  TH    GND     EP @SCM_LIB.SCM(SCH_1):GND
   2 P2V5_AUX  VOUT2 @SCM_LIB.SCM(SCH_1):P2V5_AUX
   3 P2V5_AUX  VOUT3 @SCM_LIB.SCM(SCH_1):P2V5_AUX
   8 P3V3_AUX   VIN2 @SCM_LIB.SCM(SCH_1):P3V3_AUX
   9 P3V3_AUX   VIN3 @SCM_LIB.SCM(SCH_1):P3V3_AUX

Q_RES_0402LF-12K,1%,1/16W,CHIPA  I61  R830
   1 U39_ADJ      A @SCM_LIB.SCM(SCH_1):U39_ADJ
   2    GND      B @SCM_LIB.SCM(SCH_1):GND

Q_RES_0402LF-25.5K,1%,1/16W,CHA  I62  R829
   1 P2V5_AUX      A @SCM_LIB.SCM(SCH_1):P2V5_AUX
   2 U39_ADJ      B @SCM_LIB.SCM(SCH_1):U39_ADJ

Q_CAP_C0402-0.001UF,50V,10%,EMA  I64  C153
   1 PWRGD_P2V5_AUX_R      A @SCM_LIB.SCM(SCH_1):PWRGD_P2V5_AUX_R
   2    GND      B @SCM_LIB.SCM(SCH_1):GND

Q_RES_0402LF-0,5%,1/16W,CHIP,CA  I65  R382
   1 PWRGD_P3V3_AUX      A @SCM_LIB.SCM(SCH_1):PWRGD_P3V3_AUX
   2 PWRGD_P3V3_AUX_R2      B @SCM_LIB.SCM(SCH_1):PWRGD_P3V3_AUX_R2

Q_CAP_C0402-1UF,25V,10%,X6S,CHA  I67  C287
   1 P5V_AUX      A @SCM_LIB.SCM(SCH_1):P5V_AUX
   2    GND      B @SCM_LIB.SCM(SCH_1):GND

Q_RES_0402LF-10K,1%,1/16W,CHIPA  I68  R403
   1 P3V3_AUX      A @SCM_LIB.SCM(SCH_1):P3V3_AUX
   2 PWRGD_P2V5_AUX_R      B @SCM_LIB.SCM(SCH_1):PWRGD_P2V5_AUX_R

Q_CAP_C0805-10UF,25V,10%,X6S,CA  I69  C289
   1 P2V5_AUX      A @SCM_LIB.SCM(SCH_1):P2V5_AUX
   2    GND      B @SCM_LIB.SCM(SCH_1):GND

Q_CAP_0402-0.1UF,25V,10%,X7R,CA  I70  C291
   1 P2V5_AUX      A @SCM_LIB.SCM(SCH_1):P2V5_AUX
   2    GND      B @SCM_LIB.SCM(SCH_1):GND

Q_CAP_C0805-10UF,25V,10%,X6S,CA  I71  C288
   1 P3V3_AUX      A @SCM_LIB.SCM(SCH_1):P3V3_AUX
   2    GND      B @SCM_LIB.SCM(SCH_1):GND

Q_RES_0402LF-0,5%,1/16W,EMPTY,A  I72  R873
   1 PWRGD_P2V5_AUX_R3      A @SCM_LIB.SCM(SCH_1):PWRGD_P2V5_AUX_R3
   2 PWRGD_P2V5_AUX      B @SCM_LIB.SCM(SCH_1):PWRGD_P2V5_AUX


DRAWING: @SCM_LIB.SCM(SCH_1):PAGE54 

RT9059GQW-RT9059GQW,SMLF,IC,ALA  I96  U41
   5 PWRGD_P1V8_AUX_R  PGOOD @SCM_LIB.SCM(SCH_1):PWRGD_P1V8_AUX_R
   6 EN_P1V8_R     EN @SCM_LIB.SCM(SCH_1):EN_P1V8_R
   4 U41_ADJ    ADJ @SCM_LIB.SCM(SCH_1):U41_ADJ
   1 P1V8_AUX  VOUT1 @SCM_LIB.SCM(SCH_1):P1V8_AUX
   7 P3V3_AUX   VIN1 @SCM_LIB.SCM(SCH_1):P3V3_AUX
  10 P5V_AUX    VDD @SCM_LIB.SCM(SCH_1):P5V_AUX
  TH    GND     EP @SCM_LIB.SCM(SCH_1):GND
   2 P1V8_AUX  VOUT2 @SCM_LIB.SCM(SCH_1):P1V8_AUX
   3 P1V8_AUX  VOUT3 @SCM_LIB.SCM(SCH_1):P1V8_AUX
   8 P3V3_AUX   VIN2 @SCM_LIB.SCM(SCH_1):P3V3_AUX
   9 P3V3_AUX   VIN3 @SCM_LIB.SCM(SCH_1):P3V3_AUX

Q_RES_0402LF-12K,1%,1/16W,CHIPA  I97  R832
   1 U41_ADJ      A @SCM_LIB.SCM(SCH_1):U41_ADJ
   2    GND      B @SCM_LIB.SCM(SCH_1):GND

Q_RES_0402LF-15K,1%,1/16W,CHIPA  I98  R831
   1 P1V8_AUX      A @SCM_LIB.SCM(SCH_1):P1V8_AUX
   2 U41_ADJ      B @SCM_LIB.SCM(SCH_1):U41_ADJ

Q_RES_0402LF-0,5%,1/16W,CHIP,CA  I99  R275
   1 PWRGD_P1V8_AUX      A @SCM_LIB.SCM(SCH_1):PWRGD_P1V8_AUX
   2 PWRGD_P1V8_AUX_R      B @SCM_LIB.SCM(SCH_1):PWRGD_P1V8_AUX_R

Q_CAP_C0402-0.001UF,50V,10%,EMA  I100  C154
   1 PWRGD_P1V8_AUX_R      A @SCM_LIB.SCM(SCH_1):PWRGD_P1V8_AUX_R
   2    GND      B @SCM_LIB.SCM(SCH_1):GND

Q_RES_0402LF-0,5%,1/16W,CHIP,CA  I102  R393
   1 EN_P1V8      A @SCM_LIB.SCM(SCH_1):EN_P1V8
   2 EN_P1V8_R      B @SCM_LIB.SCM(SCH_1):EN_P1V8_R

Q_CAP_C0805-10UF,25V,10%,X6S,CA  I104  C142
   1 P1V8_AUX      A @SCM_LIB.SCM(SCH_1):P1V8_AUX
   2    GND      B @SCM_LIB.SCM(SCH_1):GND

Q_CAP_0402-0.1UF,25V,10%,X7R,CA  I105  C294
   1 P1V8_AUX      A @SCM_LIB.SCM(SCH_1):P1V8_AUX
   2    GND      B @SCM_LIB.SCM(SCH_1):GND

Q_CAP_C0805-10UF,25V,10%,X6S,CA  I106  C293
   1 P3V3_AUX      A @SCM_LIB.SCM(SCH_1):P3V3_AUX
   2    GND      B @SCM_LIB.SCM(SCH_1):GND

Q_CAP_C0402-1UF,25V,10%,X6S,CHA  I107  C292
   1 P5V_AUX      A @SCM_LIB.SCM(SCH_1):P5V_AUX
   2    GND      B @SCM_LIB.SCM(SCH_1):GND

Q_RES_0402LF-10K,1%,1/16W,CHIPA  I108  R406
   1 P3V3_AUX      A @SCM_LIB.SCM(SCH_1):P3V3_AUX
   2 PWRGD_P1V8_AUX_R      B @SCM_LIB.SCM(SCH_1):PWRGD_P1V8_AUX_R

Q_CAP_0402-0.1UF,25V,10%,X7R,CA  I112  C298
   1 P3V3_LDO      A @SCM_LIB.SCM(SCH_1):P3V3_LDO
   2    GND      B @SCM_LIB.SCM(SCH_1):GND

MC74VHC1G32DTT1G-MC74VHC1G32DTA  I116  U49
   4 EN_P1V8  OUT_Y @SCM_LIB.SCM(SCH_1):EN_P1V8
   1 PWRGD_P5V_AUX   IN_B @SCM_LIB.SCM(SCH_1):PWRGD_P5V_AUX
   2 PWRGD_P3V3_RGM_R2   IN_A @SCM_LIB.SCM(SCH_1):PWRGD_P3V3_RGM_R2
   3    GND    GND @SCM_LIB.SCM(SCH_1):GND
   5 P3V3_LDO    VCC @SCM_LIB.SCM(SCH_1):P3V3_LDO

Q_CAP_C0402-1UF,25V,10%,X6S,CHA  I130  C310
   1 PWRGD_P3V3_RGM_R2      A @SCM_LIB.SCM(SCH_1):PWRGD_P3V3_RGM_R2
   2    GND      B @SCM_LIB.SCM(SCH_1):GND

Q_RES_0402LF-100,1%,1/16W,CHIPA  I132  R530
   1 PWRGD_P3V3_RGM      A @SCM_LIB.SCM(SCH_1):PWRGD_P3V3_RGM
   2 PWRGD_P3V3_RGM_R2      B @SCM_LIB.SCM(SCH_1):PWRGD_P3V3_RGM_R2

Q_RES_0402LF-0,5%,1/16W,EMPTY,A  I137  R875
   1 PWRGD_P2V5_AUX_R3      A @SCM_LIB.SCM(SCH_1):PWRGD_P2V5_AUX_R3
   2 EN_P1V8_R      B @SCM_LIB.SCM(SCH_1):EN_P1V8_R

Q_RES_0402LF-0,5%,1/16W,EMPTY,A  I139  R874
   1 PWRGD_P1V8_AUX_R3      A @SCM_LIB.SCM(SCH_1):PWRGD_P1V8_AUX_R3
   2 PWRGD_P1V8_AUX_R      B @SCM_LIB.SCM(SCH_1):PWRGD_P1V8_AUX_R


DRAWING: @SCM_LIB.SCM(SCH_1):PAGE55 

Q_RES_0402LF-150K,1%,1/16W,CHIA  I6  PR496
   1 P1V2_AUX_MODE      A @SCM_LIB.SCM(SCH_1):P1V2_AUX_MODE
   2    GND      B @SCM_LIB.SCM(SCH_1):GND

Q_CAP_C0402-1UF,25V,10%,X6S,CHA  I7  PC250
   1 P1V2_AUX_VCC      A @SCM_LIB.SCM(SCH_1):P1V2_AUX_VCC
   2    GND      B @SCM_LIB.SCM(SCH_1):GND

Q_RES_0402LF-5.1,5%,1/16W,CHIPA  I8  PR539
   1 PVCC1_AUX      A @SCM_LIB.SCM(SCH_1):PVCC1_AUX
   2 P1V2_AUX_VCC      B @SCM_LIB.SCM(SCH_1):P1V2_AUX_VCC

NB695GDZ-NB695GD-Z,SMLF,IC,AL0A  I15  PU41
   1 SW_P1V2_AUX_FLT    VIN @SCM_LIB.SCM(SCH_1):SW_P1V2_AUX_FLT
  13 PWRGD_P1V2_AUX_R     PG @SCM_LIB.SCM(SCH_1):PWRGD_P1V2_AUX_R
   2    GND   PGND @SCM_LIB.SCM(SCH_1):GND
   5 EN_P1V2_AUX_R     EN @SCM_LIB.SCM(SCH_1):EN_P1V2_AUX_R
   9 SW_P1V2_AUX_BST    BST @SCM_LIB.SCM(SCH_1):SW_P1V2_AUX_BST
  11    GND   AGND @SCM_LIB.SCM(SCH_1):GND
   6 P1V2_AUX_VCC    LP# @SCM_LIB.SCM(SCH_1):P1V2_AUX_VCC
   3    GND     C1 @SCM_LIB.SCM(SCH_1):GND
   4    GND     C0 @SCM_LIB.SCM(SCH_1):GND
   7 P1V2_AUX_MODE   MODE @SCM_LIB.SCM(SCH_1):P1V2_AUX_MODE
  12 P1V2_AUX   VOUT @SCM_LIB.SCM(SCH_1):P1V2_AUX
   8 SW_P1V2_AUX_SW     SW @SCM_LIB.SCM(SCH_1):SW_P1V2_AUX_SW
  10 P1V2_AUX_VCC    3V3 @SCM_LIB.SCM(SCH_1):P1V2_AUX_VCC

Q_CAP_0402-0.1UF,25V,10%,X7R,CA  I16  PC253
   1 SW_P1V2_AUX_FLT      A @SCM_LIB.SCM(SCH_1):SW_P1V2_AUX_FLT
   2    GND      B @SCM_LIB.SCM(SCH_1):GND

Q_RES_0402LF-10K,1%,1/16W,CHIPA  I18  PR498
   1 P3V3_AUX      A @SCM_LIB.SCM(SCH_1):P3V3_AUX
   2 PWRGD_P1V2_AUX_R      B @SCM_LIB.SCM(SCH_1):PWRGD_P1V2_AUX_R

Q_CAP_0402-0.22UF,16V,10%,X7R,A  I19  PC254
   1 SW_P1V2_AUX_BST      A @SCM_LIB.SCM(SCH_1):SW_P1V2_AUX_BST
   2 SW_P1V2_AUX_SW      B @SCM_LIB.SCM(SCH_1):SW_P1V2_AUX_SW

Q_INDUCTOR_SMLF-1UH,IND,CV-10BA  I21  PL31
   2 P1V2_AUX      2 @SCM_LIB.SCM(SCH_1):P1V2_AUX
   1 SW_P1V2_AUX_SW      1 @SCM_LIB.SCM(SCH_1):SW_P1V2_AUX_SW

Q_CAP_0402-0.1UF,25V,10%,X7R,CA  I23  PC255
   1 P1V2_AUX      A @SCM_LIB.SCM(SCH_1):P1V2_AUX
   2    GND      B @SCM_LIB.SCM(SCH_1):GND

Q_CAP_0805-22UF,4V,20%,X6S,TMPA  I24  PC256
   1 P1V2_AUX      A @SCM_LIB.SCM(SCH_1):P1V2_AUX
   2    GND      B @SCM_LIB.SCM(SCH_1):GND

Q_CAP_0805-22UF,4V,20%,X6S,TMPA  I25  PC257
   1 P1V2_AUX      A @SCM_LIB.SCM(SCH_1):P1V2_AUX
   2    GND      B @SCM_LIB.SCM(SCH_1):GND

Q_CAP_0805-22UF,4V,20%,X6S,TMPA  I28  PC258
   1 P1V2_AUX      A @SCM_LIB.SCM(SCH_1):P1V2_AUX
   2    GND      B @SCM_LIB.SCM(SCH_1):GND

Q_CAP_0805-22UF,4V,20%,X6S,TMPA  I29  PC259
   1 P1V2_AUX      A @SCM_LIB.SCM(SCH_1):P1V2_AUX
   2    GND      B @SCM_LIB.SCM(SCH_1):GND

Q_INDUCTOR_SMLF-BLM18SN220TN1DA  I31  PL29
   2 SW_P1V2_AUX_FLT      2 @SCM_LIB.SCM(SCH_1):SW_P1V2_AUX_FLT
   1 P12V_AUX      1 @SCM_LIB.SCM(SCH_1):P12V_AUX

Q_RES_0402LF-0,5%,1/16W,CHIP,CA  I38  R708
   1 EN_P1V2_AUX      A @SCM_LIB.SCM(SCH_1):EN_P1V2_AUX
   2 EN_P1V2_AUX_R      B @SCM_LIB.SCM(SCH_1):EN_P1V2_AUX_R

Q_RES_0402LF-0,5%,1/16W,EMPTY,A  I41  R764
   1 PWRGD_P1V8_AUX      A @SCM_LIB.SCM(SCH_1):PWRGD_P1V8_AUX
   2 EN_P1V2_AUX_R      B @SCM_LIB.SCM(SCH_1):EN_P1V2_AUX_R

Q_CAP_C0805-10UF,25V,10%,X6S,CA  I42  PC252
   1 SW_P1V2_AUX_FLT      A @SCM_LIB.SCM(SCH_1):SW_P1V2_AUX_FLT
   2    GND      B @SCM_LIB.SCM(SCH_1):GND

Q_CAP_C0805-10UF,25V,10%,X6S,CA  I43  PC251
   1 SW_P1V2_AUX_FLT      A @SCM_LIB.SCM(SCH_1):SW_P1V2_AUX_FLT
   2    GND      B @SCM_LIB.SCM(SCH_1):GND

Q_RES_0402LF-0,5%,1/16W,CHIP,CA  I45  PR274
   1 P3V3_AUX      A @SCM_LIB.SCM(SCH_1):P3V3_AUX
   2 PVCC1_AUX      B @SCM_LIB.SCM(SCH_1):PVCC1_AUX

Q_RES_0402LF-0,5%,1/16W,EMPTY,A  I48  PR275
   1 P5V_AUX      A @SCM_LIB.SCM(SCH_1):P5V_AUX
   2 PVCC1_AUX      B @SCM_LIB.SCM(SCH_1):PVCC1_AUX

Q_RES_0402LF-0,5%,1/16W,CHIP,CA  I50  R276
   1 PWRGD_P1V2_AUX_R      A @SCM_LIB.SCM(SCH_1):PWRGD_P1V2_AUX_R
   2 PWRGD_P1V2_AUX      B @SCM_LIB.SCM(SCH_1):PWRGD_P1V2_AUX

Q_CAP_C0402-0.001UF,50V,10%,EMA  I52  C155
   1 PWRGD_P1V2_AUX_R      A @SCM_LIB.SCM(SCH_1):PWRGD_P1V2_AUX_R
   2    GND      B @SCM_LIB.SCM(SCH_1):GND

Q_CAP_0402-0.1UF,25V,10%,X7R,CA  I54  C278
   1 P12V_AUX      A @SCM_LIB.SCM(SCH_1):P12V_AUX
   2    GND      B @SCM_LIB.SCM(SCH_1):GND

Q_CAP_0402-0.1UF,25V,10%,X7R,CA  I61  C301
   1 P3V3_LDO      A @SCM_LIB.SCM(SCH_1):P3V3_LDO
   2    GND      B @SCM_LIB.SCM(SCH_1):GND

74LVC1G08GW_SM-74LVC1G08GW,IC,A  I63  U52
   1 PWRGD_P5V_AUX      B @SCM_LIB.SCM(SCH_1):PWRGD_P5V_AUX
   2 PWRGD_P3V3_RGM      A @SCM_LIB.SCM(SCH_1):PWRGD_P3V3_RGM
   4 EN_P1V2_AUX      Y @SCM_LIB.SCM(SCH_1):EN_P1V2_AUX
   5 P3V3_LDO    VCC @SCM_LIB.SCM(SCH_1):P3V3_LDO
   3    GND    GND @SCM_LIB.SCM(SCH_1):GND

Q_RES_0402LF-0,5%,1/16W,EMPTY,A  I68  R876
   1 PWRGD_P3V3_RGM_R3      A @SCM_LIB.SCM(SCH_1):PWRGD_P3V3_RGM_R3
   2 EN_P1V2_AUX_R      B @SCM_LIB.SCM(SCH_1):EN_P1V2_AUX_R

Q_RES_0402LF-0,5%,1/16W,EMPTY,A  I70  R877
   1 PWRGD_P1V2_AUX_R      A @SCM_LIB.SCM(SCH_1):PWRGD_P1V2_AUX_R
   2 PWRGD_P1V2_AUX_R2      B @SCM_LIB.SCM(SCH_1):PWRGD_P1V2_AUX_R2


DRAWING: @SCM_LIB.SCM(SCH_1):PAGE56 

Q_CAP_C0402-1UF,25V,10%,X6S,CHA  I7  PC260
   1 P1V0_AUX_VCC      A @SCM_LIB.SCM(SCH_1):P1V0_AUX_VCC
   2    GND      B @SCM_LIB.SCM(SCH_1):GND

Q_RES_0402LF-5.1,5%,1/16W,CHIPA  I8  PR541
   1 PVCC2_AUX      A @SCM_LIB.SCM(SCH_1):PVCC2_AUX
   2 P1V0_AUX_VCC      B @SCM_LIB.SCM(SCH_1):P1V0_AUX_VCC

NB695GDZ-NB695GD-Z,SMLF,IC,AL0A  I15  PU42
   1 SW_P1V0_AUX_FLT    VIN @SCM_LIB.SCM(SCH_1):SW_P1V0_AUX_FLT
  13 PWRGD_P1V0_AUX_R     PG @SCM_LIB.SCM(SCH_1):PWRGD_P1V0_AUX_R
   2    GND   PGND @SCM_LIB.SCM(SCH_1):GND
   5 EN_P1V0_AUX_R     EN @SCM_LIB.SCM(SCH_1):EN_P1V0_AUX_R
   9 SW_P1V0_AUX_BST    BST @SCM_LIB.SCM(SCH_1):SW_P1V0_AUX_BST
  11    GND   AGND @SCM_LIB.SCM(SCH_1):GND
   6 P1V0_AUX_VCC    LP# @SCM_LIB.SCM(SCH_1):P1V0_AUX_VCC
   3 P1V0_AUX_VCC     C1 @SCM_LIB.SCM(SCH_1):P1V0_AUX_VCC
   4    GND     C0 @SCM_LIB.SCM(SCH_1):GND
   7 P1V0_AUX_MODE   MODE @SCM_LIB.SCM(SCH_1):P1V0_AUX_MODE
  12 P1V0_AUX   VOUT @SCM_LIB.SCM(SCH_1):P1V0_AUX
   8 SW_P1V0_AUX_SW     SW @SCM_LIB.SCM(SCH_1):SW_P1V0_AUX_SW
  10 P1V0_AUX_VCC    3V3 @SCM_LIB.SCM(SCH_1):P1V0_AUX_VCC

Q_CAP_0402-0.1UF,25V,10%,X7R,CA  I16  PC263
   1 SW_P1V0_AUX_FLT      A @SCM_LIB.SCM(SCH_1):SW_P1V0_AUX_FLT
   2    GND      B @SCM_LIB.SCM(SCH_1):GND

Q_RES_0402LF-10K,1%,1/16W,CHIPA  I18  PR500
   1 P3V3_AUX      A @SCM_LIB.SCM(SCH_1):P3V3_AUX
   2 PWRGD_P1V0_AUX_R      B @SCM_LIB.SCM(SCH_1):PWRGD_P1V0_AUX_R

Q_CAP_0402-0.22UF,16V,10%,X7R,A  I19  PC264
   1 SW_P1V0_AUX_BST      A @SCM_LIB.SCM(SCH_1):SW_P1V0_AUX_BST
   2 SW_P1V0_AUX_SW      B @SCM_LIB.SCM(SCH_1):SW_P1V0_AUX_SW

Q_CAP_0402-0.1UF,25V,10%,X7R,CA  I23  PC266
   1 P1V0_AUX      A @SCM_LIB.SCM(SCH_1):P1V0_AUX
   2    GND      B @SCM_LIB.SCM(SCH_1):GND

Q_CAP_0805-22UF,4V,20%,X6S,TMPA  I24  PC267
   1 P1V0_AUX      A @SCM_LIB.SCM(SCH_1):P1V0_AUX
   2    GND      B @SCM_LIB.SCM(SCH_1):GND

Q_CAP_0805-22UF,4V,20%,X6S,TMPA  I25  PC268
   1 P1V0_AUX      A @SCM_LIB.SCM(SCH_1):P1V0_AUX
   2    GND      B @SCM_LIB.SCM(SCH_1):GND

Q_CAP_0805-22UF,4V,20%,X6S,TMPA  I28  PC269
   1 P1V0_AUX      A @SCM_LIB.SCM(SCH_1):P1V0_AUX
   2    GND      B @SCM_LIB.SCM(SCH_1):GND

Q_CAP_0805-22UF,4V,20%,X6S,TMPA  I29  PC270
   1 P1V0_AUX      A @SCM_LIB.SCM(SCH_1):P1V0_AUX
   2    GND      B @SCM_LIB.SCM(SCH_1):GND

Q_INDUCTOR_SMLF-BLM18SN220TN1DA  I34  PL32
   2 SW_P1V0_AUX_FLT      2 @SCM_LIB.SCM(SCH_1):SW_P1V0_AUX_FLT
   1 P12V_AUX      1 @SCM_LIB.SCM(SCH_1):P12V_AUX

Q_INDUCTOR_SMLF-1UH,IND,CV-10BA  I37  PL33
   2 P1V0_AUX      2 @SCM_LIB.SCM(SCH_1):P1V0_AUX
   1 SW_P1V0_AUX_SW      1 @SCM_LIB.SCM(SCH_1):SW_P1V0_AUX_SW

Q_CAP_C0805-10UF,25V,10%,X6S,CA  I43  PC262
   1 SW_P1V0_AUX_FLT      A @SCM_LIB.SCM(SCH_1):SW_P1V0_AUX_FLT
   2    GND      B @SCM_LIB.SCM(SCH_1):GND

Q_CAP_C0805-10UF,25V,10%,X6S,CA  I44  PC261
   1 SW_P1V0_AUX_FLT      A @SCM_LIB.SCM(SCH_1):SW_P1V0_AUX_FLT
   2    GND      B @SCM_LIB.SCM(SCH_1):GND

Q_RES_0402LF-0,5%,1/16W,CHIP,CA  I47  PR193
   1 P3V3_AUX      A @SCM_LIB.SCM(SCH_1):P3V3_AUX
   2 PVCC2_AUX      B @SCM_LIB.SCM(SCH_1):PVCC2_AUX

Q_RES_0402LF-0,5%,1/16W,EMPTY,A  I48  PR205
   1 P5V_AUX      A @SCM_LIB.SCM(SCH_1):P5V_AUX
   2 PVCC2_AUX      B @SCM_LIB.SCM(SCH_1):PVCC2_AUX

Q_CAP_C0402-0.001UF,50V,10%,EMA  I51  C156
   1 PWRGD_P1V0_AUX_R      A @SCM_LIB.SCM(SCH_1):PWRGD_P1V0_AUX_R
   2    GND      B @SCM_LIB.SCM(SCH_1):GND

Q_RES_0402LF-0,5%,1/16W,CHIP,CA  I54  R277
   1 PWRGD_P1V0_AUX_R      A @SCM_LIB.SCM(SCH_1):PWRGD_P1V0_AUX_R
   2 PWRGD_P1V0_AUX      B @SCM_LIB.SCM(SCH_1):PWRGD_P1V0_AUX

Q_RES_0402LF-0,5%,1/16W,CHIP,CA  I55  R399
   1 EN_P1V0_AUX      A @SCM_LIB.SCM(SCH_1):EN_P1V0_AUX
   2 EN_P1V0_AUX_R      B @SCM_LIB.SCM(SCH_1):EN_P1V0_AUX_R

Q_CAP_0402-0.1UF,25V,10%,X7R,CA  I58  C280
   1 P12V_AUX      A @SCM_LIB.SCM(SCH_1):P12V_AUX
   2    GND      B @SCM_LIB.SCM(SCH_1):GND

Q_CAP_0402-0.1UF,25V,10%,X7R,CA  I64  C302
   1 P3V3_LDO      A @SCM_LIB.SCM(SCH_1):P3V3_LDO
   2    GND      B @SCM_LIB.SCM(SCH_1):GND

74LVC1G08GW_SM-74LVC1G08GW,IC,A  I66  U53
   1 PWRGD_P5V_AUX      B @SCM_LIB.SCM(SCH_1):PWRGD_P5V_AUX
   2 PWRGD_P1V2_AUX      A @SCM_LIB.SCM(SCH_1):PWRGD_P1V2_AUX
   4 EN_P1V0_AUX      Y @SCM_LIB.SCM(SCH_1):EN_P1V0_AUX
   5 P3V3_LDO    VCC @SCM_LIB.SCM(SCH_1):P3V3_LDO
   3    GND    GND @SCM_LIB.SCM(SCH_1):GND

Q_RES_0402LF-100K,1%,1/16W,CHIA  I71  PR543
   1 P1V0_AUX_MODE      A @SCM_LIB.SCM(SCH_1):P1V0_AUX_MODE
   2    GND      B @SCM_LIB.SCM(SCH_1):GND

Q_RES_0402LF-0,5%,1/16W,EMPTY,A  I72  R878
   1 PWRGD_P1V2_AUX_R2      A @SCM_LIB.SCM(SCH_1):PWRGD_P1V2_AUX_R2
   2 EN_P1V0_AUX_R      B @SCM_LIB.SCM(SCH_1):EN_P1V0_AUX_R


DRAWING: @SCM_LIB.SCM(SCH_1):PAGE57 

HOLE_TH-EMPTY,DUMMY50  I14  H2B1
   1     NC      1     NC

HOLE_TH-EMPTY,DUMMY50  I34  H2B2
   1     NC      1     NC

HOLE_TH-EMPTY,HOLE1211  I35  H5
   1    GND      1 @SCM_LIB.SCM(SCH_1):GND

HOLE_TH-EMPTY,HOLE1211  I36  H9
   1    GND      1 @SCM_LIB.SCM(SCH_1):GND

HOLE_TH-EMPTY,HOLE620  I38  H3
   1    GND      1 @SCM_LIB.SCM(SCH_1):GND

HOLE_TH-EMPTY,HOLE620  I40  H4
   1    GND      1 @SCM_LIB.SCM(SCH_1):GND

HOLE_TH-EMPTY,HOLE1247  I45  H2
   1     NC      1     NC

HOLE_TH-EMPTY,HOLE1248  I49  H1
   1    GND      1 @SCM_LIB.SCM(SCH_1):GND

HOLE_TH-EMPTY,TMP-C_HOLE8  I50  H6
   1    GND      1 @SCM_LIB.SCM(SCH_1):GND

HOLE_TH-EMPTY,TMP-C_HOLE8  I51  H7
   1    GND      1 @SCM_LIB.SCM(SCH_1):GND


DRAWING: @SCM_LIB.SCM(SCH_1):PAGE59 

ME_DUMMY_SYMBOL-QUANTA_LOGO_7XA  I27  ME1
ME_DUMMY_SYMBOL-WEEE,MECH,EMPTA  I28  ME2
ME_DUMMY_SYMBOL-PB-E1_SMALL,MEA  I29  DM7
ME_DUMMY_SYMBOL-SNLABEL_7X7,MEA  I34  ME4
DUMMY_SYMBOL-BIOS_FLASH,MECH,MA  I35  DM3
   1     NC      1     NC

DUMMY_SYMBOL-BMC_FLASH,MECH,EMA  I36  DM1
   1     NC      1     NC

DUMMY_SYMBOL-BMC_FLASH,MECH,EMA  I37  DM2
   1     NC      1     NC


DRAWING: @SCM_LIB.SCM(SCH_1):PAGE60 

TDR_3P_TH2-EMPTY,N_A  I1  DB1
   1  T_GND    GND @SCM_LIB.SCM(SCH_1):T_GND
   2 TDR_SE_50_OHM_TOP    IO1 @SCM_LIB.SCM(SCH_1):TDR_SE_50_OHM_TOP
   3 TDR_SE_50_OHM_TOP    IO2 @SCM_LIB.SCM(SCH_1):TDR_SE_50_OHM_TOP

TDR_3P_TH2-EMPTY,N_A  I3  DB6
   1  T_GND    GND @SCM_LIB.SCM(SCH_1):T_GND
   2 TDR_SE_50_OHM_BOT    IO1 @SCM_LIB.SCM(SCH_1):TDR_SE_50_OHM_BOT
   3 TDR_SE_50_OHM_BOT    IO2 @SCM_LIB.SCM(SCH_1):TDR_SE_50_OHM_BOT

TDR_3P_TH2-EMPTY,N_A  I5  DB5
   1  T_GND    GND @SCM_LIB.SCM(SCH_1):T_GND
   2 TDR_SE_50_OHM_IN4    IO1 @SCM_LIB.SCM(SCH_1):TDR_SE_50_OHM_IN4
   3 TDR_SE_50_OHM_IN4    IO2 @SCM_LIB.SCM(SCH_1):TDR_SE_50_OHM_IN4

TDR_3P_TH2-EMPTY,N_A  I7  DB4
   1  T_GND    GND @SCM_LIB.SCM(SCH_1):T_GND
   2 TDR_SE_50_OHM_IN3    IO1 @SCM_LIB.SCM(SCH_1):TDR_SE_50_OHM_IN3
   3 TDR_SE_50_OHM_IN3    IO2 @SCM_LIB.SCM(SCH_1):TDR_SE_50_OHM_IN3

TDR_3P_TH2-EMPTY,N_A  I9  DB3
   1  T_GND    GND @SCM_LIB.SCM(SCH_1):T_GND
   2 TDR_SE_50_OHM_IN2    IO1 @SCM_LIB.SCM(SCH_1):TDR_SE_50_OHM_IN2
   3 TDR_SE_50_OHM_IN2    IO2 @SCM_LIB.SCM(SCH_1):TDR_SE_50_OHM_IN2

TDR_3P_TH2-EMPTY,N_A  I11  DB2
   1  T_GND    GND @SCM_LIB.SCM(SCH_1):T_GND
   2 TDR_SE_50_OHM_IN1    IO1 @SCM_LIB.SCM(SCH_1):TDR_SE_50_OHM_IN1
   3 TDR_SE_50_OHM_IN1    IO2 @SCM_LIB.SCM(SCH_1):TDR_SE_50_OHM_IN1

TP_TDR_4P_FTS_TH-TP_TDR_4P_DIPA  I13  X1
   2 GND_P1     P1 @SCM_LIB.SCM(SCH_1):GND_P1
   3 GND_P1     P2 @SCM_LIB.SCM(SCH_1):GND_P1
   1 TDR_DIFF_85_TOP_DP     S1 @SCM_LIB.SCM(SCH_1):TDR_DIFF_85_TOP_DP
   4 TDR_DIFF_85_TOP_DN     S2 @SCM_LIB.SCM(SCH_1):TDR_DIFF_85_TOP_DN

TP_TDR_4P_FTS_TH-TP_TDR_4P_DIPA  I14  X7
   2 GND_P1     P1 @SCM_LIB.SCM(SCH_1):GND_P1
   3 GND_P1     P2 @SCM_LIB.SCM(SCH_1):GND_P1
   1 TDR_DIFF_85_TOP_DN     S1 @SCM_LIB.SCM(SCH_1):TDR_DIFF_85_TOP_DN
   4 TDR_DIFF_85_TOP_DP     S2 @SCM_LIB.SCM(SCH_1):TDR_DIFF_85_TOP_DP

TP_TDR_4P_FTS_TH-TP_TDR_4P_DIPA  I18  X12
   2 GND_P1     P1 @SCM_LIB.SCM(SCH_1):GND_P1
   3 GND_P1     P2 @SCM_LIB.SCM(SCH_1):GND_P1
   1 TDR_DIFF_85_BOT_DN     S1 @SCM_LIB.SCM(SCH_1):TDR_DIFF_85_BOT_DN
   4 TDR_DIFF_85_BOT_DP     S2 @SCM_LIB.SCM(SCH_1):TDR_DIFF_85_BOT_DP

TP_TDR_4P_FTS_TH-TP_TDR_4P_DIPA  I19  X6
   2 GND_P1     P1 @SCM_LIB.SCM(SCH_1):GND_P1
   3 GND_P1     P2 @SCM_LIB.SCM(SCH_1):GND_P1
   1 TDR_DIFF_85_BOT_DP     S1 @SCM_LIB.SCM(SCH_1):TDR_DIFF_85_BOT_DP
   4 TDR_DIFF_85_BOT_DN     S2 @SCM_LIB.SCM(SCH_1):TDR_DIFF_85_BOT_DN

TP_TDR_4P_FTS_TH-TP_TDR_4P_DIPA  I22  X11
   2 GND_P1     P1 @SCM_LIB.SCM(SCH_1):GND_P1
   3 GND_P1     P2 @SCM_LIB.SCM(SCH_1):GND_P1
   1 TDR_DIFF_85_IN4_DN     S1 @SCM_LIB.SCM(SCH_1):TDR_DIFF_85_IN4_DN
   4 TDR_DIFF_85_IN4_DP     S2 @SCM_LIB.SCM(SCH_1):TDR_DIFF_85_IN4_DP

TP_TDR_4P_FTS_TH-TP_TDR_4P_DIPA  I23  X5
   2 GND_P1     P1 @SCM_LIB.SCM(SCH_1):GND_P1
   3 GND_P1     P2 @SCM_LIB.SCM(SCH_1):GND_P1
   1 TDR_DIFF_85_IN4_DP     S1 @SCM_LIB.SCM(SCH_1):TDR_DIFF_85_IN4_DP
   4 TDR_DIFF_85_IN4_DN     S2 @SCM_LIB.SCM(SCH_1):TDR_DIFF_85_IN4_DN

TP_TDR_4P_FTS_TH-TP_TDR_4P_DIPA  I34  X8
   2 GND_P1     P1 @SCM_LIB.SCM(SCH_1):GND_P1
   3 GND_P1     P2 @SCM_LIB.SCM(SCH_1):GND_P1
   1 TDR_DIFF_85_IN1_DN     S1 @SCM_LIB.SCM(SCH_1):TDR_DIFF_85_IN1_DN
   4 TDR_DIFF_85_IN1_DP     S2 @SCM_LIB.SCM(SCH_1):TDR_DIFF_85_IN1_DP

TP_TDR_4P_FTS_TH-TP_TDR_4P_DIPA  I35  X2
   2 GND_P1     P1 @SCM_LIB.SCM(SCH_1):GND_P1
   3 GND_P1     P2 @SCM_LIB.SCM(SCH_1):GND_P1
   1 TDR_DIFF_85_IN1_DP     S1 @SCM_LIB.SCM(SCH_1):TDR_DIFF_85_IN1_DP
   4 TDR_DIFF_85_IN1_DN     S2 @SCM_LIB.SCM(SCH_1):TDR_DIFF_85_IN1_DN

TP_TDR_4P_FTS_TH-TP_TDR_4P_DIPA  I38  X19
   2 GND_P1     P1 @SCM_LIB.SCM(SCH_1):GND_P1
   3 GND_P1     P2 @SCM_LIB.SCM(SCH_1):GND_P1
   1 TDR_DIFF_100_TOP_DN     S1 @SCM_LIB.SCM(SCH_1):TDR_DIFF_100_TOP_DN
   4 TDR_DIFF_100_TOP_DP     S2 @SCM_LIB.SCM(SCH_1):TDR_DIFF_100_TOP_DP

TP_TDR_4P_FTS_TH-TP_TDR_4P_DIPA  I39  X13
   2 GND_P1     P1 @SCM_LIB.SCM(SCH_1):GND_P1
   3 GND_P1     P2 @SCM_LIB.SCM(SCH_1):GND_P1
   1 TDR_DIFF_100_TOP_DP     S1 @SCM_LIB.SCM(SCH_1):TDR_DIFF_100_TOP_DP
   4 TDR_DIFF_100_TOP_DN     S2 @SCM_LIB.SCM(SCH_1):TDR_DIFF_100_TOP_DN

TP_TDR_4P_FTS_TH-TP_TDR_4P_DIPA  I42  X18
   2 GND_P1     P1 @SCM_LIB.SCM(SCH_1):GND_P1
   3 GND_P1     P2 @SCM_LIB.SCM(SCH_1):GND_P1
   1 TDR_DIFF_100_BOT_DP     S1 @SCM_LIB.SCM(SCH_1):TDR_DIFF_100_BOT_DP
   4 TDR_DIFF_100_BOT_DN     S2 @SCM_LIB.SCM(SCH_1):TDR_DIFF_100_BOT_DN

TP_TDR_4P_FTS_TH-TP_TDR_4P_DIPA  I43  X24
   2 GND_P1     P1 @SCM_LIB.SCM(SCH_1):GND_P1
   3 GND_P1     P2 @SCM_LIB.SCM(SCH_1):GND_P1
   1 TDR_DIFF_100_BOT_DN     S1 @SCM_LIB.SCM(SCH_1):TDR_DIFF_100_BOT_DN
   4 TDR_DIFF_100_BOT_DP     S2 @SCM_LIB.SCM(SCH_1):TDR_DIFF_100_BOT_DP

TP_TDR_4P_FTS_TH-TP_TDR_4P_DIPA  I46  X17
   2 GND_P1     P1 @SCM_LIB.SCM(SCH_1):GND_P1
   3 GND_P1     P2 @SCM_LIB.SCM(SCH_1):GND_P1
   1 TDR_DIFF_100_IN4_DP     S1 @SCM_LIB.SCM(SCH_1):TDR_DIFF_100_IN4_DP
   4 TDR_DIFF_100_IN4_DN     S2 @SCM_LIB.SCM(SCH_1):TDR_DIFF_100_IN4_DN

TP_TDR_4P_FTS_TH-TP_TDR_4P_DIPA  I47  X23
   2 GND_P1     P1 @SCM_LIB.SCM(SCH_1):GND_P1
   3 GND_P1     P2 @SCM_LIB.SCM(SCH_1):GND_P1
   1 TDR_DIFF_100_IN4_DN     S1 @SCM_LIB.SCM(SCH_1):TDR_DIFF_100_IN4_DN
   4 TDR_DIFF_100_IN4_DP     S2 @SCM_LIB.SCM(SCH_1):TDR_DIFF_100_IN4_DP

TP_TDR_4P_FTS_TH-TP_TDR_4P_DIPA  I58  X14
   2 GND_P1     P1 @SCM_LIB.SCM(SCH_1):GND_P1
   3 GND_P1     P2 @SCM_LIB.SCM(SCH_1):GND_P1
   1 TDR_DIFF_100_IN1_DP     S1 @SCM_LIB.SCM(SCH_1):TDR_DIFF_100_IN1_DP
   4 TDR_DIFF_100_IN1_DN     S2 @SCM_LIB.SCM(SCH_1):TDR_DIFF_100_IN1_DN

TP_TDR_4P_FTS_TH-TP_TDR_4P_DIPA  I59  X20
   2 GND_P1     P1 @SCM_LIB.SCM(SCH_1):GND_P1
   3 GND_P1     P2 @SCM_LIB.SCM(SCH_1):GND_P1
   1 TDR_DIFF_100_IN1_DN     S1 @SCM_LIB.SCM(SCH_1):TDR_DIFF_100_IN1_DN
   4 TDR_DIFF_100_IN1_DP     S2 @SCM_LIB.SCM(SCH_1):TDR_DIFF_100_IN1_DP


DRAWING: @SCM_LIB.SCM(SCH_1):PAGE48 

Q_RES_0402LF-4.7K,1%,1/16W,EMPB  I33  R615
   1 P3V3_AUX      A @SCM_LIB.SCM(SCH_1):P3V3_AUX
   2 FM_BMC_DISABLE      B @SCM_LIB.SCM(SCH_1):FM_BMC_DISABLE

Q_RES_0402LF-100K,1%,1/16W,CHIA  I39  R620
   1 FM_JTAG_TCK_MUX_BMC_SEL      A @SCM_LIB.SCM(SCH_1):FM_JTAG_TCK_MUX_BMC_SEL
   2    GND      B @SCM_LIB.SCM(SCH_1):GND

Q_RES_0402LF-0,5%,1/16W,CHIP,CA  I40  R616
   1 FM_JTAG_TCK_MUX_BMC_SEL_R      A @SCM_LIB.SCM(SCH_1):FM_JTAG_TCK_MUX_BMC_SEL_R
   2 FM_JTAG_TCK_MUX_BMC_SEL      B @SCM_LIB.SCM(SCH_1):FM_JTAG_TCK_MUX_BMC_SEL

Q_RES_0402LF-4.7K,1%,1/16W,EMPB  I42  R881
   1 P3V3_AUX      A @SCM_LIB.SCM(SCH_1):P3V3_AUX
   2 FM_JTAG_TCK_MUX_BMC_SEL_R      B @SCM_LIB.SCM(SCH_1):FM_JTAG_TCK_MUX_BMC_SEL_R

Q_RES_0402LF-4.7K,1%,1/16W,CHIA  I48  R624
   1 P3V3_AUX      A @SCM_LIB.SCM(SCH_1):P3V3_AUX
   2 FM_BMC_DEBUG_SW_N      B @SCM_LIB.SCM(SCH_1):FM_BMC_DEBUG_SW_N

Q_RES_0402LF-33.2,1%,1/16W,CHIA  I50  R509
   1 MB_JTAG_PLD_R_JTAGEN      A @SCM_LIB.SCM(SCH_1):MB_JTAG_PLD_R_JTAGEN
   2 JTAG_SCM_PLD_JTAGEN      B @SCM_LIB.SCM(SCH_1):JTAG_SCM_PLD_JTAGEN

Q_RES_0402LF-10K,1%,1/16W,CHIPA  I51  R508
   1 P3V3_AUX      A @SCM_LIB.SCM(SCH_1):P3V3_AUX
   2 MB_JTAG_PLD_R_JTAGEN      B @SCM_LIB.SCM(SCH_1):MB_JTAG_PLD_R_JTAGEN

Q_RES_0402LF-100,1%,1/16W,EMPTA  I52  R507
   1 MB_JTAG_PLD_R_JTAGEN      A @SCM_LIB.SCM(SCH_1):MB_JTAG_PLD_R_JTAGEN
   2    GND      B @SCM_LIB.SCM(SCH_1):GND

Q_RES_0402LF-100,1%,1/16W,EMPTA  I53  R506
   1 FM_BMC_DEBUG_SW_N      A @SCM_LIB.SCM(SCH_1):FM_BMC_DEBUG_SW_N
   2    GND      B @SCM_LIB.SCM(SCH_1):GND

Q_RES_0402LF-100,1%,1/16W,EMPTA  I56  R431
   1 FM_BMC_DISABLE      A @SCM_LIB.SCM(SCH_1):FM_BMC_DISABLE
   2    GND      B @SCM_LIB.SCM(SCH_1):GND


DRAWING: @SCM_LIB.SCM(SCH_1):PAGE58 

PICOPROBE_BXA-DELTA-L 4.0,SMLFA  I55  J9
   2 85_5INCH_TOP_DP    2_N @SCM_LIB.SCM(SCH_1):85_5INCH_TOP_DP
   3 GND_P1    3_G @SCM_LIB.SCM(SCH_1):GND_P1
   1 85_5INCH_TOP_DN    1_P @SCM_LIB.SCM(SCH_1):85_5INCH_TOP_DN

PICOPROBE_BXA-DELTA-L 4.0,SMLFA  I57  J11
   2 85_5INCH_IN1_DP    2_N @SCM_LIB.SCM(SCH_1):85_5INCH_IN1_DP
   3 GND_P1    3_G @SCM_LIB.SCM(SCH_1):GND_P1
   1 85_5INCH_IN1_DN    1_P @SCM_LIB.SCM(SCH_1):85_5INCH_IN1_DN

PICOPROBE_BXA-DELTA-L 4.0,SMLFA  I58  J16
   2 85_5INCH_IN4_DP    2_N @SCM_LIB.SCM(SCH_1):85_5INCH_IN4_DP
   3 GND_P1    3_G @SCM_LIB.SCM(SCH_1):GND_P1
   1 85_5INCH_IN4_DN    1_P @SCM_LIB.SCM(SCH_1):85_5INCH_IN4_DN

PICOPROBE_BXA-DELTA-L 4.0,SMLFA  I59  J17
   2 85_5INCH_BOT_DP    2_N @SCM_LIB.SCM(SCH_1):85_5INCH_BOT_DP
   3 GND_P1    3_G @SCM_LIB.SCM(SCH_1):GND_P1
   1 85_5INCH_BOT_DN    1_P @SCM_LIB.SCM(SCH_1):85_5INCH_BOT_DN

PICOPROBE_BXA-DELTA-L 4.0,SMLFA  I60  J25
   2 85_10INCH_TOP_DP    2_N @SCM_LIB.SCM(SCH_1):85_10INCH_TOP_DP
   3 GND_P1    3_G @SCM_LIB.SCM(SCH_1):GND_P1
   1 85_10INCH_TOP_DN    1_P @SCM_LIB.SCM(SCH_1):85_10INCH_TOP_DN

PICOPROBE_BXA-DELTA-L 4.0,SMLFA  I61  J28
   2 85_10INCH_IN1_DP    2_N @SCM_LIB.SCM(SCH_1):85_10INCH_IN1_DP
   3 GND_P1    3_G @SCM_LIB.SCM(SCH_1):GND_P1
   1 85_10INCH_IN1_DN    1_P @SCM_LIB.SCM(SCH_1):85_10INCH_IN1_DN

PICOPROBE_BXA-DELTA-L 4.0,SMLFA  I62  J26
   2 85_10INCH_IN4_DP    2_N @SCM_LIB.SCM(SCH_1):85_10INCH_IN4_DP
   3 GND_P1    3_G @SCM_LIB.SCM(SCH_1):GND_P1
   1 85_10INCH_IN4_DN    1_P @SCM_LIB.SCM(SCH_1):85_10INCH_IN4_DN

PICOPROBE_BXA-DELTA-L 4.0,SMLFA  I63  J27
   2 85_10INCH_BOT_DP    2_N @SCM_LIB.SCM(SCH_1):85_10INCH_BOT_DP
   3 GND_P1    3_G @SCM_LIB.SCM(SCH_1):GND_P1
   1 85_10INCH_BOT_DN    1_P @SCM_LIB.SCM(SCH_1):85_10INCH_BOT_DN

PICOPROBE_BXA-DELTA-L 4.0,SMLFA  I64  J12
   2 85_5INCH_TOP_DN    2_N @SCM_LIB.SCM(SCH_1):85_5INCH_TOP_DN
   3 GND_P1    3_G @SCM_LIB.SCM(SCH_1):GND_P1
   1 85_5INCH_TOP_DP    1_P @SCM_LIB.SCM(SCH_1):85_5INCH_TOP_DP

PICOPROBE_BXA-DELTA-L 4.0,SMLFA  I65  J29
   2 85_5INCH_IN1_DN    2_N @SCM_LIB.SCM(SCH_1):85_5INCH_IN1_DN
   3 GND_P1    3_G @SCM_LIB.SCM(SCH_1):GND_P1
   1 85_5INCH_IN1_DP    1_P @SCM_LIB.SCM(SCH_1):85_5INCH_IN1_DP

PICOPROBE_BXA-DELTA-L 4.0,SMLFA  I66  J22
   2 85_10INCH_TOP_DN    2_N @SCM_LIB.SCM(SCH_1):85_10INCH_TOP_DN
   3 GND_P1    3_G @SCM_LIB.SCM(SCH_1):GND_P1
   1 85_10INCH_TOP_DP    1_P @SCM_LIB.SCM(SCH_1):85_10INCH_TOP_DP

PICOPROBE_BXA-DELTA-L 4.0,SMLFA  I67  J30
   2 85_10INCH_IN1_DN    2_N @SCM_LIB.SCM(SCH_1):85_10INCH_IN1_DN
   3 GND_P1    3_G @SCM_LIB.SCM(SCH_1):GND_P1
   1 85_10INCH_IN1_DP    1_P @SCM_LIB.SCM(SCH_1):85_10INCH_IN1_DP

PICOPROBE_BXA-DELTA-L 4.0,SMLFA  I68  J24
   2 85_10INCH_BOT_DN    2_N @SCM_LIB.SCM(SCH_1):85_10INCH_BOT_DN
   3 GND_P1    3_G @SCM_LIB.SCM(SCH_1):GND_P1
   1 85_10INCH_BOT_DP    1_P @SCM_LIB.SCM(SCH_1):85_10INCH_BOT_DP

PICOPROBE_BXA-DELTA-L 4.0,SMLFA  I69  J23
   2 85_10INCH_IN4_DN    2_N @SCM_LIB.SCM(SCH_1):85_10INCH_IN4_DN
   3 GND_P1    3_G @SCM_LIB.SCM(SCH_1):GND_P1
   1 85_10INCH_IN4_DP    1_P @SCM_LIB.SCM(SCH_1):85_10INCH_IN4_DP

PICOPROBE_BXA-DELTA-L 4.0,SMLFA  I70  J20
   2 85_5INCH_BOT_DN    2_N @SCM_LIB.SCM(SCH_1):85_5INCH_BOT_DN
   3 GND_P1    3_G @SCM_LIB.SCM(SCH_1):GND_P1
   1 85_5INCH_BOT_DP    1_P @SCM_LIB.SCM(SCH_1):85_5INCH_BOT_DP

PICOPROBE_BXA-DELTA-L 4.0,SMLFA  I71  J19
   2 85_5INCH_IN4_DN    2_N @SCM_LIB.SCM(SCH_1):85_5INCH_IN4_DN
   3 GND_P1    3_G @SCM_LIB.SCM(SCH_1):GND_P1
   1 85_5INCH_IN4_DP    1_P @SCM_LIB.SCM(SCH_1):85_5INCH_IN4_DP

END LOGICAL PART CROSS REFERENCE
GLOBAL SIGNAL CROSS REFERENCE - 25-Aug-2023 AT 17:03:33
85_10INCH_BOT_DN @SCM_LIB.SCM(SCH_1):85_10INCH_BOT_DN
   J27    1    1_P PICOPROBE_BXA-DELTA-L 4.0,SMLFA    I63 @SCM_LIB.SCM(SCH_1):PAGE58
   J24    2    2_N PICOPROBE_BXA-DELTA-L 4.0,SMLFA    I68 @SCM_LIB.SCM(SCH_1):PAGE58

85_10INCH_BOT_DP @SCM_LIB.SCM(SCH_1):85_10INCH_BOT_DP
   J27    2    2_N PICOPROBE_BXA-DELTA-L 4.0,SMLFA    I63 @SCM_LIB.SCM(SCH_1):PAGE58
   J24    1    1_P PICOPROBE_BXA-DELTA-L 4.0,SMLFA    I68 @SCM_LIB.SCM(SCH_1):PAGE58

85_10INCH_IN1_DN @SCM_LIB.SCM(SCH_1):85_10INCH_IN1_DN
   J28    1    1_P PICOPROBE_BXA-DELTA-L 4.0,SMLFA    I61 @SCM_LIB.SCM(SCH_1):PAGE58
   J30    2    2_N PICOPROBE_BXA-DELTA-L 4.0,SMLFA    I67 @SCM_LIB.SCM(SCH_1):PAGE58

85_10INCH_IN1_DP @SCM_LIB.SCM(SCH_1):85_10INCH_IN1_DP
   J28    2    2_N PICOPROBE_BXA-DELTA-L 4.0,SMLFA    I61 @SCM_LIB.SCM(SCH_1):PAGE58
   J30    1    1_P PICOPROBE_BXA-DELTA-L 4.0,SMLFA    I67 @SCM_LIB.SCM(SCH_1):PAGE58

85_10INCH_IN4_DN @SCM_LIB.SCM(SCH_1):85_10INCH_IN4_DN
   J26    1    1_P PICOPROBE_BXA-DELTA-L 4.0,SMLFA    I62 @SCM_LIB.SCM(SCH_1):PAGE58
   J23    2    2_N PICOPROBE_BXA-DELTA-L 4.0,SMLFA    I69 @SCM_LIB.SCM(SCH_1):PAGE58

85_10INCH_IN4_DP @SCM_LIB.SCM(SCH_1):85_10INCH_IN4_DP
   J26    2    2_N PICOPROBE_BXA-DELTA-L 4.0,SMLFA    I62 @SCM_LIB.SCM(SCH_1):PAGE58
   J23    1    1_P PICOPROBE_BXA-DELTA-L 4.0,SMLFA    I69 @SCM_LIB.SCM(SCH_1):PAGE58

85_10INCH_TOP_DN @SCM_LIB.SCM(SCH_1):85_10INCH_TOP_DN
   J25    1    1_P PICOPROBE_BXA-DELTA-L 4.0,SMLFA    I60 @SCM_LIB.SCM(SCH_1):PAGE58
   J22    2    2_N PICOPROBE_BXA-DELTA-L 4.0,SMLFA    I66 @SCM_LIB.SCM(SCH_1):PAGE58

85_10INCH_TOP_DP @SCM_LIB.SCM(SCH_1):85_10INCH_TOP_DP
   J25    2    2_N PICOPROBE_BXA-DELTA-L 4.0,SMLFA    I60 @SCM_LIB.SCM(SCH_1):PAGE58
   J22    1    1_P PICOPROBE_BXA-DELTA-L 4.0,SMLFA    I66 @SCM_LIB.SCM(SCH_1):PAGE58

85_5INCH_BOT_DN @SCM_LIB.SCM(SCH_1):85_5INCH_BOT_DN
   J17    1    1_P PICOPROBE_BXA-DELTA-L 4.0,SMLFA    I59 @SCM_LIB.SCM(SCH_1):PAGE58
   J20    2    2_N PICOPROBE_BXA-DELTA-L 4.0,SMLFA    I70 @SCM_LIB.SCM(SCH_1):PAGE58

85_5INCH_BOT_DP @SCM_LIB.SCM(SCH_1):85_5INCH_BOT_DP
   J17    2    2_N PICOPROBE_BXA-DELTA-L 4.0,SMLFA    I59 @SCM_LIB.SCM(SCH_1):PAGE58
   J20    1    1_P PICOPROBE_BXA-DELTA-L 4.0,SMLFA    I70 @SCM_LIB.SCM(SCH_1):PAGE58

85_5INCH_IN1_DN @SCM_LIB.SCM(SCH_1):85_5INCH_IN1_DN
   J11    1    1_P PICOPROBE_BXA-DELTA-L 4.0,SMLFA    I57 @SCM_LIB.SCM(SCH_1):PAGE58
   J29    2    2_N PICOPROBE_BXA-DELTA-L 4.0,SMLFA    I65 @SCM_LIB.SCM(SCH_1):PAGE58

85_5INCH_IN1_DP @SCM_LIB.SCM(SCH_1):85_5INCH_IN1_DP
   J11    2    2_N PICOPROBE_BXA-DELTA-L 4.0,SMLFA    I57 @SCM_LIB.SCM(SCH_1):PAGE58
   J29    1    1_P PICOPROBE_BXA-DELTA-L 4.0,SMLFA    I65 @SCM_LIB.SCM(SCH_1):PAGE58

85_5INCH_IN4_DN @SCM_LIB.SCM(SCH_1):85_5INCH_IN4_DN
   J16    1    1_P PICOPROBE_BXA-DELTA-L 4.0,SMLFA    I58 @SCM_LIB.SCM(SCH_1):PAGE58
   J19    2    2_N PICOPROBE_BXA-DELTA-L 4.0,SMLFA    I71 @SCM_LIB.SCM(SCH_1):PAGE58

85_5INCH_IN4_DP @SCM_LIB.SCM(SCH_1):85_5INCH_IN4_DP
   J16    2    2_N PICOPROBE_BXA-DELTA-L 4.0,SMLFA    I58 @SCM_LIB.SCM(SCH_1):PAGE58
   J19    1    1_P PICOPROBE_BXA-DELTA-L 4.0,SMLFA    I71 @SCM_LIB.SCM(SCH_1):PAGE58

85_5INCH_TOP_DN @SCM_LIB.SCM(SCH_1):85_5INCH_TOP_DN
    J9    1    1_P PICOPROBE_BXA-DELTA-L 4.0,SMLFA    I55 @SCM_LIB.SCM(SCH_1):PAGE58
   J12    2    2_N PICOPROBE_BXA-DELTA-L 4.0,SMLFA    I64 @SCM_LIB.SCM(SCH_1):PAGE58

85_5INCH_TOP_DP @SCM_LIB.SCM(SCH_1):85_5INCH_TOP_DP
    J9    2    2_N PICOPROBE_BXA-DELTA-L 4.0,SMLFA    I55 @SCM_LIB.SCM(SCH_1):PAGE58
   J12    1    1_P PICOPROBE_BXA-DELTA-L 4.0,SMLFA    I64 @SCM_LIB.SCM(SCH_1):PAGE58

AC_PWR_BMC_BTN_N @SCM_LIB.SCM(SCH_1):AC_PWR_BMC_BTN_N
   U57    4      Y 74LVC1G07GW-74LVC1G07GW,SMLF,IA   I278 @SCM_LIB.SCM(SCH_1):PAGE50
  R884    2      B Q_RES_0402LF-33.2,1%,1/16W,CHIA   I229 @SCM_LIB.SCM(SCH_1):PAGE14
  R885    2      B Q_RES_0402LF-4.7K,1%,1/16W,CHIA   I231 @SCM_LIB.SCM(SCH_1):PAGE14

AC_PWR_BMC_BTN_R_N @SCM_LIB.SCM(SCH_1):AC_PWR_BMC_BTN_R_N
    U5   C6 RGMII1TXCK||RMII1RCLKO||GPIO18A0 AST2600A3GP-AST2600A3-GP,SMLF,A   I149 @SCM_LIB.SCM(SCH_1):PAGE14
  R884    1      A Q_RES_0402LF-33.2,1%,1/16W,CHIA   I229 @SCM_LIB.SCM(SCH_1):PAGE14

AC_PWR_BTN_N @SCM_LIB.SCM(SCH_1):AC_PWR_BTN_N
   GF1  B42 QSPI0_CS1_N FCONN168_ME1016810202011_SCM-FA   I553 @SCM_LIB.SCM(SCH_1):PAGE10
  R471    2      B Q_RES_0402LF-0,5%,1/16W,CHIP,CA   I242 @SCM_LIB.SCM(SCH_1):PAGE50

AC_PWR_BTN_R1_N @SCM_LIB.SCM(SCH_1):AC_PWR_BTN_R1_N
   U16    4      Y 74LVC1G07GW-74LVC1G07GW,SMLF,EA   I227 @SCM_LIB.SCM(SCH_1):PAGE50
  R463    1      A Q_RES_0402LF-0,5%,1/16W,EMPTY,A   I131 @SCM_LIB.SCM(SCH_1):PAGE35
  R472    2      B Q_RES_0402LF-4.7K,1%,1/16W,EMPA   I136 @SCM_LIB.SCM(SCH_1):PAGE35

AC_PWR_BTN_R2_N @SCM_LIB.SCM(SCH_1):AC_PWR_BTN_R2_N
   U25  N15  PR13C LCMXO3LF2100C5BG256C-LCMXO3LF-A     I1 @SCM_LIB.SCM(SCH_1):PAGE35
  R463    2      B Q_RES_0402LF-0,5%,1/16W,EMPTY,A   I131 @SCM_LIB.SCM(SCH_1):PAGE35

ADCVREFEXT0 @SCM_LIB.SCM(SCH_1):ADCVREFEXT0
    U5 AF19 ADCVREFEXT0 AST2600A3GP-AST2600A3-GP,SMLF,A   I188 @SCM_LIB.SCM(SCH_1):PAGE16
  C284    1      A Q_CAP_0402-0.1UF,25V,10%,X7R,CA   I250 @SCM_LIB.SCM(SCH_1):PAGE17
  C282    1      A Q_CAP_C0402-1UF,25V,10%,X6S,CHA   I252 @SCM_LIB.SCM(SCH_1):PAGE17
  R780    2      B Q_RES_0402LF-0,5%,1/16W,EMPTY,A   I256 @SCM_LIB.SCM(SCH_1):PAGE17
  R783    2      B Q_RES_0402LF-0,5%,1/16W,CHIP,CA   I260 @SCM_LIB.SCM(SCH_1):PAGE17
  R784    2      B Q_RES_0402LF-0,5%,1/16W,EMPTY,A   I267 @SCM_LIB.SCM(SCH_1):PAGE17

ADCVREFEXT1 @SCM_LIB.SCM(SCH_1):ADCVREFEXT1
    U5 AF17 ADCVREFEXT1 AST2600A3GP-AST2600A3-GP,SMLF,A   I188 @SCM_LIB.SCM(SCH_1):PAGE16
  C277    1      A Q_CAP_C0402-1UF,25V,10%,X6S,CHA   I253 @SCM_LIB.SCM(SCH_1):PAGE17
  C279    1      A Q_CAP_0402-0.1UF,25V,10%,X7R,CA   I255 @SCM_LIB.SCM(SCH_1):PAGE17
  R779    2      B Q_RES_0402LF-0,5%,1/16W,CHIP,CA   I259 @SCM_LIB.SCM(SCH_1):PAGE17
  R781    2      B Q_RES_0402LF-0,5%,1/16W,EMPTY,A   I263 @SCM_LIB.SCM(SCH_1):PAGE17
  R782    2      B Q_RES_0402LF-0,5%,1/16W,EMPTY,A   I264 @SCM_LIB.SCM(SCH_1):PAGE17

A_BMC_ADCAV33 @SCM_LIB.SCM(SCH_1):A_BMC_ADCAV33
   C75    1      A Q_CAP_C0402-1UF,25V,10%,X6S,CHA    I93 @SCM_LIB.SCM(SCH_1):PAGE16
   L12    2      2 Q_INDUCTOR_SMLF-BLM18PG121SN1DA    I99 @SCM_LIB.SCM(SCH_1):PAGE16
   C77    1      A Q_CAP_0402-0.1UF,25V,10%,X7R,CA   I100 @SCM_LIB.SCM(SCH_1):PAGE16
    U5 AA21 ADCAV33_AA21 AST2600A3GP-AST2600A3-GP,SMLF,A   I188 @SCM_LIB.SCM(SCH_1):PAGE16
    U5  Y21 ADCAV33_Y21 AST2600A3GP-AST2600A3-GP,SMLF,A   I188 @SCM_LIB.SCM(SCH_1):PAGE16

A_BMC_ADCREXT0 @SCM_LIB.SCM(SCH_1):A_BMC_ADCREXT0
  R233    2      B Q_RES_0402LF-49.9K,1%,1/16W,CHA    I87 @SCM_LIB.SCM(SCH_1):PAGE16
    U5 AF20 ADCREXT0 AST2600A3GP-AST2600A3-GP,SMLF,A   I188 @SCM_LIB.SCM(SCH_1):PAGE16

A_BMC_ADCREXT1 @SCM_LIB.SCM(SCH_1):A_BMC_ADCREXT1
  R234    2      B Q_RES_0402LF-49.9K,1%,1/16W,CHA    I86 @SCM_LIB.SCM(SCH_1):PAGE16
    U5 AF18 ADCREXT1 AST2600A3GP-AST2600A3-GP,SMLF,A   I188 @SCM_LIB.SCM(SCH_1):PAGE16

A_BMC_ADCVREFN0 @SCM_LIB.SCM(SCH_1):A_BMC_ADCVREFN0
    U5 AB20 ADCVREFN0 AST2600A3GP-AST2600A3-GP,SMLF,A   I188 @SCM_LIB.SCM(SCH_1):PAGE16
  C134    2      B Q_CAP_C0402-0.01UF,50V,10%,X7RA   I106 @SCM_LIB.SCM(SCH_1):PAGE17
  C138    1      A Q_CAP_C0402-0.01UF,50V,10%,X7RA   I109 @SCM_LIB.SCM(SCH_1):PAGE17

A_BMC_ADCVREFN1 @SCM_LIB.SCM(SCH_1):A_BMC_ADCVREFN1
    U5 AD18 ADCVREFN1 AST2600A3GP-AST2600A3-GP,SMLF,A   I188 @SCM_LIB.SCM(SCH_1):PAGE16
  C133    2      B Q_CAP_C0402-0.01UF,50V,10%,X7RA   I104 @SCM_LIB.SCM(SCH_1):PAGE17
  C137    1      A Q_CAP_C0402-0.01UF,50V,10%,X7RA   I108 @SCM_LIB.SCM(SCH_1):PAGE17

A_BMC_ADCVREFP0 @SCM_LIB.SCM(SCH_1):A_BMC_ADCVREFP0
    U5 AC20 ADCVREFP0 AST2600A3GP-AST2600A3-GP,SMLF,A   I188 @SCM_LIB.SCM(SCH_1):PAGE16
  C138    2      B Q_CAP_C0402-0.01UF,50V,10%,X7RA   I109 @SCM_LIB.SCM(SCH_1):PAGE17
  C136    2      B Q_CAP_C0402-0.01UF,50V,10%,X7RA   I110 @SCM_LIB.SCM(SCH_1):PAGE17

A_BMC_ADCVREFP1 @SCM_LIB.SCM(SCH_1):A_BMC_ADCVREFP1
    U5 AD17 ADCVREFP1 AST2600A3GP-AST2600A3-GP,SMLF,A   I188 @SCM_LIB.SCM(SCH_1):PAGE16
  C135    2      B Q_CAP_C0402-0.01UF,50V,10%,X7RA   I107 @SCM_LIB.SCM(SCH_1):PAGE17
  C137    2      B Q_CAP_C0402-0.01UF,50V,10%,X7RA   I108 @SCM_LIB.SCM(SCH_1):PAGE17

A_BMC_DACREST @SCM_LIB.SCM(SCH_1):A_BMC_DACREST
  R235    2      B Q_RES_0402LF-2.74K,1%,1/16W,CHA   I187 @SCM_LIB.SCM(SCH_1):PAGE16
    U5 AC21 DACRSET AST2600A3GP-AST2600A3-GP,SMLF,A   I188 @SCM_LIB.SCM(SCH_1):PAGE16

BATTERY_DETECT @SCM_LIB.SCM(SCH_1):BATTERY_DETECT
    U5 AE15 GPIOV4||SIOPWRGD AST2600A3GP-AST2600A3-GP,SMLF,A   I363 @SCM_LIB.SCM(SCH_1):PAGE13
  R775    1      A Q_RES_0402LF-1K,1%,1/16W,CHIP,A   I183 @SCM_LIB.SCM(SCH_1):PAGE15

BATTERY_DETECT_R @SCM_LIB.SCM(SCH_1):BATTERY_DETECT_R
   Q11    G   GATE MOSFET_N_GSD-NX7002AK,SMLF,IC,A   I179 @SCM_LIB.SCM(SCH_1):PAGE15
  R775    2      B Q_RES_0402LF-1K,1%,1/16W,CHIP,A   I183 @SCM_LIB.SCM(SCH_1):PAGE15
  R776    1      A Q_RES_0402LF-47K,1%,1/16W,CHIPA   I184 @SCM_LIB.SCM(SCH_1):PAGE15

BEEP_LED @SCM_LIB.SCM(SCH_1):BEEP_LED
    U9    1   IN_B MC74VHC1G32DTT1G-MC74VHC1G32DTA     I5 @SCM_LIB.SCM(SCH_1):PAGE49
  R306    1      A Q_RES_0402LF-10K,1%,1/16W,CHIPA     I8 @SCM_LIB.SCM(SCH_1):PAGE49
    U8    4      Y 74LVC1G126SE7-74LVC1G126SE-7,SA    I11 @SCM_LIB.SCM(SCH_1):PAGE49

BJT_Q3_B @SCM_LIB.SCM(SCH_1):BJT_Q3_B
    Q3    B      1 MMBT39047F-MMBT3904-7-F,SMLF,IA     I4 @SCM_LIB.SCM(SCH_1):PAGE22
  R290    1      A Q_RES_0402LF-47K,1%,1/16W,CHIPA     I8 @SCM_LIB.SCM(SCH_1):PAGE22

BJT_Q3_C @SCM_LIB.SCM(SCH_1):BJT_Q3_C
    Q1    B      1 MMBT39047F-MMBT3904-7-F,SMLF,IA     I2 @SCM_LIB.SCM(SCH_1):PAGE22
    Q3    C      3 MMBT39047F-MMBT3904-7-F,SMLF,IA     I4 @SCM_LIB.SCM(SCH_1):PAGE22
  R289    2      B Q_RES_0402LF-10K,1%,1/16W,CHIPA     I7 @SCM_LIB.SCM(SCH_1):PAGE22

BMC_CLK_25M @SCM_LIB.SCM(SCH_1):BMC_CLK_25M
  R215    2      B Q_RES_0402LF-33.2,1%,1/16W,CHIA    I42 @SCM_LIB.SCM(SCH_1):PAGE15
    U5  D10  CLKIN AST2600A3GP-AST2600A3-GP,SMLF,A   I350 @SCM_LIB.SCM(SCH_1):PAGE15

BMC_CLK_25M_R @SCM_LIB.SCM(SCH_1):BMC_CLK_25M_R
  OSC1    3    OUT OSC4_7X25000018-25MHZ,SMLF,MISA    I39 @SCM_LIB.SCM(SCH_1):PAGE15
  R215    1      A Q_RES_0402LF-33.2,1%,1/16W,CHIA    I42 @SCM_LIB.SCM(SCH_1):PAGE15

BMC_CPLD_GPIO_12 @SCM_LIB.SCM(SCH_1):BMC_CPLD_GPIO_12
  R607    2      B Q_RES_0402LF-4.7K,1%,1/16W,CHIA    I29 @SCM_LIB.SCM(SCH_1):PAGE42
  R536    2      B Q_RES_0402LF-33.2,1%,1/16W,CHIA   I144 @SCM_LIB.SCM(SCH_1):PAGE35

BMC_CPLD_GPIO_12_R2 @SCM_LIB.SCM(SCH_1):BMC_CPLD_GPIO_12_R2
   U25  G16   PR6A LCMXO3LF2100C5BG256C-LCMXO3LF-A     I1 @SCM_LIB.SCM(SCH_1):PAGE35
  R536    1      A Q_RES_0402LF-33.2,1%,1/16W,CHIA   I144 @SCM_LIB.SCM(SCH_1):PAGE35

BMC_CPLD_GPIO_13 @SCM_LIB.SCM(SCH_1):BMC_CPLD_GPIO_13
  R608    2      B Q_RES_0402LF-4.7K,1%,1/16W,CHIA    I27 @SCM_LIB.SCM(SCH_1):PAGE42
  R537    2      B Q_RES_0402LF-33.2,1%,1/16W,CHIA   I145 @SCM_LIB.SCM(SCH_1):PAGE35

BMC_CPLD_GPIO_13_R2 @SCM_LIB.SCM(SCH_1):BMC_CPLD_GPIO_13_R2
   U25  H15   PR6B LCMXO3LF2100C5BG256C-LCMXO3LF-A     I1 @SCM_LIB.SCM(SCH_1):PAGE35
  R537    1      A Q_RES_0402LF-33.2,1%,1/16W,CHIA   I145 @SCM_LIB.SCM(SCH_1):PAGE35

BMC_CPLD_GPIO_2 @SCM_LIB.SCM(SCH_1):BMC_CPLD_GPIO_2
  R586    2      B Q_RES_0402LF-4.7K,1%,1/16W,CHIA    I67 @SCM_LIB.SCM(SCH_1):PAGE42
  R519    1      A Q_RES_0402LF-0,5%,1/16W,CHIP,CA   I147 @SCM_LIB.SCM(SCH_1):PAGE34
   R65    2      B Q_RES_0402LF-33.2,1%,1/16W,CHIA   I421 @SCM_LIB.SCM(SCH_1):PAGE13
  R629    1      A Q_RES_0402LF-0,5%,1/16W,CHIP,CA    I78 @SCM_LIB.SCM(SCH_1):PAGE31

BMC_CPLD_GPIO_2_R1 @SCM_LIB.SCM(SCH_1):BMC_CPLD_GPIO_2_R1
    U5  T24 GPIOS7||RXD11 AST2600A3GP-AST2600A3-GP,SMLF,A   I363 @SCM_LIB.SCM(SCH_1):PAGE13
   R65    1      A Q_RES_0402LF-33.2,1%,1/16W,CHIA   I421 @SCM_LIB.SCM(SCH_1):PAGE13

BMC_CPLD_GPIO_2_R2 @SCM_LIB.SCM(SCH_1):BMC_CPLD_GPIO_2_R2
   U25   E6  PT13C LCMXO3LF2100C5BG256C-LCMXO3LF-A     I1 @SCM_LIB.SCM(SCH_1):PAGE34
  R519    2      B Q_RES_0402LF-0,5%,1/16W,CHIP,CA   I147 @SCM_LIB.SCM(SCH_1):PAGE34

BMC_CPLD_GPIO_7 @SCM_LIB.SCM(SCH_1):BMC_CPLD_GPIO_7
  R593    2      B Q_RES_0402LF-4.7K,1%,1/16W,EMPA    I39 @SCM_LIB.SCM(SCH_1):PAGE42
  R526    2      B Q_RES_0402LF-33.2,1%,1/16W,EMPA   I147 @SCM_LIB.SCM(SCH_1):PAGE35

BMC_CPLD_GPIO_7_R2 @SCM_LIB.SCM(SCH_1):BMC_CPLD_GPIO_7_R2
   U25  F15   PR3B LCMXO3LF2100C5BG256C-LCMXO3LF-A     I1 @SCM_LIB.SCM(SCH_1):PAGE35
  R526    1      A Q_RES_0402LF-33.2,1%,1/16W,EMPA   I147 @SCM_LIB.SCM(SCH_1):PAGE35

BMC_CPLD_GPIO_8 @SCM_LIB.SCM(SCH_1):BMC_CPLD_GPIO_8
  R595    2      B Q_RES_0402LF-4.7K,1%,1/16W,EMPA    I37 @SCM_LIB.SCM(SCH_1):PAGE42
  R531    2      B Q_RES_0402LF-33.2,1%,1/16W,EMPA   I146 @SCM_LIB.SCM(SCH_1):PAGE35

BMC_CPLD_GPIO_8_R2 @SCM_LIB.SCM(SCH_1):BMC_CPLD_GPIO_8_R2
   U25  F14   PR4A LCMXO3LF2100C5BG256C-LCMXO3LF-A     I1 @SCM_LIB.SCM(SCH_1):PAGE35
  R531    1      A Q_RES_0402LF-33.2,1%,1/16W,EMPA   I146 @SCM_LIB.SCM(SCH_1):PAGE35

BMC_DDC_BUF_EN @SCM_LIB.SCM(SCH_1):BMC_DDC_BUF_EN
   U33    1      1 74HC1G126GW-74HC1G126GW,SMLF,IA    I32 @SCM_LIB.SCM(SCH_1):PAGE23
   U26    1      1 74HC1G126GW-74HC1G126GW,SMLF,IA    I33 @SCM_LIB.SCM(SCH_1):PAGE23
   R30    2      B Q_RES_0402LF-0,5%,1/16W,CHIP,CA    I39 @SCM_LIB.SCM(SCH_1):PAGE23

BMC_DDC_BUF_PWR @SCM_LIB.SCM(SCH_1):BMC_DDC_BUF_PWR
   R18    2      B Q_RES_0402LF-0,5%,1/16W,CHIP,CA    I19 @SCM_LIB.SCM(SCH_1):PAGE23
   U33    5      5 74HC1G126GW-74HC1G126GW,SMLF,IA    I32 @SCM_LIB.SCM(SCH_1):PAGE23
   U26    5      5 74HC1G126GW-74HC1G126GW,SMLF,IA    I33 @SCM_LIB.SCM(SCH_1):PAGE23

BMC_EMMC_CD_N @SCM_LIB.SCM(SCH_1):BMC_EMMC_CD_N
    U5  A24 GPIOF6||SD1CD#||PWM14 AST2600A3GP-AST2600A3-GP,SMLF,A   I436 @SCM_LIB.SCM(SCH_1):PAGE12
  R685    1      A Q_RES_0402LF-1K,1%,1/16W,EMPTYB   I165 @SCM_LIB.SCM(SCH_1):PAGE14
  R687    2      B Q_RES_0402LF-4.7K,1%,1/16W,EMPB   I166 @SCM_LIB.SCM(SCH_1):PAGE14

BMC_EMMC_CLK @SCM_LIB.SCM(SCH_1):BMC_EMMC_CLK
    U5  D22 GPIOF0||SD1CLK||PWM8 AST2600A3GP-AST2600A3-GP,SMLF,A   I436 @SCM_LIB.SCM(SCH_1):PAGE12
  R654    2      B Q_RES_0402LF-33.2,1%,1/16W,EMPA    I33 @SCM_LIB.SCM(SCH_1):PAGE21

BMC_EMMC_CMD @SCM_LIB.SCM(SCH_1):BMC_EMMC_CMD
    U5  E22 GPIOF1||SD1CMD||PWM9 AST2600A3GP-AST2600A3-GP,SMLF,A   I436 @SCM_LIB.SCM(SCH_1):PAGE12
   R48    2      B Q_RES_0402LF-33.2,1%,1/16W,EMPA    I35 @SCM_LIB.SCM(SCH_1):PAGE21

BMC_EMMC_DT0 @SCM_LIB.SCM(SCH_1):BMC_EMMC_DT0
    U5  D23 GPIOF2||SD1DAT0||PWM10 AST2600A3GP-AST2600A3-GP,SMLF,A   I436 @SCM_LIB.SCM(SCH_1):PAGE12
  R649    2      B Q_RES_0402LF-33.2,1%,1/16W,EMPA    I42 @SCM_LIB.SCM(SCH_1):PAGE21

BMC_EMMC_DT1 @SCM_LIB.SCM(SCH_1):BMC_EMMC_DT1
    U5  C23 GPIOF3||SD1DAT1||PWM11 AST2600A3GP-AST2600A3-GP,SMLF,A   I436 @SCM_LIB.SCM(SCH_1):PAGE12
  R648    2      B Q_RES_0402LF-33.2,1%,1/16W,EMPA    I43 @SCM_LIB.SCM(SCH_1):PAGE21

BMC_EMMC_DT2 @SCM_LIB.SCM(SCH_1):BMC_EMMC_DT2
    U5  C22 GPIOF4||SD1DAT2||PWM12 AST2600A3GP-AST2600A3-GP,SMLF,A   I436 @SCM_LIB.SCM(SCH_1):PAGE12
  R647    2      B Q_RES_0402LF-33.2,1%,1/16W,EMPA    I45 @SCM_LIB.SCM(SCH_1):PAGE21

BMC_EMMC_DT3 @SCM_LIB.SCM(SCH_1):BMC_EMMC_DT3
    U5  A25 GPIOF5||SD1DAT3||PWM13 AST2600A3GP-AST2600A3-GP,SMLF,A   I436 @SCM_LIB.SCM(SCH_1):PAGE12
  R532    2      B Q_RES_0402LF-33.2,1%,1/16W,EMPA    I46 @SCM_LIB.SCM(SCH_1):PAGE21

BMC_EMMC_DT4 @SCM_LIB.SCM(SCH_1):BMC_EMMC_DT4
    U5  C21 GPIOG2||TXD7||SD2DAT0||SALT11 AST2600A3GP-AST2600A3-GP,SMLF,A   I436 @SCM_LIB.SCM(SCH_1):PAGE12
  R653    1      A Q_RES_0402LF-33.2,1%,1/16W,EMPA   I100 @SCM_LIB.SCM(SCH_1):PAGE21

BMC_EMMC_DT5 @SCM_LIB.SCM(SCH_1):BMC_EMMC_DT5
    U5  A22 GPIOG3||RXD7||SD2DAT1||SALT12 AST2600A3GP-AST2600A3-GP,SMLF,A   I436 @SCM_LIB.SCM(SCH_1):PAGE12
  R652    1      A Q_RES_0402LF-33.2,1%,1/16W,EMPA   I101 @SCM_LIB.SCM(SCH_1):PAGE21

BMC_EMMC_DT6 @SCM_LIB.SCM(SCH_1):BMC_EMMC_DT6
    U5  A21 GPIOG4||TXD8||SD2DAT2||SALT13 AST2600A3GP-AST2600A3-GP,SMLF,A   I436 @SCM_LIB.SCM(SCH_1):PAGE12
  R651    1      A Q_RES_0402LF-33.2,1%,1/16W,EMPA    I98 @SCM_LIB.SCM(SCH_1):PAGE21

BMC_EMMC_DT7 @SCM_LIB.SCM(SCH_1):BMC_EMMC_DT7
    U5  E20 GPIOG5||RXD8||SD2DAT3||SALT14 AST2600A3GP-AST2600A3-GP,SMLF,A   I436 @SCM_LIB.SCM(SCH_1):PAGE12
  R650    1      A Q_RES_0402LF-33.2,1%,1/16W,EMPA    I99 @SCM_LIB.SCM(SCH_1):PAGE21

BMC_EMMC_RST_N @SCM_LIB.SCM(SCH_1):BMC_EMMC_RST_N
   R96    2      B Q_RES_0402LF-33.2,1%,1/16W,CHIA   I286 @SCM_LIB.SCM(SCH_1):PAGE13
    J4   66     66 SCONN67_NASA0S6730TS67-SCONN67A    I84 @SCM_LIB.SCM(SCH_1):PAGE21
   R11    2      B Q_RES_0402LF-4.7K,1%,1/16W,CHIA   I172 @SCM_LIB.SCM(SCH_1):PAGE21

BMC_EMMC_RST_R_N @SCM_LIB.SCM(SCH_1):BMC_EMMC_RST_R_N
   R96    1      A Q_RES_0402LF-33.2,1%,1/16W,CHIA   I286 @SCM_LIB.SCM(SCH_1):PAGE13
    U5 AA12 GPIOY3||SALT8||WDTRST4# AST2600A3GP-AST2600A3-GP,SMLF,A   I363 @SCM_LIB.SCM(SCH_1):PAGE13

BMC_EMMC_WP_N @SCM_LIB.SCM(SCH_1):BMC_EMMC_WP_N
    U5  A23 GPIOF7||SD1WP#||PWM15 AST2600A3GP-AST2600A3-GP,SMLF,A   I436 @SCM_LIB.SCM(SCH_1):PAGE12
  R684    1      A Q_RES_0402LF-1K,1%,1/16W,EMPTYB   I163 @SCM_LIB.SCM(SCH_1):PAGE14
  R686    2      B Q_RES_0402LF-4.7K,1%,1/16W,EMPB   I164 @SCM_LIB.SCM(SCH_1):PAGE14

BMC_HEARTBEAT_N @SCM_LIB.SCM(SCH_1):BMC_HEARTBEAT_N
    D8    C      C Q_LED_SMLF-LED_GREEN,19-213/GVA    I46 @SCM_LIB.SCM(SCH_1):PAGE13
  R805    2      B Q_RES_0402LF-4.7K,1%,1/16W,CHIA   I356 @SCM_LIB.SCM(SCH_1):PAGE13
    U5  Y23 GPIOP7||PWM15||HBLED# AST2600A3GP-AST2600A3-GP,SMLF,A   I350 @SCM_LIB.SCM(SCH_1):PAGE15

BMC_HEARTBEAT_R_N @SCM_LIB.SCM(SCH_1):BMC_HEARTBEAT_R_N
  R167    2      B Q_RES_0402LF-330,1%,1/16W,CHIPA    I33 @SCM_LIB.SCM(SCH_1):PAGE13
    D8    A      A Q_LED_SMLF-LED_GREEN,19-213/GVA    I46 @SCM_LIB.SCM(SCH_1):PAGE13

BMC_ID_BEEP_SEL @SCM_LIB.SCM(SCH_1):BMC_ID_BEEP_SEL
  R461    1      A Q_RES_0402LF-33.2,1%,1/16W,CHIA   I365 @SCM_LIB.SCM(SCH_1):PAGE13
  R319    2      B Q_RES_0402LF-4.7K,1%,1/16W,CHIA    I65 @SCM_LIB.SCM(SCH_1):PAGE42
    U8    1     OE 74LVC1G126SE7-74LVC1G126SE-7,SA    I11 @SCM_LIB.SCM(SCH_1):PAGE49

BMC_ID_BEEP_SEL_R1 @SCM_LIB.SCM(SCH_1):BMC_ID_BEEP_SEL_R1
    U5 AD14 GPIOV2||SIOPWREQ# AST2600A3GP-AST2600A3-GP,SMLF,A   I363 @SCM_LIB.SCM(SCH_1):PAGE13
  R461    2      B Q_RES_0402LF-33.2,1%,1/16W,CHIA   I365 @SCM_LIB.SCM(SCH_1):PAGE13

BMC_MONITER @SCM_LIB.SCM(SCH_1):BMC_MONITER
    U5  T25 GPIOS1||MDIO1 AST2600A3GP-AST2600A3-GP,SMLF,A   I363 @SCM_LIB.SCM(SCH_1):PAGE13
   U25   M6  PB11C LCMXO3LF2100C5BG256C-LCMXO3LF-A     I1 @SCM_LIB.SCM(SCH_1):PAGE36

BMC_PWR_LED @SCM_LIB.SCM(SCH_1):BMC_PWR_LED
  R316    1      A Q_RES_0402LF-0,5%,1/16W,CHIP,CA   I318 @SCM_LIB.SCM(SCH_1):PAGE15
    U5  W23 GPIOP4||PWM12||THRUIN2 AST2600A3GP-AST2600A3-GP,SMLF,A   I350 @SCM_LIB.SCM(SCH_1):PAGE15

BMC_RSTIND_N @SCM_LIB.SCM(SCH_1):BMC_RSTIND_N
  R548    1      A Q_RES_0402LF-33.2,1%,1/16W,CHIA   I172 @SCM_LIB.SCM(SCH_1):PAGE25
  R585    1      A Q_RES_0402LF-33.2,1%,1/16W,CHIA   I404 @SCM_LIB.SCM(SCH_1):PAGE15

BSM_PRSNT_N @SCM_LIB.SCM(SCH_1):BSM_PRSNT_N
    J4   16     16 SCONN67_NASA0S6730TS67-SCONN67A    I84 @SCM_LIB.SCM(SCH_1):PAGE21
  R404    2      B Q_RES_0402LF-10K,1%,1/16W,CHIPA   I166 @SCM_LIB.SCM(SCH_1):PAGE21
   R57    2      B Q_RES_0402LF-0,5%,1/16W,CHIP,CA   I167 @SCM_LIB.SCM(SCH_1):PAGE21

BSM_PRSNT_R1_N @SCM_LIB.SCM(SCH_1):BSM_PRSNT_R1_N
   U25   A3  PT11C LCMXO3LF2100C5BG256C-LCMXO3LF-A     I1 @SCM_LIB.SCM(SCH_1):PAGE34
  R459    2      B Q_RES_0402LF-33.2,1%,1/16W,CHIA   I159 @SCM_LIB.SCM(SCH_1):PAGE34

BSM_PRSNT_R_N @SCM_LIB.SCM(SCH_1):BSM_PRSNT_R_N
    U5 AC16 ADC12||GPIU4||SALT13 AST2600A3GP-AST2600A3-GP,SMLF,A   I350 @SCM_LIB.SCM(SCH_1):PAGE15
   R57    1      A Q_RES_0402LF-0,5%,1/16W,CHIP,CA   I167 @SCM_LIB.SCM(SCH_1):PAGE21
  R459    1      A Q_RES_0402LF-33.2,1%,1/16W,CHIA   I159 @SCM_LIB.SCM(SCH_1):PAGE34

CLK_100M_GPU_DN @SCM_LIB.SCM(SCH_1):CLK_100M_GPU_DN
   GF1  A69 PCIE_HPM_RXN_3 FCONN168_ME1016810202011_SCM-FA   I553 @SCM_LIB.SCM(SCH_1):PAGE10
    U5  AE2 RCREFCLKN AST2600A3GP-AST2600A3-GP,SMLF,A   I436 @SCM_LIB.SCM(SCH_1):PAGE12

CLK_100M_GPU_DP @SCM_LIB.SCM(SCH_1):CLK_100M_GPU_DP
   GF1  A68 PCIE_HPM_RXP_3 FCONN168_ME1016810202011_SCM-FA   I553 @SCM_LIB.SCM(SCH_1):PAGE10
    U5  AE1 RCREFCLKP AST2600A3GP-AST2600A3-GP,SMLF,A   I436 @SCM_LIB.SCM(SCH_1):PAGE12

CLK_100M_PCH_DN @SCM_LIB.SCM(SCH_1):CLK_100M_PCH_DN
   GF1  A15 CLK_100M_PCIE_DN FCONN168_ME1016810202011_SCM-FA   I553 @SCM_LIB.SCM(SCH_1):PAGE10
    U5  AD6 PEREFCLKN AST2600A3GP-AST2600A3-GP,SMLF,A   I436 @SCM_LIB.SCM(SCH_1):PAGE12

CLK_100M_PCH_DP @SCM_LIB.SCM(SCH_1):CLK_100M_PCH_DP
   GF1  A14 CLK_100M_PCIE_DP FCONN168_ME1016810202011_SCM-FA   I553 @SCM_LIB.SCM(SCH_1):PAGE10
    U5  AD5 PEREFCLKP AST2600A3GP-AST2600A3-GP,SMLF,A   I436 @SCM_LIB.SCM(SCH_1):PAGE12

CLK_25M_OSC_FPGA @SCM_LIB.SCM(SCH_1):CLK_25M_OSC_FPGA
   U25   C8 PT17A||PCLKT0_1 LCMXO3LF2100C5BG256C-LCMXO3LF-A     I1 @SCM_LIB.SCM(SCH_1):PAGE34
  R807    2      B Q_RES_0402LF-33.2,1%,1/16W,CHIA   I126 @SCM_LIB.SCM(SCH_1):PAGE34

CLK_25M_OSC_FPGA_R @SCM_LIB.SCM(SCH_1):CLK_25M_OSC_FPGA_R
  R807    1      A Q_RES_0402LF-33.2,1%,1/16W,CHIA   I126 @SCM_LIB.SCM(SCH_1):PAGE34
  OSC2    3    OUT OSC4_7X25000018-25MHZ,SMLF,MISA   I127 @SCM_LIB.SCM(SCH_1):PAGE34

CLK_BUF1_GPU_FPGA_OE_R_N @SCM_LIB.SCM(SCH_1):CLK_BUF1_GPU_FPGA_OE_R_N
    U5  F26 RGMII3RXD1||RMII3RXD1||GPIOD1 AST2600A3GP-AST2600A3-GP,SMLF,A   I363 @SCM_LIB.SCM(SCH_1):PAGE13
   U25   N8  PB12C LCMXO3LF2100C5BG256C-LCMXO3LF-A     I1 @SCM_LIB.SCM(SCH_1):PAGE36

CLK_GEN2_BMC_RC_OE_N @SCM_LIB.SCM(SCH_1):CLK_GEN2_BMC_RC_OE_N
    U5 AF10 GPIOZ7||SPI1DQ3||RXD13 AST2600A3GP-AST2600A3-GP,SMLF,A   I363 @SCM_LIB.SCM(SCH_1):PAGE13
   U25   M7   PB9C LCMXO3LF2100C5BG256C-LCMXO3LF-A     I1 @SCM_LIB.SCM(SCH_1):PAGE36

CRT_VCC5 @SCM_LIB.SCM(SCH_1):CRT_VCC5
   R30    1      A Q_RES_0402LF-0,5%,1/16W,CHIP,CA    I39 @SCM_LIB.SCM(SCH_1):PAGE23
   R27    2      B Q_RES_0603LF-0,5%,1/10W,EMPTY,A    I40 @SCM_LIB.SCM(SCH_1):PAGE23
   D11    C      C SCHOTTKY_AC-SS0530,SMLF,IC,BCSA    I41 @SCM_LIB.SCM(SCH_1):PAGE23
    D9    C      C SCHOTTKY_AC-SS0530,SMLF,EMPTY,A    I42 @SCM_LIB.SCM(SCH_1):PAGE23
  C204    1      A Q_CAP_0603-1UF,16V,10%,EMPTY,TA    I45 @SCM_LIB.SCM(SCH_1):PAGE23
   R91    1      A Q_RES_0402LF-2.2K,5%,1/16W,CHIA    I62 @SCM_LIB.SCM(SCH_1):PAGE23
   R92    1      A Q_RES_0402LF-2.2K,5%,1/16W,CHIA    I64 @SCM_LIB.SCM(SCH_1):PAGE23
   R17    2      B Q_RES_0402LF-2.21K,1%,1/16W,EMA    I68 @SCM_LIB.SCM(SCH_1):PAGE23
   D12    1      1 BZA462A-BZA462A,SMLF,EMPTY,BCZA    I74 @SCM_LIB.SCM(SCH_1):PAGE23
   D12    3      3 BZA462A-BZA462A,SMLF,EMPTY,BCZA    I74 @SCM_LIB.SCM(SCH_1):PAGE23
   D12    4      4 BZA462A-BZA462A,SMLF,EMPTY,BCZA    I74 @SCM_LIB.SCM(SCH_1):PAGE23
   D12    6      6 BZA462A-BZA462A,SMLF,EMPTY,BCZA    I74 @SCM_LIB.SCM(SCH_1):PAGE23
   R16    2      B Q_RES_0402LF-2.21K,1%,1/16W,EMA    I75 @SCM_LIB.SCM(SCH_1):PAGE23

CRT_VCC5_2_D @SCM_LIB.SCM(SCH_1):CRT_VCC5_2_D
   FS1    1      1 Q_FUSE_SMLF-1.1A/8V,EMPTY,DK11A   I153 @SCM_LIB.SCM(SCH_1):PAGE23
   D16    2      C SCHOTTKY_12-SBA130Q,SMLF,EMPTYA   I161 @SCM_LIB.SCM(SCH_1):PAGE23

CRT_VCC5_2_FUSE @SCM_LIB.SCM(SCH_1):CRT_VCC5_2_FUSE
   FS1    2      2 Q_FUSE_SMLF-1.1A/8V,EMPTY,DK11A   I153 @SCM_LIB.SCM(SCH_1):PAGE23
    J8   13     13 SCONN13_502280130CV01-SCONN13_A   I165 @SCM_LIB.SCM(SCH_1):PAGE23

DEBUG_PORT_PRSNT @SCM_LIB.SCM(SCH_1):DEBUG_PORT_PRSNT
   U23    2      A 74LVC1G07W57-74LVC1G07W5-7,SMLA   I180 @SCM_LIB.SCM(SCH_1):PAGE28
   U36    1      1 74HC1G126GW-74HC1G126GW,SMLF,IA   I164 @SCM_LIB.SCM(SCH_1):PAGE29
   U29    1      1 74HC1G126GW-74HC1G126GW,SMLF,IA   I174 @SCM_LIB.SCM(SCH_1):PAGE29
    Q6    G      G 2N7002A7-2N7002A-7,SMLF,IC,BAMA   I202 @SCM_LIB.SCM(SCH_1):PAGE29
   U22    9    SEL PI3PCIE3212ZBEX-PI3PCIE3212ZBEA   I206 @SCM_LIB.SCM(SCH_1):PAGE29
  R693    1      A Q_RES_0402LF-33.2,1%,1/16W,CHIA   I222 @SCM_LIB.SCM(SCH_1):PAGE29

DEBUG_PORT_PRSNT_BUF_EN @SCM_LIB.SCM(SCH_1):DEBUG_PORT_PRSNT_BUF_EN
   U37    5 ENABLE PCA9517ADP_SMLF-PCA9517ADP,IC,A    I99 @SCM_LIB.SCM(SCH_1):PAGE28
  R670    2      B Q_RES_0402LF-0,5%,1/16W,CHIP,CA   I104 @SCM_LIB.SCM(SCH_1):PAGE28

DEBUG_PORT_PRSNT_BUF_R_EN @SCM_LIB.SCM(SCH_1):DEBUG_PORT_PRSNT_BUF_R_EN
  R670    1      A Q_RES_0402LF-0,5%,1/16W,CHIP,CA   I104 @SCM_LIB.SCM(SCH_1):PAGE28
  R296    1      A Q_RES_0402LF-100K,1%,1/16W,EMPA   I105 @SCM_LIB.SCM(SCH_1):PAGE28
  R295    2      B Q_RES_0402LF-10K,1%,1/16W,CHIPA   I113 @SCM_LIB.SCM(SCH_1):PAGE28
   U23    4      Y 74LVC1G07W57-74LVC1G07W5-7,SMLA   I180 @SCM_LIB.SCM(SCH_1):PAGE28

DEBUG_PORT_PRSNT_R @SCM_LIB.SCM(SCH_1):DEBUG_PORT_PRSNT_R
  R205    1      A Q_RES_0402LF-20K,1%,1/16W,CHIPA   I184 @SCM_LIB.SCM(SCH_1):PAGE29
    J2    7  GND_D CONN9_GSB3111315HR-CONN9_GSB31A   I221 @SCM_LIB.SCM(SCH_1):PAGE29
  R693    2      B Q_RES_0402LF-33.2,1%,1/16W,CHIA   I222 @SCM_LIB.SCM(SCH_1):PAGE29

DEBUG_PORT_UART_RX @SCM_LIB.SCM(SCH_1):DEBUG_PORT_UART_RX
  R274    2      B Q_RES_0402LF-100K,1%,1/16W,EMPA   I157 @SCM_LIB.SCM(SCH_1):PAGE29
   U36    2      2 74HC1G126GW-74HC1G126GW,SMLF,IA   I164 @SCM_LIB.SCM(SCH_1):PAGE29
   U22   15   C0_P PI3PCIE3212ZBEX-PI3PCIE3212ZBEA   I206 @SCM_LIB.SCM(SCH_1):PAGE29

DEBUG_PORT_UART_TX @SCM_LIB.SCM(SCH_1):DEBUG_PORT_UART_TX
  R219    1      A Q_RES_0402LF-100K,1%,1/16W,EMPA   I170 @SCM_LIB.SCM(SCH_1):PAGE29
   U29    4      4 74HC1G126GW-74HC1G126GW,SMLF,IA   I174 @SCM_LIB.SCM(SCH_1):PAGE29
   U22   14   C0_N PI3PCIE3212ZBEX-PI3PCIE3212ZBEA   I206 @SCM_LIB.SCM(SCH_1):PAGE29

DP_BMC_HPD_3V3_BUF @SCM_LIB.SCM(SCH_1):DP_BMC_HPD_3V3_BUF
    U5   C7  DPHPD AST2600A3GP-AST2600A3-GP,SMLF,A   I436 @SCM_LIB.SCM(SCH_1):PAGE12
  R387    2      B Q_RES_0402LF-100K,1%,1/16W,CHIA   I508 @SCM_LIB.SCM(SCH_1):PAGE12

EMMC_CLK_R @SCM_LIB.SCM(SCH_1):EMMC_CLK_R
  R654    1      A Q_RES_0402LF-33.2,1%,1/16W,EMPA    I33 @SCM_LIB.SCM(SCH_1):PAGE21
    J4   55     55 SCONN67_NASA0S6730TS67-SCONN67A    I84 @SCM_LIB.SCM(SCH_1):PAGE21

EMMC_CMD_R @SCM_LIB.SCM(SCH_1):EMMC_CMD_R
   R48    1      A Q_RES_0402LF-33.2,1%,1/16W,EMPA    I35 @SCM_LIB.SCM(SCH_1):PAGE21
  R663    2      B Q_RES_0402LF-10K,1%,1/16W,EMPTB    I59 @SCM_LIB.SCM(SCH_1):PAGE21
    J4   59     59 SCONN67_NASA0S6730TS67-SCONN67A    I84 @SCM_LIB.SCM(SCH_1):PAGE21

EMMC_DT0_R @SCM_LIB.SCM(SCH_1):EMMC_DT0_R
  R649    1      A Q_RES_0402LF-33.2,1%,1/16W,EMPA    I42 @SCM_LIB.SCM(SCH_1):PAGE21
  R655    2      B Q_RES_0402LF-10K,1%,1/16W,EMPTB    I67 @SCM_LIB.SCM(SCH_1):PAGE21
    J4   71     71 SCONN67_NASA0S6730TS67-SCONN67A    I84 @SCM_LIB.SCM(SCH_1):PAGE21

EMMC_DT1_R @SCM_LIB.SCM(SCH_1):EMMC_DT1_R
  R648    1      A Q_RES_0402LF-33.2,1%,1/16W,EMPA    I43 @SCM_LIB.SCM(SCH_1):PAGE21
  R656    2      B Q_RES_0402LF-10K,1%,1/16W,EMPTB    I66 @SCM_LIB.SCM(SCH_1):PAGE21
    J4   67     67 SCONN67_NASA0S6730TS67-SCONN67A    I84 @SCM_LIB.SCM(SCH_1):PAGE21

EMMC_DT2_R @SCM_LIB.SCM(SCH_1):EMMC_DT2_R
  R647    1      A Q_RES_0402LF-33.2,1%,1/16W,EMPA    I45 @SCM_LIB.SCM(SCH_1):PAGE21
  R657    2      B Q_RES_0402LF-10K,1%,1/16W,EMPTB    I63 @SCM_LIB.SCM(SCH_1):PAGE21
    J4   65     65 SCONN67_NASA0S6730TS67-SCONN67A    I84 @SCM_LIB.SCM(SCH_1):PAGE21

EMMC_DT3_R @SCM_LIB.SCM(SCH_1):EMMC_DT3_R
  R532    1      A Q_RES_0402LF-33.2,1%,1/16W,EMPA    I46 @SCM_LIB.SCM(SCH_1):PAGE21
  R658    2      B Q_RES_0402LF-10K,1%,1/16W,EMPTB    I62 @SCM_LIB.SCM(SCH_1):PAGE21
    J4   61     61 SCONN67_NASA0S6730TS67-SCONN67A    I84 @SCM_LIB.SCM(SCH_1):PAGE21

EMMC_DT4_R @SCM_LIB.SCM(SCH_1):EMMC_DT4_R
  R659    2      B Q_RES_0402LF-10K,1%,1/16W,EMPTB    I64 @SCM_LIB.SCM(SCH_1):PAGE21
    J4   58     58 SCONN67_NASA0S6730TS67-SCONN67A    I84 @SCM_LIB.SCM(SCH_1):PAGE21
  R653    2      B Q_RES_0402LF-33.2,1%,1/16W,EMPA   I100 @SCM_LIB.SCM(SCH_1):PAGE21

EMMC_DT5_R @SCM_LIB.SCM(SCH_1):EMMC_DT5_R
  R660    2      B Q_RES_0402LF-10K,1%,1/16W,EMPTB    I61 @SCM_LIB.SCM(SCH_1):PAGE21
    J4   56     56 SCONN67_NASA0S6730TS67-SCONN67A    I84 @SCM_LIB.SCM(SCH_1):PAGE21
  R652    2      B Q_RES_0402LF-33.2,1%,1/16W,EMPA   I101 @SCM_LIB.SCM(SCH_1):PAGE21

EMMC_DT6_R @SCM_LIB.SCM(SCH_1):EMMC_DT6_R
  R661    2      B Q_RES_0402LF-10K,1%,1/16W,EMPTB    I60 @SCM_LIB.SCM(SCH_1):PAGE21
    J4   54     54 SCONN67_NASA0S6730TS67-SCONN67A    I84 @SCM_LIB.SCM(SCH_1):PAGE21
  R651    2      B Q_RES_0402LF-33.2,1%,1/16W,EMPA    I98 @SCM_LIB.SCM(SCH_1):PAGE21

EMMC_DT7_R @SCM_LIB.SCM(SCH_1):EMMC_DT7_R
  R662    2      B Q_RES_0402LF-10K,1%,1/16W,EMPTB    I58 @SCM_LIB.SCM(SCH_1):PAGE21
    J4   52     52 SCONN67_NASA0S6730TS67-SCONN67A    I84 @SCM_LIB.SCM(SCH_1):PAGE21
  R650    2      B Q_RES_0402LF-33.2,1%,1/16W,EMPA    I99 @SCM_LIB.SCM(SCH_1):PAGE21

EMMC_WP @SCM_LIB.SCM(SCH_1):EMMC_WP
    J4   46     46 SCONN67_NASA0S6730TS67-SCONN67A    I84 @SCM_LIB.SCM(SCH_1):PAGE21
  R867    2      B Q_RES_0402LF-1K,1%,1/16W,EMPTYA   I161 @SCM_LIB.SCM(SCH_1):PAGE21

EN_P1V0_AUX @SCM_LIB.SCM(SCH_1):EN_P1V0_AUX
  R399    1      A Q_RES_0402LF-0,5%,1/16W,CHIP,CA    I55 @SCM_LIB.SCM(SCH_1):PAGE56
   U53    4      Y 74LVC1G08GW_SM-74LVC1G08GW,IC,A    I66 @SCM_LIB.SCM(SCH_1):PAGE56

EN_P1V0_AUX_R @SCM_LIB.SCM(SCH_1):EN_P1V0_AUX_R
  PU42    5     EN NB695GDZ-NB695GD-Z,SMLF,IC,AL0A    I15 @SCM_LIB.SCM(SCH_1):PAGE56
  R399    2      B Q_RES_0402LF-0,5%,1/16W,CHIP,CA    I55 @SCM_LIB.SCM(SCH_1):PAGE56
  R878    2      B Q_RES_0402LF-0,5%,1/16W,EMPTY,A    I72 @SCM_LIB.SCM(SCH_1):PAGE56

EN_P1V2_AUX @SCM_LIB.SCM(SCH_1):EN_P1V2_AUX
  R708    1      A Q_RES_0402LF-0,5%,1/16W,CHIP,CA    I38 @SCM_LIB.SCM(SCH_1):PAGE55
   U52    4      Y 74LVC1G08GW_SM-74LVC1G08GW,IC,A    I63 @SCM_LIB.SCM(SCH_1):PAGE55

EN_P1V2_AUX_R @SCM_LIB.SCM(SCH_1):EN_P1V2_AUX_R
  PU41    5     EN NB695GDZ-NB695GD-Z,SMLF,IC,AL0A    I15 @SCM_LIB.SCM(SCH_1):PAGE55
  R708    2      B Q_RES_0402LF-0,5%,1/16W,CHIP,CA    I38 @SCM_LIB.SCM(SCH_1):PAGE55
  R764    2      B Q_RES_0402LF-0,5%,1/16W,EMPTY,A    I41 @SCM_LIB.SCM(SCH_1):PAGE55
  R876    2      B Q_RES_0402LF-0,5%,1/16W,EMPTY,A    I68 @SCM_LIB.SCM(SCH_1):PAGE55

EN_P1V8 @SCM_LIB.SCM(SCH_1):EN_P1V8
  R393    1      A Q_RES_0402LF-0,5%,1/16W,CHIP,CA   I102 @SCM_LIB.SCM(SCH_1):PAGE54
   U49    4  OUT_Y MC74VHC1G32DTT1G-MC74VHC1G32DTA   I116 @SCM_LIB.SCM(SCH_1):PAGE54

EN_P1V8_R @SCM_LIB.SCM(SCH_1):EN_P1V8_R
   U41    6     EN RT9059GQW-RT9059GQW,SMLF,IC,ALA    I96 @SCM_LIB.SCM(SCH_1):PAGE54
  R393    2      B Q_RES_0402LF-0,5%,1/16W,CHIP,CA   I102 @SCM_LIB.SCM(SCH_1):PAGE54
  R875    2      B Q_RES_0402LF-0,5%,1/16W,EMPTY,A   I137 @SCM_LIB.SCM(SCH_1):PAGE54

EN_P3V3 @SCM_LIB.SCM(SCH_1):EN_P3V3
  R381    1      A Q_RES_0402LF-0,5%,1/16W,CHIP,CA    I97 @SCM_LIB.SCM(SCH_1):PAGE52
   U42    4  OUT_Y MC74VHC1G32DTT1G-MC74VHC1G32DTA   I104 @SCM_LIB.SCM(SCH_1):PAGE52

EN_P3V3_R1 @SCM_LIB.SCM(SCH_1):EN_P3V3_R1
  R868    2      B Q_RES_0402LF-0,5%,1/16W,EMPTY,A    I54 @SCM_LIB.SCM(SCH_1):PAGE51
  R871    1      A Q_RES_0402LF-0,5%,1/16W,EMPTY,A   I137 @SCM_LIB.SCM(SCH_1):PAGE52

EN_P3V3_RGM @SCM_LIB.SCM(SCH_1):EN_P3V3_RGM
   U18    4      Y 74LVC1G08GW_SM-74LVC1G08GW,IC,A   I114 @SCM_LIB.SCM(SCH_1):PAGE52
  R380    1      A Q_RES_0402LF-100,1%,1/16W,CHIPA   I147 @SCM_LIB.SCM(SCH_1):PAGE52

EN_P3V3_RGM_R @SCM_LIB.SCM(SCH_1):EN_P3V3_RGM_R
   U14    4     EN AP22811AW57-AP22811AW5-7,SMLF,A    I79 @SCM_LIB.SCM(SCH_1):PAGE52
  R869    2      B Q_RES_0402LF-0,5%,1/16W,EMPTY,A   I139 @SCM_LIB.SCM(SCH_1):PAGE52
  R380    2      B Q_RES_0402LF-100,1%,1/16W,CHIPA   I147 @SCM_LIB.SCM(SCH_1):PAGE52

EN_P5V_AUX @SCM_LIB.SCM(SCH_1):EN_P5V_AUX
 PC205    1      A Q_CAP_0402-0.1UF,25V,10%,X7R,CA     I1 @SCM_LIB.SCM(SCH_1):PAGE51
 PR522    1      A Q_RES_0402LF-100K,1%,1/16W,CHIA     I3 @SCM_LIB.SCM(SCH_1):PAGE51
 PR521    2      B Q_RES_0402LF-681K,1%,1/16W,CHIA     I4 @SCM_LIB.SCM(SCH_1):PAGE51
  PU38    8     EN MPQ8633AGLEC807Z-MPQ8633AGLE-CA    I42 @SCM_LIB.SCM(SCH_1):PAGE51

ESPI_HOST_LPC_BMC_CLK @SCM_LIB.SCM(SCH_1):ESPI_HOST_LPC_BMC_CLK
   GF1   B1 ESPI_CLK FCONN168_ME1016810202011_SCM-FA   I553 @SCM_LIB.SCM(SCH_1):PAGE10
  R310    1      A Q_RES_0402LF-33.2,1%,1/16W,CHIA   I441 @SCM_LIB.SCM(SCH_1):PAGE12

ESPI_HOST_LPC_BMC_CLK_R @SCM_LIB.SCM(SCH_1):ESPI_HOST_LPC_BMC_CLK_R
    U5  AE7 GPIOW4||LCLK||ESPICK AST2600A3GP-AST2600A3-GP,SMLF,A   I436 @SCM_LIB.SCM(SCH_1):PAGE12
  R310    2      B Q_RES_0402LF-33.2,1%,1/16W,CHIA   I441 @SCM_LIB.SCM(SCH_1):PAGE12

ESPI_HOST_LPC_BMC_LFRAME_N @SCM_LIB.SCM(SCH_1):ESPI_HOST_LPC_BMC_LFRAME_N
   GF1   B2 ESPI_CS0_N FCONN168_ME1016810202011_SCM-FA   I553 @SCM_LIB.SCM(SCH_1):PAGE10
  R115    2      B Q_RES_0402LF-4.7K,1%,1/16W,EMPA     I4 @SCM_LIB.SCM(SCH_1):PAGE12
  R311    1      A Q_RES_0402LF-33.2,1%,1/16W,CHIA   I447 @SCM_LIB.SCM(SCH_1):PAGE12

ESPI_HOST_LPC_BMC_LFRAME_N_R @SCM_LIB.SCM(SCH_1):ESPI_HOST_LPC_BMC_LFRAME_N_R
    U5  AF7 GPIOW5||LFRAME#||ESPICS# AST2600A3GP-AST2600A3-GP,SMLF,A   I436 @SCM_LIB.SCM(SCH_1):PAGE12
  R311    2      B Q_RES_0402LF-33.2,1%,1/16W,CHIA   I447 @SCM_LIB.SCM(SCH_1):PAGE12

ESPI_LPC_D0_IO0 @SCM_LIB.SCM(SCH_1):ESPI_LPC_D0_IO0
    U5  AB7 GPIOW0||LAD0||ESPID0 AST2600A3GP-AST2600A3-GP,SMLF,A   I436 @SCM_LIB.SCM(SCH_1):PAGE12
  R128    1      A Q_RES_0402LF-22,1%,1/16W,CHIP,A   I442 @SCM_LIB.SCM(SCH_1):PAGE12

ESPI_LPC_D1_IO1 @SCM_LIB.SCM(SCH_1):ESPI_LPC_D1_IO1
    U5  AB8 GPIOW1||LAD1||ESPID1 AST2600A3GP-AST2600A3-GP,SMLF,A   I436 @SCM_LIB.SCM(SCH_1):PAGE12
  R129    1      A Q_RES_0402LF-22,1%,1/16W,CHIP,A   I445 @SCM_LIB.SCM(SCH_1):PAGE12

ESPI_LPC_D2_IO2 @SCM_LIB.SCM(SCH_1):ESPI_LPC_D2_IO2
    U5  AC8 GPIOW2||LAD2||ESPID2 AST2600A3GP-AST2600A3-GP,SMLF,A   I436 @SCM_LIB.SCM(SCH_1):PAGE12
  R130    1      A Q_RES_0402LF-22,1%,1/16W,CHIP,A   I444 @SCM_LIB.SCM(SCH_1):PAGE12

ESPI_LPC_D3_IO3 @SCM_LIB.SCM(SCH_1):ESPI_LPC_D3_IO3
    U5  AC7 GPIOW3||LAD3||ESPID3 AST2600A3GP-AST2600A3-GP,SMLF,A   I436 @SCM_LIB.SCM(SCH_1):PAGE12
  R131    1      A Q_RES_0402LF-22,1%,1/16W,CHIP,A   I443 @SCM_LIB.SCM(SCH_1):PAGE12

ESPI_LPC_LAD0_IO0 @SCM_LIB.SCM(SCH_1):ESPI_LPC_LAD0_IO0
   GF1   B5 ESPI_IO0 FCONN168_ME1016810202011_SCM-FA   I553 @SCM_LIB.SCM(SCH_1):PAGE10
  R128    2      B Q_RES_0402LF-22,1%,1/16W,CHIP,A   I442 @SCM_LIB.SCM(SCH_1):PAGE12

ESPI_LPC_LAD1_IO1 @SCM_LIB.SCM(SCH_1):ESPI_LPC_LAD1_IO1
   GF1   B6 ESPI_IO1 FCONN168_ME1016810202011_SCM-FA   I553 @SCM_LIB.SCM(SCH_1):PAGE10
  R129    2      B Q_RES_0402LF-22,1%,1/16W,CHIP,A   I445 @SCM_LIB.SCM(SCH_1):PAGE12

ESPI_LPC_LAD2_IO2 @SCM_LIB.SCM(SCH_1):ESPI_LPC_LAD2_IO2
   GF1   B7 ESPI_IO2 FCONN168_ME1016810202011_SCM-FA   I553 @SCM_LIB.SCM(SCH_1):PAGE10
  R130    2      B Q_RES_0402LF-22,1%,1/16W,CHIP,A   I444 @SCM_LIB.SCM(SCH_1):PAGE12

ESPI_LPC_LAD3_IO3 @SCM_LIB.SCM(SCH_1):ESPI_LPC_LAD3_IO3
   GF1   B8 ESPI_IO3 FCONN168_ME1016810202011_SCM-FA   I553 @SCM_LIB.SCM(SCH_1):PAGE10
  R131    2      B Q_RES_0402LF-22,1%,1/16W,CHIP,A   I443 @SCM_LIB.SCM(SCH_1):PAGE12

FLASH_LATCH_CP @SCM_LIB.SCM(SCH_1):FLASH_LATCH_CP
   U54    1     CP 74LVC1G74DP-74LVC1G74DP,SMLF,IA   I138 @SCM_LIB.SCM(SCH_1):PAGE25
  R545    2      B Q_RES_0402LF-0,5%,1/16W,CHIP,CA   I143 @SCM_LIB.SCM(SCH_1):PAGE25

FLASH_LATCH_D @SCM_LIB.SCM(SCH_1):FLASH_LATCH_D
   U54    2      D 74LVC1G74DP-74LVC1G74DP,SMLF,IA   I138 @SCM_LIB.SCM(SCH_1):PAGE25
  R182    2      B Q_RES_0402LF-0,5%,1/16W,CHIP,CA   I142 @SCM_LIB.SCM(SCH_1):PAGE25

FLASH_LATCH_Q_N_R @SCM_LIB.SCM(SCH_1):FLASH_LATCH_Q_N_R
   U54    3    Q_N 74LVC1G74DP-74LVC1G74DP,SMLF,IA   I138 @SCM_LIB.SCM(SCH_1):PAGE25
  R555    1      A Q_RES_0402LF-33.2,1%,1/16W,CHIA   I174 @SCM_LIB.SCM(SCH_1):PAGE25

FLASH_LATCH_Q_N_R1 @SCM_LIB.SCM(SCH_1):FLASH_LATCH_Q_N_R1
  R560    1      A Q_RES_0402LF-0,5%,1/16W,CHIP,CA   I149 @SCM_LIB.SCM(SCH_1):PAGE25
  R555    2      B Q_RES_0402LF-33.2,1%,1/16W,CHIA   I174 @SCM_LIB.SCM(SCH_1):PAGE25

FLASH_LATCH_Q_N_R2 @SCM_LIB.SCM(SCH_1):FLASH_LATCH_Q_N_R2
  R560    2      B Q_RES_0402LF-0,5%,1/16W,CHIP,CA   I149 @SCM_LIB.SCM(SCH_1):PAGE25
   U55    2      A SN74LVC1G14DCKR_SMLF-IC,SN74LVA   I150 @SCM_LIB.SCM(SCH_1):PAGE25
    J1    2      2 SCONN3_212H9103GBR1-SCONN3_212A   I169 @SCM_LIB.SCM(SCH_1):PAGE25
  R556    2      B Q_RES_0402LF-33.2,1%,1/16W,CHIA   I175 @SCM_LIB.SCM(SCH_1):PAGE25
  R559    2      B Q_RES_0402LF-33.2,1%,1/16W,CHIA   I176 @SCM_LIB.SCM(SCH_1):PAGE25

FLASH_R_WP_STATUS @SCM_LIB.SCM(SCH_1):FLASH_R_WP_STATUS
   U55    4      Y SN74LVC1G14DCKR_SMLF-IC,SN74LVA   I150 @SCM_LIB.SCM(SCH_1):PAGE25
  R554    2      B Q_RES_0402LF-4.7K,1%,1/16W,EMPB   I156 @SCM_LIB.SCM(SCH_1):PAGE25
  R551    2      B Q_RES_0402LF-33.2,1%,1/16W,CHIA   I173 @SCM_LIB.SCM(SCH_1):PAGE25

FLASH_WP_STATUS @SCM_LIB.SCM(SCH_1):FLASH_WP_STATUS
  R466    2      B Q_RES_0402LF-33.2,1%,1/16W,CHIA   I431 @SCM_LIB.SCM(SCH_1):PAGE13
  R551    1      A Q_RES_0402LF-33.2,1%,1/16W,CHIA   I173 @SCM_LIB.SCM(SCH_1):PAGE25

FLASH_WP_STATUS_R1 @SCM_LIB.SCM(SCH_1):FLASH_WP_STATUS_R1
    U5  E16 GPIOI5||SIOPBO# AST2600A3GP-AST2600A3-GP,SMLF,A   I363 @SCM_LIB.SCM(SCH_1):PAGE13
  R466    1      A Q_RES_0402LF-33.2,1%,1/16W,CHIA   I431 @SCM_LIB.SCM(SCH_1):PAGE13

FM_ADR_COMPLETE @SCM_LIB.SCM(SCH_1):FM_ADR_COMPLETE
    U5 AC24 GPIOO6||PWM6 AST2600A3GP-AST2600A3-GP,SMLF,A   I350 @SCM_LIB.SCM(SCH_1):PAGE15
   U25  A12  PT22B LCMXO3LF2100C5BG256C-LCMXO3LF-A     I1 @SCM_LIB.SCM(SCH_1):PAGE34

FM_ADR_TRIGGER_N @SCM_LIB.SCM(SCH_1):FM_ADR_TRIGGER_N
    U5 AD25 GPIOO4||PWM4 AST2600A3GP-AST2600A3-GP,SMLF,A   I350 @SCM_LIB.SCM(SCH_1):PAGE15
   U25  J13   PR9D LCMXO3LF2100C5BG256C-LCMXO3LF-A     I1 @SCM_LIB.SCM(SCH_1):PAGE35
  R835    2      B Q_RES_0402LF-4.7K,1%,1/16W,CHIA    I63 @SCM_LIB.SCM(SCH_1):PAGE42

FM_BIC_DEBUG_SW_N @SCM_LIB.SCM(SCH_1):FM_BIC_DEBUG_SW_N
   U50    6      S NC7SB3157_SMLF-NC7SB3157P6X,NCA    I23 @SCM_LIB.SCM(SCH_1):PAGE31
   U51    6      S NC7SB3157_SMLF-NC7SB3157P6X,NCA    I24 @SCM_LIB.SCM(SCH_1):PAGE31
  R122    1      A Q_RES_0402LF-33.2,1%,1/16W,CHIA   I399 @SCM_LIB.SCM(SCH_1):PAGE13

FM_BIC_DEBUG_SW_N_R @SCM_LIB.SCM(SCH_1):FM_BIC_DEBUG_SW_N_R
    U5  F25 RGMII3RXD2||RMII3CRSDV||GPIOD2 AST2600A3GP-AST2600A3-GP,SMLF,A   I363 @SCM_LIB.SCM(SCH_1):PAGE13
  R122    2      B Q_RES_0402LF-33.2,1%,1/16W,CHIA   I399 @SCM_LIB.SCM(SCH_1):PAGE13

FM_BIOS_DEBUG_EN_N @SCM_LIB.SCM(SCH_1):FM_BIOS_DEBUG_EN_N
   U25  K12  PR11D LCMXO3LF2100C5BG256C-LCMXO3LF-A     I1 @SCM_LIB.SCM(SCH_1):PAGE35
  R112    2      B Q_RES_0402LF-33.2,1%,1/16W,CHIA   I427 @SCM_LIB.SCM(SCH_1):PAGE13

FM_BIOS_DEBUG_EN_R_N @SCM_LIB.SCM(SCH_1):FM_BIOS_DEBUG_EN_R_N
   R56    2      B Q_RES_0402LF-4.7K,1%,1/16W,CHIA   I279 @SCM_LIB.SCM(SCH_1):PAGE13
    U5  D24 RGMII4TXD3||NRTS3||GPIOE1 AST2600A3GP-AST2600A3-GP,SMLF,A   I363 @SCM_LIB.SCM(SCH_1):PAGE13
  R112    1      A Q_RES_0402LF-33.2,1%,1/16W,CHIA   I427 @SCM_LIB.SCM(SCH_1):PAGE13

FM_BIOS_POST_CMPLT_BMC_N @SCM_LIB.SCM(SCH_1):FM_BIOS_POST_CMPLT_BMC_N
    U5  U26 GPIOR7||TACH15 AST2600A3GP-AST2600A3-GP,SMLF,A   I350 @SCM_LIB.SCM(SCH_1):PAGE15
   U25   E8  PT16B LCMXO3LF2100C5BG256C-LCMXO3LF-A     I1 @SCM_LIB.SCM(SCH_1):PAGE34

FM_BMC_BIOS_MUX_CS_SPI_R_SEL_0 @SCM_LIB.SCM(SCH_1):FM_BMC_BIOS_MUX_CS_SPI_R_SEL_0
   U30    1      S IDTQS3VH257PAG_SMLF-IDTQS3VH25A   I271 @SCM_LIB.SCM(SCH_1):PAGE44
   U21    1      S IDTQS3VH257PAG_SMLF-IDTQS3VH25A   I296 @SCM_LIB.SCM(SCH_1):PAGE44
  R866    1      A Q_RES_0402LF-10K,1%,1/16W,CHIPA   I311 @SCM_LIB.SCM(SCH_1):PAGE44
  R852    2      B Q_RES_0402LF-68.1,1%,1/16W,CHIA   I366 @SCM_LIB.SCM(SCH_1):PAGE44

FM_BMC_CPU_FBRK_OUT_N @SCM_LIB.SCM(SCH_1):FM_BMC_CPU_FBRK_OUT_N
    U5  H22 RGMII3TXD0||RMII3TXD0||GPIOC2 AST2600A3GP-AST2600A3-GP,SMLF,A   I363 @SCM_LIB.SCM(SCH_1):PAGE13
  R242    1      A Q_RES_0402LF-33.2,1%,1/16W,CHIA   I384 @SCM_LIB.SCM(SCH_1):PAGE13

FM_BMC_CPU_FBRK_OUT_R_N @SCM_LIB.SCM(SCH_1):FM_BMC_CPU_FBRK_OUT_R_N
   U25   L9  PB12D LCMXO3LF2100C5BG256C-LCMXO3LF-A     I1 @SCM_LIB.SCM(SCH_1):PAGE36
  R242    2      B Q_RES_0402LF-33.2,1%,1/16W,CHIA   I384 @SCM_LIB.SCM(SCH_1):PAGE13

FM_BMC_CRASHLOG_TRIG_N @SCM_LIB.SCM(SCH_1):FM_BMC_CRASHLOG_TRIG_N
  R747    1      A Q_RES_0402LF-0,5%,1/16W,CHIP,CA     I9 @SCM_LIB.SCM(SCH_1):PAGE36
  R749    2      B Q_RES_0402LF-4.7K,1%,1/16W,CHIA    I61 @SCM_LIB.SCM(SCH_1):PAGE42
  R760    1      A Q_RES_0402LF-33.2,1%,1/16W,CHIA   I400 @SCM_LIB.SCM(SCH_1):PAGE13

FM_BMC_CRASHLOG_TRIG_R1_N @SCM_LIB.SCM(SCH_1):FM_BMC_CRASHLOG_TRIG_R1_N
    U5  E26 RGMII3RXD3||RMII3RXER||GPIOD3 AST2600A3GP-AST2600A3-GP,SMLF,A   I363 @SCM_LIB.SCM(SCH_1):PAGE13
  R760    2      B Q_RES_0402LF-33.2,1%,1/16W,CHIA   I400 @SCM_LIB.SCM(SCH_1):PAGE13

FM_BMC_CRASHLOG_TRIG_R2_N @SCM_LIB.SCM(SCH_1):FM_BMC_CRASHLOG_TRIG_R2_N
   U25   R6   PB6B LCMXO3LF2100C5BG256C-LCMXO3LF-A     I1 @SCM_LIB.SCM(SCH_1):PAGE36
  R747    2      B Q_RES_0402LF-0,5%,1/16W,CHIP,CA     I9 @SCM_LIB.SCM(SCH_1):PAGE36

FM_BMC_DBP_PRESENT_N @SCM_LIB.SCM(SCH_1):FM_BMC_DBP_PRESENT_N
  R705    1      A Q_RES_0402LF-33.2,1%,1/16W,CHIA   I353 @SCM_LIB.SCM(SCH_1):PAGE12
  R706    2      B Q_RES_0402LF-4.7K,1%,1/16W,CHIA   I354 @SCM_LIB.SCM(SCH_1):PAGE12
   U25   D6  PT12A LCMXO3LF2100C5BG256C-LCMXO3LF-A     I1 @SCM_LIB.SCM(SCH_1):PAGE34

FM_BMC_DBP_PRESENT_R_N @SCM_LIB.SCM(SCH_1):FM_BMC_DBP_PRESENT_R_N
  R705    2      B Q_RES_0402LF-33.2,1%,1/16W,CHIA   I353 @SCM_LIB.SCM(SCH_1):PAGE12
    U5  B21 GPIOG7||RXD9||SD2WP#||SALT16 AST2600A3GP-AST2600A3-GP,SMLF,A   I436 @SCM_LIB.SCM(SCH_1):PAGE12

FM_BMC_DEBUG_SW_N @SCM_LIB.SCM(SCH_1):FM_BMC_DEBUG_SW_N
    U5  R26 GPIOS4||TXD10 AST2600A3GP-AST2600A3-GP,SMLF,A   I363 @SCM_LIB.SCM(SCH_1):PAGE13
  R624    2      B Q_RES_0402LF-4.7K,1%,1/16W,CHIA    I48 @SCM_LIB.SCM(SCH_1):PAGE48
  R506    1      A Q_RES_0402LF-100,1%,1/16W,EMPTA    I53 @SCM_LIB.SCM(SCH_1):PAGE48
  R750    1      A Q_RES_0402LF-33.2,1%,1/16W,CHIA    I82 @SCM_LIB.SCM(SCH_1):PAGE36

FM_BMC_DEBUG_SW_R2_N @SCM_LIB.SCM(SCH_1):FM_BMC_DEBUG_SW_R2_N
   U25   N6   PB8C LCMXO3LF2100C5BG256C-LCMXO3LF-A     I1 @SCM_LIB.SCM(SCH_1):PAGE36
  R750    2      B Q_RES_0402LF-33.2,1%,1/16W,CHIA    I82 @SCM_LIB.SCM(SCH_1):PAGE36

FM_BMC_DISABLE @SCM_LIB.SCM(SCH_1):FM_BMC_DISABLE
   U11    3      C BAT54C-BAT54C,SMLF,IC,BCBAT54CA   I185 @SCM_LIB.SCM(SCH_1):PAGE27
  R615    2      B Q_RES_0402LF-4.7K,1%,1/16W,EMPB    I33 @SCM_LIB.SCM(SCH_1):PAGE48
  R431    1      A Q_RES_0402LF-100,1%,1/16W,EMPTA    I56 @SCM_LIB.SCM(SCH_1):PAGE48

FM_BMC_EN_DET_R @SCM_LIB.SCM(SCH_1):FM_BMC_EN_DET_R
    U5 AA16 ADC13||GPIU5||SALT14 AST2600A3GP-AST2600A3-GP,SMLF,A   I350 @SCM_LIB.SCM(SCH_1):PAGE15
  R846    2      B Q_RES_0402LF-4.7K,1%,1/16W,EMPA   I181 @SCM_LIB.SCM(SCH_1):PAGE27
   U25  L12  PR10D LCMXO3LF2100C5BG256C-LCMXO3LF-A     I1 @SCM_LIB.SCM(SCH_1):PAGE35

FM_BMC_MUX_CS_SPI_SEL_0 @SCM_LIB.SCM(SCH_1):FM_BMC_MUX_CS_SPI_SEL_0
    U5  J23 GPIOB4||MDC2 AST2600A3GP-AST2600A3-GP,SMLF,A   I363 @SCM_LIB.SCM(SCH_1):PAGE13
  R852    1      A Q_RES_0402LF-68.1,1%,1/16W,CHIA   I366 @SCM_LIB.SCM(SCH_1):PAGE44

FM_BMC_ONCTL_R_N @SCM_LIB.SCM(SCH_1):FM_BMC_ONCTL_R_N
  R821    2      B Q_RES_0402LF-4.7K,1%,1/16W,EMPA   I220 @SCM_LIB.SCM(SCH_1):PAGE13
    U5 AC15 GPIOV3||SIOONCTRL# AST2600A3GP-AST2600A3-GP,SMLF,A   I363 @SCM_LIB.SCM(SCH_1):PAGE13
   U11    1      B BAT54C-BAT54C,SMLF,IC,BCBAT54CA   I185 @SCM_LIB.SCM(SCH_1):PAGE27
  R430    2      B Q_RES_0402LF-4.7K,1%,1/16W,CHIA   I188 @SCM_LIB.SCM(SCH_1):PAGE27
   U25  L13  PR12D LCMXO3LF2100C5BG256C-LCMXO3LF-A     I1 @SCM_LIB.SCM(SCH_1):PAGE35

FM_BMC_READY_PLD_N @SCM_LIB.SCM(SCH_1):FM_BMC_READY_PLD_N
  R111    2      B Q_RES_0402LF-33.2,1%,1/16W,CHIA   I266 @SCM_LIB.SCM(SCH_1):PAGE13
   U25  K13  PR11C LCMXO3LF2100C5BG256C-LCMXO3LF-A     I1 @SCM_LIB.SCM(SCH_1):PAGE35

FM_BMC_READY_R_PLD_N @SCM_LIB.SCM(SCH_1):FM_BMC_READY_R_PLD_N
  R111    1      A Q_RES_0402LF-33.2,1%,1/16W,CHIA   I266 @SCM_LIB.SCM(SCH_1):PAGE13
   R55    2      B Q_RES_0402LF-4.7K,1%,1/16W,CHIA   I278 @SCM_LIB.SCM(SCH_1):PAGE13
    U5 AE14 GPIOV5||LPCPD# AST2600A3GP-AST2600A3-GP,SMLF,A   I363 @SCM_LIB.SCM(SCH_1):PAGE13

FM_BMC_SSPRST_N @SCM_LIB.SCM(SCH_1):FM_BMC_SSPRST_N
  R211    2      B Q_RES_0402LF-10K,1%,1/16W,CHIPA    I51 @SCM_LIB.SCM(SCH_1):PAGE15
    U5   D7 SSPRST# AST2600A3GP-AST2600A3-GP,SMLF,A   I350 @SCM_LIB.SCM(SCH_1):PAGE15

FM_BMC_SUSACK_N @SCM_LIB.SCM(SCH_1):FM_BMC_SUSACK_N
   R38    2      B Q_RES_0402LF-4.7K,1%,1/16W,CHIA   I200 @SCM_LIB.SCM(SCH_1):PAGE13
  R407    2      B Q_RES_0402LF-33.2,1%,1/16W,CHIA   I349 @SCM_LIB.SCM(SCH_1):PAGE13
  R445    1      A Q_RES_0402LF-33.2,1%,1/16W,CHIA    I81 @SCM_LIB.SCM(SCH_1):PAGE36

FM_BMC_SUSACK_R1_N @SCM_LIB.SCM(SCH_1):FM_BMC_SUSACK_R1_N
  R407    1      A Q_RES_0402LF-33.2,1%,1/16W,CHIA   I349 @SCM_LIB.SCM(SCH_1):PAGE13
    U5 AD15 GPIOV6||LPCPME# AST2600A3GP-AST2600A3-GP,SMLF,A   I363 @SCM_LIB.SCM(SCH_1):PAGE13

FM_BMC_SUSACK_R2_N @SCM_LIB.SCM(SCH_1):FM_BMC_SUSACK_R2_N
   U25   R4   PB6D LCMXO3LF2100C5BG256C-LCMXO3LF-A     I1 @SCM_LIB.SCM(SCH_1):PAGE36
  R445    2      B Q_RES_0402LF-33.2,1%,1/16W,CHIA    I81 @SCM_LIB.SCM(SCH_1):PAGE36

FM_BMC_UARTSW_LSB_N @SCM_LIB.SCM(SCH_1):FM_BMC_UARTSW_LSB_N
   GF1  A55 SPARE0 FCONN168_ME1016810202011_SCM-FA   I553 @SCM_LIB.SCM(SCH_1):PAGE10
  R134    1      A Q_RES_0402LF-0,5%,1/16W,CHIP,CA    I47 @SCM_LIB.SCM(SCH_1):PAGE36

FM_BMC_UARTSW_MSB_N @SCM_LIB.SCM(SCH_1):FM_BMC_UARTSW_MSB_N
   GF1  A52 SPARE1 FCONN168_ME1016810202011_SCM-FA   I553 @SCM_LIB.SCM(SCH_1):PAGE10
  R220    1      A Q_RES_0402LF-0,5%,1/16W,CHIP,CA    I46 @SCM_LIB.SCM(SCH_1):PAGE36

FM_BOARD_BMC_REV_ID0 @SCM_LIB.SCM(SCH_1):FM_BOARD_BMC_REV_ID0
    U5   D3 RGMII2TXD1||RMII2TXD1||GPIO18B7 AST2600A3GP-AST2600A3-GP,SMLF,A   I149 @SCM_LIB.SCM(SCH_1):PAGE14
  R858    2      B Q_RES_0402LF-4.7K,1%,1/16W,CHIA   I222 @SCM_LIB.SCM(SCH_1):PAGE14
  R865    1      A Q_RES_0402LF-1K,1%,1/16W,EMPTYA   I225 @SCM_LIB.SCM(SCH_1):PAGE14

FM_BOARD_BMC_REV_ID1 @SCM_LIB.SCM(SCH_1):FM_BOARD_BMC_REV_ID1
    U5   E4 RGMII2TXD2||GPIO18C0 AST2600A3GP-AST2600A3-GP,SMLF,A   I149 @SCM_LIB.SCM(SCH_1):PAGE14
  R856    2      B Q_RES_0402LF-4.7K,1%,1/16W,CHIA   I220 @SCM_LIB.SCM(SCH_1):PAGE14
  R857    1      A Q_RES_0402LF-1K,1%,1/16W,EMPTYA   I224 @SCM_LIB.SCM(SCH_1):PAGE14

FM_BOARD_BMC_REV_ID2 @SCM_LIB.SCM(SCH_1):FM_BOARD_BMC_REV_ID2
    U5   F5 RGMII2TXD3||GPIO18C1 AST2600A3GP-AST2600A3-GP,SMLF,A   I149 @SCM_LIB.SCM(SCH_1):PAGE14
  R854    2      B Q_RES_0402LF-4.7K,1%,1/16W,EMPA   I221 @SCM_LIB.SCM(SCH_1):PAGE14
  R855    1      A Q_RES_0402LF-1K,1%,1/16W,CHIP,A   I223 @SCM_LIB.SCM(SCH_1):PAGE14

FM_CPU_MSMI_CATERR_LVT3_N @SCM_LIB.SCM(SCH_1):FM_CPU_MSMI_CATERR_LVT3_N
  R163    2      B Q_RES_0402LF-4.7K,1%,1/16W,CHIA   I212 @SCM_LIB.SCM(SCH_1):PAGE11
  R720    1      A Q_RES_0402LF-0,5%,1/16W,CHIP,CA   I144 @SCM_LIB.SCM(SCH_1):PAGE28
  R121    2      B Q_RES_0402LF-33.2,1%,1/16W,CHIA   I381 @SCM_LIB.SCM(SCH_1):PAGE13
  R270    2      B Q_RES_0402LF-33.2,1%,1/16W,CHIA   I164 @SCM_LIB.SCM(SCH_1):PAGE34

FM_CPU_MSMI_CATERR_LVT3_PLD_N @SCM_LIB.SCM(SCH_1):FM_CPU_MSMI_CATERR_LVT3_PLD_N
   U25  E10  PT20B LCMXO3LF2100C5BG256C-LCMXO3LF-A     I1 @SCM_LIB.SCM(SCH_1):PAGE34
  R270    1      A Q_RES_0402LF-33.2,1%,1/16W,CHIA   I164 @SCM_LIB.SCM(SCH_1):PAGE34

FM_CPU_MSMI_CATERR_LVT3_R3_N @SCM_LIB.SCM(SCH_1):FM_CPU_MSMI_CATERR_LVT3_R3_N
   U40   18    P15 PCA9555PW_SMLF-PCA9555PW,IC,TMA   I141 @SCM_LIB.SCM(SCH_1):PAGE28
  R720    2      B Q_RES_0402LF-0,5%,1/16W,CHIP,CA   I144 @SCM_LIB.SCM(SCH_1):PAGE28

FM_CPU_RMCA_CATERR_LVT3_R_N @SCM_LIB.SCM(SCH_1):FM_CPU_RMCA_CATERR_LVT3_R_N
    U5  J22 RGMII3TXCTL||RMII3TXEN||GPIOC1 AST2600A3GP-AST2600A3-GP,SMLF,A   I363 @SCM_LIB.SCM(SCH_1):PAGE13
  R121    1      A Q_RES_0402LF-33.2,1%,1/16W,CHIA   I381 @SCM_LIB.SCM(SCH_1):PAGE13

FM_DBG_SW_N @SCM_LIB.SCM(SCH_1):FM_DBG_SW_N
    U7    6      S NC7SB3157_SMLF-NC7SB3157P6X,NCA    I27 @SCM_LIB.SCM(SCH_1):PAGE31
   U20    6      S NC7SB3157_SMLF-NC7SB3157P6X,NCA    I38 @SCM_LIB.SCM(SCH_1):PAGE31
   J13    2      2 SCONN3_212H9103GBR1-SCONN3_212B    I61 @SCM_LIB.SCM(SCH_1):PAGE31
  R629    2      B Q_RES_0402LF-0,5%,1/16W,CHIP,CA    I78 @SCM_LIB.SCM(SCH_1):PAGE31

FM_DBP_BMC_PRDY_N @SCM_LIB.SCM(SCH_1):FM_DBP_BMC_PRDY_N
   GF1  A50 DBP_PRDY_N FCONN168_ME1016810202011_SCM-FA   I553 @SCM_LIB.SCM(SCH_1):PAGE10
  R237    1      A Q_RES_0402LF-33.2,1%,1/16W,CHIA   I156 @SCM_LIB.SCM(SCH_1):PAGE13

FM_DBP_BMC_PRDY_R_N @SCM_LIB.SCM(SCH_1):FM_DBP_BMC_PRDY_R_N
  R237    2      B Q_RES_0402LF-33.2,1%,1/16W,CHIA   I156 @SCM_LIB.SCM(SCH_1):PAGE13
    U5  C12 GPIOM5||NRTS1 AST2600A3GP-AST2600A3-GP,SMLF,A   I363 @SCM_LIB.SCM(SCH_1):PAGE13

FM_DBP_CPU_PREQ_GF_N @SCM_LIB.SCM(SCH_1):FM_DBP_CPU_PREQ_GF_N
  R158    2      B Q_RES_0402LF-33.2,1%,1/16W,CHIA    I16 @SCM_LIB.SCM(SCH_1):PAGE13
    U5  C15 GPIOL4||TXD3 AST2600A3GP-AST2600A3-GP,SMLF,A   I363 @SCM_LIB.SCM(SCH_1):PAGE13

FM_DBP_CPU_PREQ_GF_R_N @SCM_LIB.SCM(SCH_1):FM_DBP_CPU_PREQ_GF_R_N
   GF1  A49 DBP_PREQ_N FCONN168_ME1016810202011_SCM-FA   I553 @SCM_LIB.SCM(SCH_1):PAGE10
  R158    1      A Q_RES_0402LF-33.2,1%,1/16W,CHIA    I16 @SCM_LIB.SCM(SCH_1):PAGE13

FM_DEBUG_PORT_PRSNT_N @SCM_LIB.SCM(SCH_1):FM_DEBUG_PORT_PRSNT_N
  R707    2      B Q_RES_0402LF-0,5%,1/16W,CHIP,CA   I201 @SCM_LIB.SCM(SCH_1):PAGE29
  R579    1      A Q_RES_0402LF-0,5%,1/16W,CHIP,CA     I7 @SCM_LIB.SCM(SCH_1):PAGE36
  R458    2      B Q_RES_0402LF-33.2,1%,1/16W,CHIA   I407 @SCM_LIB.SCM(SCH_1):PAGE13

FM_DEBUG_PORT_PRSNT_R1_N @SCM_LIB.SCM(SCH_1):FM_DEBUG_PORT_PRSNT_R1_N
    U5 AD11 GPIOZ6||SPI1DQ2||TXD13 AST2600A3GP-AST2600A3-GP,SMLF,A   I363 @SCM_LIB.SCM(SCH_1):PAGE13
  R458    1      A Q_RES_0402LF-33.2,1%,1/16W,CHIA   I407 @SCM_LIB.SCM(SCH_1):PAGE13

FM_DEBUG_PORT_R2_PRSNT_N @SCM_LIB.SCM(SCH_1):FM_DEBUG_PORT_R2_PRSNT_N
   U25   R5 PB5A||CSSPIN LCMXO3LF2100C5BG256C-LCMXO3LF-A     I1 @SCM_LIB.SCM(SCH_1):PAGE36
  R579    2      B Q_RES_0402LF-0,5%,1/16W,CHIP,CA     I7 @SCM_LIB.SCM(SCH_1):PAGE36

FM_DEBUG_PORT_R_PRSNT_N @SCM_LIB.SCM(SCH_1):FM_DEBUG_PORT_R_PRSNT_N
  R707    1      A Q_RES_0402LF-0,5%,1/16W,CHIP,CA   I201 @SCM_LIB.SCM(SCH_1):PAGE29
    Q6    D      D 2N7002A7-2N7002A-7,SMLF,IC,BAMA   I202 @SCM_LIB.SCM(SCH_1):PAGE29
  R730    2      B Q_RES_0402LF-4.7K,1%,1/16W,CHIA   I204 @SCM_LIB.SCM(SCH_1):PAGE29

FM_DEBUG_PWR_BTN_N @SCM_LIB.SCM(SCH_1):FM_DEBUG_PWR_BTN_N
   U40   14    P11 PCA9555PW_SMLF-PCA9555PW,IC,TMA   I141 @SCM_LIB.SCM(SCH_1):PAGE28
  R734    2      B Q_RES_0402LF-0,5%,1/16W,CHIP,CA   I152 @SCM_LIB.SCM(SCH_1):PAGE50

FM_DEBUG_RST_BTN_N @SCM_LIB.SCM(SCH_1):FM_DEBUG_RST_BTN_N
   U40   13    P10 PCA9555PW_SMLF-PCA9555PW,IC,TMA   I141 @SCM_LIB.SCM(SCH_1):PAGE28
  R733    2      B Q_RES_0402LF-0,5%,1/16W,CHIP,CA   I154 @SCM_LIB.SCM(SCH_1):PAGE50

FM_ESPI_PLD_EN @SCM_LIB.SCM(SCH_1):FM_ESPI_PLD_EN
  R444    1      A Q_RES_0402LF-33.2,1%,1/16W,CHIA   I306 @SCM_LIB.SCM(SCH_1):PAGE13
  R833    1      A Q_RES_0402LF-33.2,1%,1/16W,CHIA   I139 @SCM_LIB.SCM(SCH_1):PAGE35

FM_ESPI_PLD_R1_EN @SCM_LIB.SCM(SCH_1):FM_ESPI_PLD_R1_EN
  R444    2      B Q_RES_0402LF-33.2,1%,1/16W,CHIA   I306 @SCM_LIB.SCM(SCH_1):PAGE13
    U5  H25 GPIOB6||TXD4 AST2600A3GP-AST2600A3-GP,SMLF,A   I363 @SCM_LIB.SCM(SCH_1):PAGE13

FM_ESPI_PLD_R_EN @SCM_LIB.SCM(SCH_1):FM_ESPI_PLD_R_EN
   U25  H13   PR6C LCMXO3LF2100C5BG256C-LCMXO3LF-A     I1 @SCM_LIB.SCM(SCH_1):PAGE35
  R833    2      B Q_RES_0402LF-33.2,1%,1/16W,CHIA   I139 @SCM_LIB.SCM(SCH_1):PAGE35

FM_FLASH_LATCH_N @SCM_LIB.SCM(SCH_1):FM_FLASH_LATCH_N
   U54    7   SD_N 74LVC1G74DP-74LVC1G74DP,SMLF,IA   I138 @SCM_LIB.SCM(SCH_1):PAGE25
  R465    2      B Q_RES_0402LF-33.2,1%,1/16W,CHIA   I432 @SCM_LIB.SCM(SCH_1):PAGE13
  R181    2      B Q_RES_0402LF-4.7K,1%,1/16W,CHIA   I170 @SCM_LIB.SCM(SCH_1):PAGE25

FM_FLASH_LATCH_N_R1 @SCM_LIB.SCM(SCH_1):FM_FLASH_LATCH_N_R1
    U5 AE11 GPIOY2||SALT7||WDTRST3# AST2600A3GP-AST2600A3-GP,SMLF,A   I363 @SCM_LIB.SCM(SCH_1):PAGE13
  R465    1      A Q_RES_0402LF-33.2,1%,1/16W,CHIA   I432 @SCM_LIB.SCM(SCH_1):PAGE13

FM_HDD_LED_N @SCM_LIB.SCM(SCH_1):FM_HDD_LED_N
    U5  Y26 GPIOQ4||TACH4 AST2600A3GP-AST2600A3-GP,SMLF,A   I350 @SCM_LIB.SCM(SCH_1):PAGE15
   U25   P6 PB8A||MCLK||CCLK LCMXO3LF2100C5BG256C-LCMXO3LF-A     I1 @SCM_LIB.SCM(SCH_1):PAGE36
  R838    2      B Q_RES_0402LF-0,5%,1/16W,CHIP,CA   I568 @SCM_LIB.SCM(SCH_1):PAGE10

FM_ID_LED @SCM_LIB.SCM(SCH_1):FM_ID_LED
    U5  G26 GPIOB5||MDIO2 AST2600A3GP-AST2600A3-GP,SMLF,A   I363 @SCM_LIB.SCM(SCH_1):PAGE13
  R390    1      A Q_RES_0402LF-33.2,1%,1/16W,CHIA    I92 @SCM_LIB.SCM(SCH_1):PAGE49

FM_ID_R_LED @SCM_LIB.SCM(SCH_1):FM_ID_R_LED
    U9    2   IN_A MC74VHC1G32DTT1G-MC74VHC1G32DTA     I5 @SCM_LIB.SCM(SCH_1):PAGE49
  R390    2      B Q_RES_0402LF-33.2,1%,1/16W,CHIA    I92 @SCM_LIB.SCM(SCH_1):PAGE49

FM_INTRUDER_N @SCM_LIB.SCM(SCH_1):FM_INTRUDER_N
   GF1  A54 CHASI_N FCONN168_ME1016810202011_SCM-FA   I553 @SCM_LIB.SCM(SCH_1):PAGE10
  R853    2      B Q_RES_0402LF-0,5%,1/16W,CHIP,CA   I387 @SCM_LIB.SCM(SCH_1):PAGE15

FM_INTRUDER_R_N @SCM_LIB.SCM(SCH_1):FM_INTRUDER_R_N
    U5 AB21 CHASI# AST2600A3GP-AST2600A3-GP,SMLF,A   I350 @SCM_LIB.SCM(SCH_1):PAGE15
  R853    1      A Q_RES_0402LF-0,5%,1/16W,CHIP,CA   I387 @SCM_LIB.SCM(SCH_1):PAGE15

FM_JTAG_BMC_MUX_SEL @SCM_LIB.SCM(SCH_1):FM_JTAG_BMC_MUX_SEL
  R644    1      A Q_RES_0402LF-33.2,1%,1/16W,CHIA   I345 @SCM_LIB.SCM(SCH_1):PAGE15
  R634    1      A Q_RES_0402LF-0,5%,1/16W,CHIP,CA    I37 @SCM_LIB.SCM(SCH_1):PAGE34
  R640    2      B Q_RES_0402LF-4.7K,1%,1/16W,EMPA    I56 @SCM_LIB.SCM(SCH_1):PAGE42
  R642    2      B Q_RES_0402LF-100K,1%,1/16W,CHIA    I58 @SCM_LIB.SCM(SCH_1):PAGE42

FM_JTAG_BMC_MUX_SEL_R1 @SCM_LIB.SCM(SCH_1):FM_JTAG_BMC_MUX_SEL_R1
  R644    2      B Q_RES_0402LF-33.2,1%,1/16W,CHIA   I345 @SCM_LIB.SCM(SCH_1):PAGE15
    U5 AD24 GPIOO3||PWM3 AST2600A3GP-AST2600A3-GP,SMLF,A   I350 @SCM_LIB.SCM(SCH_1):PAGE15

FM_JTAG_BMC_MUX_SEL_R2 @SCM_LIB.SCM(SCH_1):FM_JTAG_BMC_MUX_SEL_R2
   U25   B6  PT11B LCMXO3LF2100C5BG256C-LCMXO3LF-A     I1 @SCM_LIB.SCM(SCH_1):PAGE34
  R634    2      B Q_RES_0402LF-0,5%,1/16W,CHIP,CA    I37 @SCM_LIB.SCM(SCH_1):PAGE34

FM_JTAG_SEL @SCM_LIB.SCM(SCH_1):FM_JTAG_SEL
   GF1  A43 HPM_FW_RECOVERY FCONN168_ME1016810202011_SCM-FA   I553 @SCM_LIB.SCM(SCH_1):PAGE10
    U5  G23 RGMII3RXCK||RMII3RCLKI||GPIOC6 AST2600A3GP-AST2600A3-GP,SMLF,A   I363 @SCM_LIB.SCM(SCH_1):PAGE13

FM_JTAG_TCK_MUX_BMC_SEL @SCM_LIB.SCM(SCH_1):FM_JTAG_TCK_MUX_BMC_SEL
  R159    1      A Q_RES_0402LF-33.2,1%,1/16W,CHIA    I17 @SCM_LIB.SCM(SCH_1):PAGE13
   U25   T8  PB12B LCMXO3LF2100C5BG256C-LCMXO3LF-A     I1 @SCM_LIB.SCM(SCH_1):PAGE36
  R620    1      A Q_RES_0402LF-100K,1%,1/16W,CHIA    I39 @SCM_LIB.SCM(SCH_1):PAGE48
  R616    2      B Q_RES_0402LF-0,5%,1/16W,CHIP,CA    I40 @SCM_LIB.SCM(SCH_1):PAGE48

FM_JTAG_TCK_MUX_BMC_SEL_R @SCM_LIB.SCM(SCH_1):FM_JTAG_TCK_MUX_BMC_SEL_R
  R616    1      A Q_RES_0402LF-0,5%,1/16W,CHIP,CA    I40 @SCM_LIB.SCM(SCH_1):PAGE48
  R881    2      B Q_RES_0402LF-4.7K,1%,1/16W,EMPB    I42 @SCM_LIB.SCM(SCH_1):PAGE48

FM_JTAG_TCK_MUX_BMC_SEL_R1 @SCM_LIB.SCM(SCH_1):FM_JTAG_TCK_MUX_BMC_SEL_R1
  R159    2      B Q_RES_0402LF-33.2,1%,1/16W,CHIA    I17 @SCM_LIB.SCM(SCH_1):PAGE13
    U5  F15 GPIOL5||RXD3 AST2600A3GP-AST2600A3-GP,SMLF,A   I363 @SCM_LIB.SCM(SCH_1):PAGE13

FM_ME_BT_DONE @SCM_LIB.SCM(SCH_1):FM_ME_BT_DONE
    U5  J26 GPIOB0||SALT1 AST2600A3GP-AST2600A3-GP,SMLF,A   I363 @SCM_LIB.SCM(SCH_1):PAGE13
  R266    2      B Q_RES_0402LF-4.7K,1%,1/16W,EMPA    I95 @SCM_LIB.SCM(SCH_1):PAGE27
   U25   D7  PT13D LCMXO3LF2100C5BG256C-LCMXO3LF-A     I1 @SCM_LIB.SCM(SCH_1):PAGE34

FM_P12V_HSC_ENABLE @SCM_LIB.SCM(SCH_1):FM_P12V_HSC_ENABLE
  R479    1      A Q_RES_0402LF-33.2,1%,1/16W,CHIA   I330 @SCM_LIB.SCM(SCH_1):PAGE15
  R575    1      A Q_RES_0402LF-0,5%,1/16W,CHIP,CA     I2 @SCM_LIB.SCM(SCH_1):PAGE36
  R621    2      B Q_RES_0402LF-4.7K,1%,1/16W,CHIA    I13 @SCM_LIB.SCM(SCH_1):PAGE42

FM_P12V_HSC_ENABLE_R1 @SCM_LIB.SCM(SCH_1):FM_P12V_HSC_ENABLE_R1
  R479    2      B Q_RES_0402LF-33.2,1%,1/16W,CHIA   I330 @SCM_LIB.SCM(SCH_1):PAGE15
    U5 AC26 GPIOQ5||TACH5 AST2600A3GP-AST2600A3-GP,SMLF,A   I350 @SCM_LIB.SCM(SCH_1):PAGE15

FM_P12V_HSC_ENABLE_R2 @SCM_LIB.SCM(SCH_1):FM_P12V_HSC_ENABLE_R2
   U25   P4   PB3A LCMXO3LF2100C5BG256C-LCMXO3LF-A     I1 @SCM_LIB.SCM(SCH_1):PAGE36
  R575    2      B Q_RES_0402LF-0,5%,1/16W,CHIP,CA     I2 @SCM_LIB.SCM(SCH_1):PAGE36

FM_PCHHOT_R_N @SCM_LIB.SCM(SCH_1):FM_PCHHOT_R_N
    U5 AD16 ADC14||GPIU6||SALT15 AST2600A3GP-AST2600A3-GP,SMLF,A   I350 @SCM_LIB.SCM(SCH_1):PAGE15
   U25  K11  PR12C LCMXO3LF2100C5BG256C-LCMXO3LF-A     I1 @SCM_LIB.SCM(SCH_1):PAGE35

FM_PCH_BEEP_LED @SCM_LIB.SCM(SCH_1):FM_PCH_BEEP_LED
    U5  Y25 GPIOQ6||TACH6 AST2600A3GP-AST2600A3-GP,SMLF,A   I350 @SCM_LIB.SCM(SCH_1):PAGE15
   U25   T6 PB8B||SO||SPISO LCMXO3LF2100C5BG256C-LCMXO3LF-A     I1 @SCM_LIB.SCM(SCH_1):PAGE36
  R847    2      B Q_RES_0402LF-0,5%,1/16W,CHIP,CA   I569 @SCM_LIB.SCM(SCH_1):PAGE10

FM_PCH_BMC_THERMTRIP_N @SCM_LIB.SCM(SCH_1):FM_PCH_BMC_THERMTRIP_N
   R62    2      B Q_RES_0402LF-4.7K,1%,1/16W,CHIA   I350 @SCM_LIB.SCM(SCH_1):PAGE12
   U25   D8  PT17C LCMXO3LF2100C5BG256C-LCMXO3LF-A     I1 @SCM_LIB.SCM(SCH_1):PAGE34
  R763    1      A Q_RES_0402LF-33.2,1%,1/16W,CHIA   I402 @SCM_LIB.SCM(SCH_1):PAGE13

FM_PCIE_M2_SSD0_PRSNT_N @SCM_LIB.SCM(SCH_1):FM_PCIE_M2_SSD0_PRSNT_N
    U5 AD23 GPIOO2||PWM2 AST2600A3GP-AST2600A3-GP,SMLF,A   I350 @SCM_LIB.SCM(SCH_1):PAGE15
   U25   F7  PT16A LCMXO3LF2100C5BG256C-LCMXO3LF-A     I1 @SCM_LIB.SCM(SCH_1):PAGE34

FM_PECI_SEL_N @SCM_LIB.SCM(SCH_1):FM_PECI_SEL_N
  R439    1      A Q_RES_0402LF-33.2,1%,1/16W,CHIA   I227 @SCM_LIB.SCM(SCH_1):PAGE13
  R446    2      B Q_RES_0402LF-4.7K,1%,1/16W,CHIA   I299 @SCM_LIB.SCM(SCH_1):PAGE13
   U25  B16   PR1D LCMXO3LF2100C5BG256C-LCMXO3LF-A     I1 @SCM_LIB.SCM(SCH_1):PAGE35

FM_PECI_SEL_R_N @SCM_LIB.SCM(SCH_1):FM_PECI_SEL_R_N
  R439    2      B Q_RES_0402LF-33.2,1%,1/16W,CHIA   I227 @SCM_LIB.SCM(SCH_1):PAGE13
    U5  E14 GPIOM3||NRI1 AST2600A3GP-AST2600A3-GP,SMLF,A   I363 @SCM_LIB.SCM(SCH_1):PAGE13

FM_PFR_DSW_PWROK_N @SCM_LIB.SCM(SCH_1):FM_PFR_DSW_PWROK_N
    U5  M24 GPIOA0||SCL11||MDC3 AST2600A3GP-AST2600A3-GP,SMLF,A   I436 @SCM_LIB.SCM(SCH_1):PAGE12
   U25   L8  PB11D LCMXO3LF2100C5BG256C-LCMXO3LF-A     I1 @SCM_LIB.SCM(SCH_1):PAGE36

FM_PLT_BMC_THERMTRIP_N_R @SCM_LIB.SCM(SCH_1):FM_PLT_BMC_THERMTRIP_N_R
    U5  C26 RGMII4RXCTL||NDCD4||GPIOE3 AST2600A3GP-AST2600A3-GP,SMLF,A   I363 @SCM_LIB.SCM(SCH_1):PAGE13
  R763    2      B Q_RES_0402LF-33.2,1%,1/16W,CHIA   I402 @SCM_LIB.SCM(SCH_1):PAGE13

FM_PMBUS_ALERT_EN @SCM_LIB.SCM(SCH_1):FM_PMBUS_ALERT_EN
    U5 AD26 GPIOO0||PWM0 AST2600A3GP-AST2600A3-GP,SMLF,A   I350 @SCM_LIB.SCM(SCH_1):PAGE15
   U25  J16   PR7C LCMXO3LF2100C5BG256C-LCMXO3LF-A     I1 @SCM_LIB.SCM(SCH_1):PAGE35

FM_PRSNT_0_R_N @SCM_LIB.SCM(SCH_1):FM_PRSNT_0_R_N
  R822    2      B Q_RES_0402LF-0,5%,1/16W,CHIP,CA   I456 @SCM_LIB.SCM(SCH_1):PAGE10
   GF1  OB3 PRSNT0_N FCONN168_ME1016810202011_SCM-FA   I553 @SCM_LIB.SCM(SCH_1):PAGE10

FM_PRSNT_1_N @SCM_LIB.SCM(SCH_1):FM_PRSNT_1_N
  R822    1      A Q_RES_0402LF-0,5%,1/16W,CHIP,CA   I456 @SCM_LIB.SCM(SCH_1):PAGE10
   GF1  A57 PRSNT1_N FCONN168_ME1016810202011_SCM-FA   I553 @SCM_LIB.SCM(SCH_1):PAGE10

FM_PWR_BTN @SCM_LIB.SCM(SCH_1):FM_PWR_BTN
    U5 AB22 GPIOP0||PWM8||THRUIN0 AST2600A3GP-AST2600A3-GP,SMLF,A   I350 @SCM_LIB.SCM(SCH_1):PAGE15
  R432    2      B Q_RES_0402LF-0,5%,1/16W,CHIP,CA   I100 @SCM_LIB.SCM(SCH_1):PAGE35
  R225    1      A Q_RES_0402LF-100,1%,1/16W,CHIPA   I405 @SCM_LIB.SCM(SCH_1):PAGE15

FM_PWR_R_BTN @SCM_LIB.SCM(SCH_1):FM_PWR_R_BTN
   U25  K14  PR10A LCMXO3LF2100C5BG256C-LCMXO3LF-A     I1 @SCM_LIB.SCM(SCH_1):PAGE35
  R432    1      A Q_RES_0402LF-0,5%,1/16W,CHIP,CA   I100 @SCM_LIB.SCM(SCH_1):PAGE35

FM_SLPS3_GF_N @SCM_LIB.SCM(SCH_1):FM_SLPS3_GF_N
  R774    2      B Q_RES_0402LF-4.7K,1%,1/16W,CHIA   I213 @SCM_LIB.SCM(SCH_1):PAGE13
  R722    2      B Q_RES_0402LF-0,5%,1/16W,CHIP,CA   I350 @SCM_LIB.SCM(SCH_1):PAGE13
  R721    1      A Q_RES_0402LF-0,5%,1/16W,CHIP,CA   I145 @SCM_LIB.SCM(SCH_1):PAGE28
  R773    1      A Q_RES_0402LF-33.2,1%,1/16W,CHIA   I137 @SCM_LIB.SCM(SCH_1):PAGE35

FM_SLPS3_GF_R1_N @SCM_LIB.SCM(SCH_1):FM_SLPS3_GF_R1_N
  R722    1      A Q_RES_0402LF-0,5%,1/16W,CHIP,CA   I350 @SCM_LIB.SCM(SCH_1):PAGE13
    U5 AB15 GPIOV0||SIOS3# AST2600A3GP-AST2600A3-GP,SMLF,A   I363 @SCM_LIB.SCM(SCH_1):PAGE13

FM_SLPS3_GF_R2_N @SCM_LIB.SCM(SCH_1):FM_SLPS3_GF_R2_N
   U40   19    P16 PCA9555PW_SMLF-PCA9555PW,IC,TMA   I141 @SCM_LIB.SCM(SCH_1):PAGE28
  R721    2      B Q_RES_0402LF-0,5%,1/16W,CHIP,CA   I145 @SCM_LIB.SCM(SCH_1):PAGE28

FM_SLPS3_GF_R_N @SCM_LIB.SCM(SCH_1):FM_SLPS3_GF_R_N
   U25  G11   PR5C LCMXO3LF2100C5BG256C-LCMXO3LF-A     I1 @SCM_LIB.SCM(SCH_1):PAGE35
  R773    2      B Q_RES_0402LF-33.2,1%,1/16W,CHIA   I137 @SCM_LIB.SCM(SCH_1):PAGE35

FM_SOL_UART_CH_SEL @SCM_LIB.SCM(SCH_1):FM_SOL_UART_CH_SEL
   GF1 OB14 SPI0_MISO FCONN168_ME1016810202011_SCM-FA   I553 @SCM_LIB.SCM(SCH_1):PAGE10
  R489    1      A Q_RES_0402LF-33.2,1%,1/16W,CHIA   I326 @SCM_LIB.SCM(SCH_1):PAGE15
  R626    1      A Q_RES_0402LF-0,5%,1/16W,CHIP,CA   I161 @SCM_LIB.SCM(SCH_1):PAGE28
  R577    1      A Q_RES_0402LF-0,5%,1/16W,CHIP,CA     I3 @SCM_LIB.SCM(SCH_1):PAGE36

FM_SOL_UART_CH_SEL_R1 @SCM_LIB.SCM(SCH_1):FM_SOL_UART_CH_SEL_R1
  R489    2      B Q_RES_0402LF-33.2,1%,1/16W,CHIA   I326 @SCM_LIB.SCM(SCH_1):PAGE15
    U5 AA26 GPIOQ7||TACH7 AST2600A3GP-AST2600A3-GP,SMLF,A   I350 @SCM_LIB.SCM(SCH_1):PAGE15

FM_SOL_UART_CH_SEL_R2 @SCM_LIB.SCM(SCH_1):FM_SOL_UART_CH_SEL_R2
   U25   T2   PB3C LCMXO3LF2100C5BG256C-LCMXO3LF-A     I1 @SCM_LIB.SCM(SCH_1):PAGE36
  R577    2      B Q_RES_0402LF-0,5%,1/16W,CHIP,CA     I3 @SCM_LIB.SCM(SCH_1):PAGE36

FM_SOL_UART_CH_SEL_R3 @SCM_LIB.SCM(SCH_1):FM_SOL_UART_CH_SEL_R3
  R626    2      B Q_RES_0402LF-0,5%,1/16W,CHIP,CA   I161 @SCM_LIB.SCM(SCH_1):PAGE28
  R736    2      B Q_RES_0402LF-1K,1%,1/16W,CHIP,A   I162 @SCM_LIB.SCM(SCH_1):PAGE28
    Q8    D      D 2N7002A7-2N7002A-7,SMLF,IC,BAMA   I163 @SCM_LIB.SCM(SCH_1):PAGE28

FM_SPD_REMOTE_EN_R @SCM_LIB.SCM(SCH_1):FM_SPD_REMOTE_EN_R
    U5 AC23 GPIOO7||PWM7 AST2600A3GP-AST2600A3-GP,SMLF,A   I350 @SCM_LIB.SCM(SCH_1):PAGE15
   U25  E15   PR1B LCMXO3LF2100C5BG256C-LCMXO3LF-A     I1 @SCM_LIB.SCM(SCH_1):PAGE35

FM_THERMTRIP_DLY_LVC1_R_N @SCM_LIB.SCM(SCH_1):FM_THERMTRIP_DLY_LVC1_R_N
    U5  T26 GPIOS2||PEWAKE# AST2600A3GP-AST2600A3-GP,SMLF,A   I436 @SCM_LIB.SCM(SCH_1):PAGE12
   U25  A15  PT24B LCMXO3LF2100C5BG256C-LCMXO3LF-A     I1 @SCM_LIB.SCM(SCH_1):PAGE34
  R400    2      B Q_RES_0402LF-4.7K,1%,1/16W,EMPA   I454 @SCM_LIB.SCM(SCH_1):PAGE12

FM_THROTTLE_N @SCM_LIB.SCM(SCH_1):FM_THROTTLE_N
   R45    2      B Q_RES_0402LF-4.7K,1%,1/16W,CHIA   I176 @SCM_LIB.SCM(SCH_1):PAGE11
    U5  B16 GPIOI6||SIOPBI# AST2600A3GP-AST2600A3-GP,SMLF,A   I363 @SCM_LIB.SCM(SCH_1):PAGE13
  R769    1      A Q_RES_0402LF-33.2,1%,1/16W,CHIA   I140 @SCM_LIB.SCM(SCH_1):PAGE35

FM_THROTTLE_R_N @SCM_LIB.SCM(SCH_1):FM_THROTTLE_R_N
   U25  J12   PR6D LCMXO3LF2100C5BG256C-LCMXO3LF-A     I1 @SCM_LIB.SCM(SCH_1):PAGE35
  R769    2      B Q_RES_0402LF-33.2,1%,1/16W,CHIA   I140 @SCM_LIB.SCM(SCH_1):PAGE35

FM_TPM_PRSNT_0_N @SCM_LIB.SCM(SCH_1):FM_TPM_PRSNT_0_N
    U5 AC22 GPIOO5||PWM5 AST2600A3GP-AST2600A3-GP,SMLF,A   I350 @SCM_LIB.SCM(SCH_1):PAGE15
    J5    8      8 SCONN11_9192031111LF-SCONN11_9A    I56 @SCM_LIB.SCM(SCH_1):PAGE46
  R464    2      B Q_RES_0402LF-10K,1%,1/16W,CHIPA    I75 @SCM_LIB.SCM(SCH_1):PAGE46
  R767    1      A Q_RES_0402LF-33.2,1%,1/16W,CHIA   I150 @SCM_LIB.SCM(SCH_1):PAGE34

FM_TPM_PRSNT_0_R_N @SCM_LIB.SCM(SCH_1):FM_TPM_PRSNT_0_R_N
   U25   C4   PT9A LCMXO3LF2100C5BG256C-LCMXO3LF-A     I1 @SCM_LIB.SCM(SCH_1):PAGE34
  R767    2      B Q_RES_0402LF-33.2,1%,1/16W,CHIA   I150 @SCM_LIB.SCM(SCH_1):PAGE34

FM_TPM_PRSNT_1_N @SCM_LIB.SCM(SCH_1):FM_TPM_PRSNT_1_N
    U5  R24 GPIOS3||OSCCLK AST2600A3GP-AST2600A3-GP,SMLF,A   I436 @SCM_LIB.SCM(SCH_1):PAGE12
   R50    2      B Q_RES_0402LF-10K,1%,1/16W,CHIPA   I104 @SCM_LIB.SCM(SCH_1):PAGE46
   J10    8      8 SCONN11_9192031111LF-SCONN11_9A   I113 @SCM_LIB.SCM(SCH_1):PAGE46
  R123    1      A Q_RES_0402LF-33.2,1%,1/16W,CHIA   I156 @SCM_LIB.SCM(SCH_1):PAGE34

FM_TPM_PRSNT_1_R_N @SCM_LIB.SCM(SCH_1):FM_TPM_PRSNT_1_R_N
   U25   B5   PT9B LCMXO3LF2100C5BG256C-LCMXO3LF-A     I1 @SCM_LIB.SCM(SCH_1):PAGE34
  R123    2      B Q_RES_0402LF-33.2,1%,1/16W,CHIA   I156 @SCM_LIB.SCM(SCH_1):PAGE34

FM_UARTSW_LSB_N @SCM_LIB.SCM(SCH_1):FM_UARTSW_LSB_N
    U2    5     S2 FSA3357K8X-FSA3357K8X,SMLF,IC,A   I250 @SCM_LIB.SCM(SCH_1):PAGE30
    U3    5     S2 FSA3357K8X-FSA3357K8X,SMLF,IC,A   I251 @SCM_LIB.SCM(SCH_1):PAGE30
  R898    2      B Q_RES_0402LF-0,5%,1/16W,CHIP,CA    I42 @SCM_LIB.SCM(SCH_1):PAGE36
  R134    2      B Q_RES_0402LF-0,5%,1/16W,CHIP,CA    I47 @SCM_LIB.SCM(SCH_1):PAGE36
  R283    1      A Q_RES_0402LF-75,1%,1/16W,CHIP,A    I88 @SCM_LIB.SCM(SCH_1):PAGE49

FM_UARTSW_LSB_R1_N @SCM_LIB.SCM(SCH_1):FM_UARTSW_LSB_R1_N
   D18    C      C Q_LED_SMLF-LED_BLUE,LTST-C281TA    I51 @SCM_LIB.SCM(SCH_1):PAGE49
  R283    2      B Q_RES_0402LF-75,1%,1/16W,CHIP,A    I88 @SCM_LIB.SCM(SCH_1):PAGE49

FM_UARTSW_LSB_R_N @SCM_LIB.SCM(SCH_1):FM_UARTSW_LSB_R_N
   U25   M9  PB18C LCMXO3LF2100C5BG256C-LCMXO3LF-A     I1 @SCM_LIB.SCM(SCH_1):PAGE36
  R898    1      A Q_RES_0402LF-0,5%,1/16W,CHIP,CA    I42 @SCM_LIB.SCM(SCH_1):PAGE36

FM_UARTSW_MSB_N @SCM_LIB.SCM(SCH_1):FM_UARTSW_MSB_N
    U2    6     S1 FSA3357K8X-FSA3357K8X,SMLF,IC,A   I250 @SCM_LIB.SCM(SCH_1):PAGE30
    U3    6     S1 FSA3357K8X-FSA3357K8X,SMLF,IC,A   I251 @SCM_LIB.SCM(SCH_1):PAGE30
  R899    2      B Q_RES_0402LF-0,5%,1/16W,CHIP,CA    I43 @SCM_LIB.SCM(SCH_1):PAGE36
  R220    2      B Q_RES_0402LF-0,5%,1/16W,CHIP,CA    I46 @SCM_LIB.SCM(SCH_1):PAGE36
  R284    1      A Q_RES_0402LF-75,1%,1/16W,CHIP,A    I89 @SCM_LIB.SCM(SCH_1):PAGE49

FM_UARTSW_MSB_R1_N @SCM_LIB.SCM(SCH_1):FM_UARTSW_MSB_R1_N
   D19    C      C Q_LED_SMLF-LED_BLUE,LTST-C281TA    I50 @SCM_LIB.SCM(SCH_1):PAGE49
  R284    2      B Q_RES_0402LF-75,1%,1/16W,CHIP,A    I89 @SCM_LIB.SCM(SCH_1):PAGE49

FM_UARTSW_MSB_R_N @SCM_LIB.SCM(SCH_1):FM_UARTSW_MSB_R_N
   U25  L10  PB18D LCMXO3LF2100C5BG256C-LCMXO3LF-A     I1 @SCM_LIB.SCM(SCH_1):PAGE36
  R899    1      A Q_RES_0402LF-0,5%,1/16W,CHIP,CA    I43 @SCM_LIB.SCM(SCH_1):PAGE36

FM_UART_SEL_N @SCM_LIB.SCM(SCH_1):FM_UART_SEL_N
    Q8    G      G 2N7002A7-2N7002A-7,SMLF,IC,BAMA   I163 @SCM_LIB.SCM(SCH_1):PAGE28
   R83    1      A Q_RES_0402LF-0,5%,1/16W,CHIP,CA   I164 @SCM_LIB.SCM(SCH_1):PAGE28

FM_UART_SWITCH_N @SCM_LIB.SCM(SCH_1):FM_UART_SWITCH_N
   U40   20    P17 PCA9555PW_SMLF-PCA9555PW,IC,TMA   I141 @SCM_LIB.SCM(SCH_1):PAGE28
   R83    2      B Q_RES_0402LF-0,5%,1/16W,CHIP,CA   I164 @SCM_LIB.SCM(SCH_1):PAGE28
  R735    2      B Q_RES_0402LF-1K,1%,1/16W,CHIP,A   I166 @SCM_LIB.SCM(SCH_1):PAGE28

FM_VIRTUAL_RESEAT @SCM_LIB.SCM(SCH_1):FM_VIRTUAL_RESEAT
   GF1 OA14 VIRTUAL_RESEAT FCONN168_ME1016810202011_SCM-FA   I553 @SCM_LIB.SCM(SCH_1):PAGE10
  R823    2      B Q_RES_0402LF-100K,1%,1/16W,CHIA   I234 @SCM_LIB.SCM(SCH_1):PAGE11
  R824    1      A Q_RES_0402LF-33.2,1%,1/16W,CHIA   I223 @SCM_LIB.SCM(SCH_1):PAGE13

FM_VIRTUAL_RESEAT_BMC @SCM_LIB.SCM(SCH_1):FM_VIRTUAL_RESEAT_BMC
  R824    2      B Q_RES_0402LF-33.2,1%,1/16W,CHIA   I223 @SCM_LIB.SCM(SCH_1):PAGE13
    U5  B13 GPIOM1||NDCD1 AST2600A3GP-AST2600A3-GP,SMLF,A   I363 @SCM_LIB.SCM(SCH_1):PAGE13

FRU_E0 @SCM_LIB.SCM(SCH_1):FRU_E0
  R411    1      A Q_RES_0402LF-100,1%,1/16W,CHIPA     I6 @SCM_LIB.SCM(SCH_1):PAGE26
   R12    2      B Q_RES_0402LF-4.7K,1%,1/16W,EMPA     I9 @SCM_LIB.SCM(SCH_1):PAGE26
   U19    1     E0 M24128BWDW6TP-M24128-BWDW6TP,SA    I15 @SCM_LIB.SCM(SCH_1):PAGE26

FRU_E1 @SCM_LIB.SCM(SCH_1):FRU_E1
  R412    1      A Q_RES_0402LF-100,1%,1/16W,CHIPA     I8 @SCM_LIB.SCM(SCH_1):PAGE26
   R13    2      B Q_RES_0402LF-4.7K,1%,1/16W,EMPA    I11 @SCM_LIB.SCM(SCH_1):PAGE26
   U19    2     E1 M24128BWDW6TP-M24128-BWDW6TP,SA    I15 @SCM_LIB.SCM(SCH_1):PAGE26

FRU_E2 @SCM_LIB.SCM(SCH_1):FRU_E2
  R413    1      A Q_RES_0402LF-100,1%,1/16W,CHIPA    I12 @SCM_LIB.SCM(SCH_1):PAGE26
   R14    2      B Q_RES_0402LF-4.7K,1%,1/16W,EMPA    I14 @SCM_LIB.SCM(SCH_1):PAGE26
   U19    3     E2 M24128BWDW6TP-M24128-BWDW6TP,SA    I15 @SCM_LIB.SCM(SCH_1):PAGE26

GND @SCM_LIB.SCM(SCH_1):GND
  C174    2      B Q_CAP_0402-0.1UF,25V,10%,EMPTYA   I503 @SCM_LIB.SCM(SCH_1):PAGE10
   GF1  A13 GND_A13 FCONN168_ME1016810202011_SCM-FA   I553 @SCM_LIB.SCM(SCH_1):PAGE10
   GF1  A16 GND_A16 FCONN168_ME1016810202011_SCM-FA   I553 @SCM_LIB.SCM(SCH_1):PAGE10
   GF1  A19 GND_A19 FCONN168_ME1016810202011_SCM-FA   I553 @SCM_LIB.SCM(SCH_1):PAGE10
   GF1  A22 GND_A22 FCONN168_ME1016810202011_SCM-FA   I553 @SCM_LIB.SCM(SCH_1):PAGE10
   GF1  A33 GND_A33 FCONN168_ME1016810202011_SCM-FA   I553 @SCM_LIB.SCM(SCH_1):PAGE10
   GF1  A42 GND_A42 FCONN168_ME1016810202011_SCM-FA   I553 @SCM_LIB.SCM(SCH_1):PAGE10
   GF1  A58 GND_A58 FCONN168_ME1016810202011_SCM-FA   I553 @SCM_LIB.SCM(SCH_1):PAGE10
   GF1  A61 GND_A61 FCONN168_ME1016810202011_SCM-FA   I553 @SCM_LIB.SCM(SCH_1):PAGE10
   GF1  A64 GND_A64 FCONN168_ME1016810202011_SCM-FA   I553 @SCM_LIB.SCM(SCH_1):PAGE10
   GF1  A67 GND_A67 FCONN168_ME1016810202011_SCM-FA   I553 @SCM_LIB.SCM(SCH_1):PAGE10
   GF1  A70 GND_A70 FCONN168_ME1016810202011_SCM-FA   I553 @SCM_LIB.SCM(SCH_1):PAGE10
   GF1  B10 GND_B10 FCONN168_ME1016810202011_SCM-FA   I553 @SCM_LIB.SCM(SCH_1):PAGE10
   GF1  B17 GND_B17 FCONN168_ME1016810202011_SCM-FA   I553 @SCM_LIB.SCM(SCH_1):PAGE10
   GF1  B26 GND_B26 FCONN168_ME1016810202011_SCM-FA   I553 @SCM_LIB.SCM(SCH_1):PAGE10
   GF1  B33 GND_B33 FCONN168_ME1016810202011_SCM-FA   I553 @SCM_LIB.SCM(SCH_1):PAGE10
   GF1  B38 GND_B38 FCONN168_ME1016810202011_SCM-FA   I553 @SCM_LIB.SCM(SCH_1):PAGE10
   GF1  B49 GND_B49 FCONN168_ME1016810202011_SCM-FA   I553 @SCM_LIB.SCM(SCH_1):PAGE10
   GF1  B52 GND_B52 FCONN168_ME1016810202011_SCM-FA   I553 @SCM_LIB.SCM(SCH_1):PAGE10
   GF1  B55 GND_B55 FCONN168_ME1016810202011_SCM-FA   I553 @SCM_LIB.SCM(SCH_1):PAGE10
   GF1  B58 GND_B58 FCONN168_ME1016810202011_SCM-FA   I553 @SCM_LIB.SCM(SCH_1):PAGE10
   GF1  B61 GND_B61 FCONN168_ME1016810202011_SCM-FA   I553 @SCM_LIB.SCM(SCH_1):PAGE10
   GF1  B64 GND_B64 FCONN168_ME1016810202011_SCM-FA   I553 @SCM_LIB.SCM(SCH_1):PAGE10
   GF1  B67 GND_B67 FCONN168_ME1016810202011_SCM-FA   I553 @SCM_LIB.SCM(SCH_1):PAGE10
   GF1  B70 GND_B70 FCONN168_ME1016810202011_SCM-FA   I553 @SCM_LIB.SCM(SCH_1):PAGE10
   GF1  OA3 GND_OA3 FCONN168_ME1016810202011_SCM-FA   I553 @SCM_LIB.SCM(SCH_1):PAGE10
   GF1  OA4 GND_OA4 FCONN168_ME1016810202011_SCM-FA   I553 @SCM_LIB.SCM(SCH_1):PAGE10
   GF1 OA13 GND_OA13 FCONN168_ME1016810202011_SCM-FA   I553 @SCM_LIB.SCM(SCH_1):PAGE10
   GF1  OB4 GND_OB4 FCONN168_ME1016810202011_SCM-FA   I553 @SCM_LIB.SCM(SCH_1):PAGE10
   GF1  OB7 GND_OB7 FCONN168_ME1016810202011_SCM-FA   I553 @SCM_LIB.SCM(SCH_1):PAGE10
   GF1 OB10 GND_OB10 FCONN168_ME1016810202011_SCM-FA   I553 @SCM_LIB.SCM(SCH_1):PAGE10
   R40    1      A Q_RES_0402LF-2K,1%,1/16W,EMPTYA   I171 @SCM_LIB.SCM(SCH_1):PAGE11
   R66    1      A Q_RES_0402LF-100K,1%,1/16W,CHIA   I181 @SCM_LIB.SCM(SCH_1):PAGE11
   R63    2      B Q_RES_0402LF-0,5%,1/16W,EMPTY,A   I231 @SCM_LIB.SCM(SCH_1):PAGE11
   R64    2      B Q_RES_0402LF-0,5%,1/16W,EMPTY,A   I233 @SCM_LIB.SCM(SCH_1):PAGE11
  R823    1      A Q_RES_0402LF-100K,1%,1/16W,CHIA   I234 @SCM_LIB.SCM(SCH_1):PAGE11
   C21    2      B Q_CAP_C0402-0.01UF,50V,10%,EMPA    I24 @SCM_LIB.SCM(SCH_1):PAGE12
   C23    2      B Q_CAP_0402-0.1UF,25V,10%,X7R,CA    I28 @SCM_LIB.SCM(SCH_1):PAGE12
  R127    1      A Q_RES_0402LF-240,1%,1/16W,CHIPA    I46 @SCM_LIB.SCM(SCH_1):PAGE12
  R118    1      A Q_RES_0402LF-100K,1%,1/16W,CHIA    I53 @SCM_LIB.SCM(SCH_1):PAGE12
  R820    2      B Q_RES_0402LF-100K,1%,1/16W,EMPA   I390 @SCM_LIB.SCM(SCH_1):PAGE12
  R819    2      B Q_RES_0402LF-100K,1%,1/16W,EMPA   I391 @SCM_LIB.SCM(SCH_1):PAGE12
  R818    2      B Q_RES_0402LF-100K,1%,1/16W,EMPA   I392 @SCM_LIB.SCM(SCH_1):PAGE12
  R817    2      B Q_RES_0402LF-100K,1%,1/16W,EMPA   I393 @SCM_LIB.SCM(SCH_1):PAGE12
   C30    2      B Q_CAP_C0402-1UF,25V,10%,X6S,CHA    I29 @SCM_LIB.SCM(SCH_1):PAGE13
   C31    2      B Q_CAP_0402-0.1UF,25V,10%,X7R,CA    I30 @SCM_LIB.SCM(SCH_1):PAGE13
   C32    2      B Q_CAP_C0402-1UF,25V,10%,X6S,CHA    I31 @SCM_LIB.SCM(SCH_1):PAGE13
   C33    2      B Q_CAP_0402-0.1UF,25V,10%,X7R,CA    I32 @SCM_LIB.SCM(SCH_1):PAGE13
  R273    2      B Q_RES_0402LF-100K,1%,1/16W,CHIA   I340 @SCM_LIB.SCM(SCH_1):PAGE13
  R684    2      B Q_RES_0402LF-1K,1%,1/16W,EMPTYB   I163 @SCM_LIB.SCM(SCH_1):PAGE14
  R685    2      B Q_RES_0402LF-1K,1%,1/16W,EMPTYB   I165 @SCM_LIB.SCM(SCH_1):PAGE14
   C35    2      B Q_CAP_C0402-1UF,25V,10%,X6S,CHA    I14 @SCM_LIB.SCM(SCH_1):PAGE15
   C36    2      B Q_CAP_0402-0.1UF,25V,10%,X7R,CA    I16 @SCM_LIB.SCM(SCH_1):PAGE15
  R209    2      B Q_RES_0402LF-10K,1%,1/16W,EMPTA    I19 @SCM_LIB.SCM(SCH_1):PAGE15
   C37    2      B Q_CAP_0402-0.1UF,25V,10%,X7R,CA    I24 @SCM_LIB.SCM(SCH_1):PAGE15
   C38    2      B Q_CAP_C0402-1UF,25V,10%,X6S,CHA    I36 @SCM_LIB.SCM(SCH_1):PAGE15
   C39    2      B Q_CAP_0402-0.1UF,25V,10%,X7R,CA    I37 @SCM_LIB.SCM(SCH_1):PAGE15
  OSC1    2    GND OSC4_7X25000018-25MHZ,SMLF,MISA    I39 @SCM_LIB.SCM(SCH_1):PAGE15
  R210    1      A Q_RES_0402LF-1K,1%,1/16W,CHIP,A    I47 @SCM_LIB.SCM(SCH_1):PAGE15
   C41    2      B Q_CAP_0402-0.1UF,25V,10%,X7R,CA    I68 @SCM_LIB.SCM(SCH_1):PAGE15
   C45    2      B Q_CAP_0402-0.1UF,25V,10%,X7R,CA    I89 @SCM_LIB.SCM(SCH_1):PAGE15
   C42    2      B Q_CAP_C0603-22UF,6.3V,20%,X6S,A   I117 @SCM_LIB.SCM(SCH_1):PAGE15
   C43    2      B Q_CAP_C0402-1UF,25V,10%,X6S,CHA   I119 @SCM_LIB.SCM(SCH_1):PAGE15
   R25    2      B Q_RES_0402LF-150,1%,1/16W,CHIPA   I149 @SCM_LIB.SCM(SCH_1):PAGE15
   R23    2      B Q_RES_0402LF-150,1%,1/16W,CHIPA   I150 @SCM_LIB.SCM(SCH_1):PAGE15
   R22    2      B Q_RES_0402LF-150,1%,1/16W,CHIPA   I151 @SCM_LIB.SCM(SCH_1):PAGE15
  C275    2      B Q_CAP_0402-100PF,50V,5%,NPO,CHA   I180 @SCM_LIB.SCM(SCH_1):PAGE15
  R778    2      B Q_RES_0402LF-100K,1%,1/16W,CHIA   I181 @SCM_LIB.SCM(SCH_1):PAGE15
  R776    2      B Q_RES_0402LF-47K,1%,1/16W,CHIPA   I184 @SCM_LIB.SCM(SCH_1):PAGE15
  C290    2      B Q_CAP_0402-0.1UF,25V,10%,X7R,CA   I201 @SCM_LIB.SCM(SCH_1):PAGE15
  R786    2      B Q_RES_0402LF-2K,1%,1/16W,CHIP,A   I203 @SCM_LIB.SCM(SCH_1):PAGE15
  C295    2      B Q_CAP_0402-0.1UF,25V,10%,X7R,CA   I207 @SCM_LIB.SCM(SCH_1):PAGE15
  R788    2      B Q_RES_0402LF-2K,1%,1/16W,CHIP,A   I211 @SCM_LIB.SCM(SCH_1):PAGE15
  C299    2      B Q_CAP_0402-0.1UF,25V,10%,X7R,CA   I215 @SCM_LIB.SCM(SCH_1):PAGE15
  R790    2      B Q_RES_0402LF-2K,1%,1/16W,CHIP,A   I220 @SCM_LIB.SCM(SCH_1):PAGE15
  C303    2      B Q_CAP_0402-0.1UF,25V,10%,X7R,CA   I235 @SCM_LIB.SCM(SCH_1):PAGE15
  R792    2      B Q_RES_0402LF-2K,1%,1/16W,CHIP,A   I236 @SCM_LIB.SCM(SCH_1):PAGE15
  C307    2      B Q_CAP_0402-0.1UF,25V,10%,X7R,CA   I240 @SCM_LIB.SCM(SCH_1):PAGE15
  R794    2      B Q_RES_0402LF-2K,1%,1/16W,CHIP,A   I242 @SCM_LIB.SCM(SCH_1):PAGE15
  C309    2      B Q_CAP_0402-0.1UF,25V,10%,X7R,CA   I247 @SCM_LIB.SCM(SCH_1):PAGE15
  C311    2      B Q_CAP_0402-0.1UF,25V,10%,X7R,CA   I256 @SCM_LIB.SCM(SCH_1):PAGE15
  C314    2      B Q_CAP_0402-0.1UF,25V,10%,X7R,CA   I259 @SCM_LIB.SCM(SCH_1):PAGE15
  R798    2      B Q_RES_0402LF-2K,1%,1/16W,CHIP,A   I262 @SCM_LIB.SCM(SCH_1):PAGE15
   C55    2      B Q_CAP_C0603-22UF,6.3V,20%,X6S,A    I23 @SCM_LIB.SCM(SCH_1):PAGE16
   C52    2      B Q_CAP_C0402-1UF,25V,10%,X6S,CHA    I31 @SCM_LIB.SCM(SCH_1):PAGE16
   C54    2      B Q_CAP_0402-0.1UF,25V,10%,X7R,CA    I32 @SCM_LIB.SCM(SCH_1):PAGE16
   C56    2      B Q_CAP_C0402-1UF,25V,10%,X6S,CHA    I33 @SCM_LIB.SCM(SCH_1):PAGE16
   C63    2      B Q_CAP_0402-2200PF,50V,10%,X7R,A    I46 @SCM_LIB.SCM(SCH_1):PAGE16
   C67    2      B Q_CAP_C0402-1UF,25V,10%,X6S,CHA    I48 @SCM_LIB.SCM(SCH_1):PAGE16
   C71    2      B Q_CAP_0402-0.1UF,25V,10%,X7R,CA    I49 @SCM_LIB.SCM(SCH_1):PAGE16
   C73    2      B Q_CAP_0402-0.1UF,25V,10%,X7R,CA    I51 @SCM_LIB.SCM(SCH_1):PAGE16
   C58    2      B Q_CAP_C0402-1UF,25V,10%,X6S,CHA    I52 @SCM_LIB.SCM(SCH_1):PAGE16
   C62    2      B Q_CAP_C0402-1UF,25V,10%,X6S,CHA    I53 @SCM_LIB.SCM(SCH_1):PAGE16
   C66    2      B Q_CAP_0402-0.1UF,25V,10%,X7R,CA    I54 @SCM_LIB.SCM(SCH_1):PAGE16
   C61    2      B Q_CAP_C0402-1UF,25V,10%,X6S,CHA    I55 @SCM_LIB.SCM(SCH_1):PAGE16
   C70    2      B Q_CAP_0402-0.1UF,25V,10%,X7R,CA    I57 @SCM_LIB.SCM(SCH_1):PAGE16
   C72    2      B Q_CAP_0402-0.1UF,25V,10%,X7R,CA    I58 @SCM_LIB.SCM(SCH_1):PAGE16
   C69    2      B Q_CAP_0402-0.1UF,25V,10%,X7R,CA    I59 @SCM_LIB.SCM(SCH_1):PAGE16
   C74    2      B Q_CAP_0402-0.1UF,25V,10%,X7R,CA    I66 @SCM_LIB.SCM(SCH_1):PAGE16
   C59    2      B Q_CAP_0402-0.1UF,25V,10%,X7R,CA    I79 @SCM_LIB.SCM(SCH_1):PAGE16
   C64    2      B Q_CAP_C0402-1UF,25V,10%,X6S,CHA    I81 @SCM_LIB.SCM(SCH_1):PAGE16
   C68    2      B Q_CAP_0402-0.1UF,25V,10%,X7R,CA    I82 @SCM_LIB.SCM(SCH_1):PAGE16
  R234    1      A Q_RES_0402LF-49.9K,1%,1/16W,CHA    I86 @SCM_LIB.SCM(SCH_1):PAGE16
  R233    1      A Q_RES_0402LF-49.9K,1%,1/16W,CHA    I87 @SCM_LIB.SCM(SCH_1):PAGE16
   C75    2      B Q_CAP_C0402-1UF,25V,10%,X6S,CHA    I93 @SCM_LIB.SCM(SCH_1):PAGE16
   C77    2      B Q_CAP_0402-0.1UF,25V,10%,X7R,CA   I100 @SCM_LIB.SCM(SCH_1):PAGE16
   C83    2      B Q_CAP_0402-0.1UF,25V,10%,X7R,CA   I106 @SCM_LIB.SCM(SCH_1):PAGE16
   C89    2      B Q_CAP_0402-0.1UF,25V,10%,X7R,CA   I118 @SCM_LIB.SCM(SCH_1):PAGE16
   C95    2      B Q_CAP_0402-0.1UF,25V,10%,X7R,CA   I119 @SCM_LIB.SCM(SCH_1):PAGE16
   C85    2      B Q_CAP_0402-0.1UF,25V,10%,X7R,CA   I120 @SCM_LIB.SCM(SCH_1):PAGE16
   C88    2      B Q_CAP_0402-0.1UF,25V,10%,X7R,CA   I123 @SCM_LIB.SCM(SCH_1):PAGE16
   C94    2      B Q_CAP_0402-0.1UF,25V,10%,X7R,CA   I124 @SCM_LIB.SCM(SCH_1):PAGE16
  C102    2      B Q_CAP_0402-0.1UF,25V,10%,X7R,CA   I126 @SCM_LIB.SCM(SCH_1):PAGE16
  C106    2      B Q_CAP_C0402-1UF,25V,10%,X6S,CHA   I127 @SCM_LIB.SCM(SCH_1):PAGE16
  C111    2      B Q_CAP_C0402-1UF,25V,10%,X6S,CHA   I128 @SCM_LIB.SCM(SCH_1):PAGE16
  C116    2      B Q_CAP_C0402-1UF,25V,10%,X6S,CHA   I129 @SCM_LIB.SCM(SCH_1):PAGE16
  C121    2      B Q_CAP_C0603-22UF,6.3V,20%,X6S,A   I131 @SCM_LIB.SCM(SCH_1):PAGE16
  C101    2      B Q_CAP_0402-0.1UF,25V,10%,X7R,CA   I132 @SCM_LIB.SCM(SCH_1):PAGE16
  C110    2      B Q_CAP_C0402-1UF,25V,10%,X6S,CHA   I133 @SCM_LIB.SCM(SCH_1):PAGE16
  C115    2      B Q_CAP_C0402-1UF,25V,10%,X6S,CHA   I135 @SCM_LIB.SCM(SCH_1):PAGE16
  C126    2      B Q_CAP_C0603-22UF,6.3V,20%,X6S,A   I143 @SCM_LIB.SCM(SCH_1):PAGE16
   C87    2      B Q_CAP_0402-0.1UF,25V,10%,X7R,CA   I147 @SCM_LIB.SCM(SCH_1):PAGE16
   C93    2      B Q_CAP_0402-0.1UF,25V,10%,X7R,CA   I148 @SCM_LIB.SCM(SCH_1):PAGE16
   C86    2      B Q_CAP_0402-0.1UF,25V,10%,X7R,CA   I149 @SCM_LIB.SCM(SCH_1):PAGE16
   C92    2      B Q_CAP_0402-0.1UF,25V,10%,X7R,CA   I150 @SCM_LIB.SCM(SCH_1):PAGE16
   C91    2      B Q_CAP_0402-0.1UF,25V,10%,X7R,CA   I151 @SCM_LIB.SCM(SCH_1):PAGE16
  C100    2      B Q_CAP_0402-0.1UF,25V,10%,X7R,CA   I152 @SCM_LIB.SCM(SCH_1):PAGE16
  C105    2      B Q_CAP_0402-0.1UF,25V,10%,X7R,CA   I153 @SCM_LIB.SCM(SCH_1):PAGE16
   C99    2      B Q_CAP_0402-0.1UF,25V,10%,X7R,CA   I154 @SCM_LIB.SCM(SCH_1):PAGE16
  C104    2      B Q_CAP_C0402-1UF,25V,10%,X6S,CHA   I155 @SCM_LIB.SCM(SCH_1):PAGE16
  C109    2      B Q_CAP_0402-0.1UF,25V,10%,X7R,CA   I156 @SCM_LIB.SCM(SCH_1):PAGE16
  C108    2      B Q_CAP_C0402-1UF,25V,10%,X6S,CHA   I157 @SCM_LIB.SCM(SCH_1):PAGE16
  C114    2      B Q_CAP_C0402-1UF,25V,10%,X6S,CHA   I158 @SCM_LIB.SCM(SCH_1):PAGE16
  C119    2      B Q_CAP_C0402-1UF,25V,10%,X6S,CHA   I159 @SCM_LIB.SCM(SCH_1):PAGE16
  C118    2      B Q_CAP_C0603-22UF,6.3V,20%,X6S,A   I162 @SCM_LIB.SCM(SCH_1):PAGE16
   C98    2      B Q_CAP_0402-0.1UF,25V,10%,X7R,CA   I163 @SCM_LIB.SCM(SCH_1):PAGE16
  C103    2      B Q_CAP_0402-0.1UF,25V,10%,X7R,CA   I164 @SCM_LIB.SCM(SCH_1):PAGE16
  C107    2      B Q_CAP_0402-0.1UF,25V,10%,X7R,CA   I165 @SCM_LIB.SCM(SCH_1):PAGE16
  C112    2      B Q_CAP_0402-0.1UF,25V,10%,X7R,CA   I166 @SCM_LIB.SCM(SCH_1):PAGE16
  C117    2      B Q_CAP_C0402-1UF,25V,10%,X6S,CHA   I167 @SCM_LIB.SCM(SCH_1):PAGE16
  C122    2      B Q_CAP_C0402-1UF,25V,10%,X6S,CHA   I168 @SCM_LIB.SCM(SCH_1):PAGE16
  C124    2      B Q_CAP_C0603-22UF,6.3V,20%,X6S,A   I169 @SCM_LIB.SCM(SCH_1):PAGE16
  C123    2      B Q_CAP_C0603-22UF,6.3V,20%,X6S,A   I171 @SCM_LIB.SCM(SCH_1):PAGE16
  C127    2      B Q_CAP_C0402-1UF,25V,10%,X6S,CHA   I173 @SCM_LIB.SCM(SCH_1):PAGE16
  C129    2      B Q_CAP_C0402-1UF,25V,10%,X6S,CHA   I174 @SCM_LIB.SCM(SCH_1):PAGE16
   C84    2      B Q_CAP_0402-0.1UF,25V,10%,X7R,CA   I179 @SCM_LIB.SCM(SCH_1):PAGE16
   C82    2      B Q_CAP_0402-0.1UF,25V,10%,X7R,CA   I180 @SCM_LIB.SCM(SCH_1):PAGE16
   C76    2      B Q_CAP_0402-0.1UF,25V,10%,X7R,CA   I183 @SCM_LIB.SCM(SCH_1):PAGE16
  R235    1      A Q_RES_0402LF-2.74K,1%,1/16W,CHA   I187 @SCM_LIB.SCM(SCH_1):PAGE16
  C140    2      B Q_CAP_0402-0.1UF,25V,10%,X7R,CA    I97 @SCM_LIB.SCM(SCH_1):PAGE17
  C139    2      B Q_CAP_0402-0.1UF,25V,10%,X7R,CA    I98 @SCM_LIB.SCM(SCH_1):PAGE17
  C133    1      A Q_CAP_C0402-0.01UF,50V,10%,X7RA   I104 @SCM_LIB.SCM(SCH_1):PAGE17
  C134    1      A Q_CAP_C0402-0.01UF,50V,10%,X7RA   I106 @SCM_LIB.SCM(SCH_1):PAGE17
  C135    1      A Q_CAP_C0402-0.01UF,50V,10%,X7RA   I107 @SCM_LIB.SCM(SCH_1):PAGE17
  C136    1      A Q_CAP_C0402-0.01UF,50V,10%,X7RA   I110 @SCM_LIB.SCM(SCH_1):PAGE17
   C49    2      B Q_CAP_0402-0.1UF,25V,10%,X7R,CA   I118 @SCM_LIB.SCM(SCH_1):PAGE17
   C46    2      B Q_CAP_C0402-1UF,25V,10%,X6S,CHA   I122 @SCM_LIB.SCM(SCH_1):PAGE17
   C50    2      B Q_CAP_0402-0.1UF,25V,10%,X7R,CA   I126 @SCM_LIB.SCM(SCH_1):PAGE17
   C47    2      B Q_CAP_C0402-1UF,25V,10%,X6S,CHA   I128 @SCM_LIB.SCM(SCH_1):PAGE17
   C57    2      B Q_CAP_0402-0.1UF,25V,10%,X7R,CA   I133 @SCM_LIB.SCM(SCH_1):PAGE17
   C53    2      B Q_CAP_C0402-1UF,25V,10%,X6S,CHA   I135 @SCM_LIB.SCM(SCH_1):PAGE17
   C65    2      B Q_CAP_0402-0.1UF,25V,10%,X7R,CA   I139 @SCM_LIB.SCM(SCH_1):PAGE17
   C60    2      B Q_CAP_C0402-1UF,25V,10%,X6S,CHA   I141 @SCM_LIB.SCM(SCH_1):PAGE17
   C51    2      B Q_CAP_0402-0.1UF,25V,10%,X7R,CA   I145 @SCM_LIB.SCM(SCH_1):PAGE17
   C48    2      B Q_CAP_C0402-1UF,25V,10%,X6S,CHA   I148 @SCM_LIB.SCM(SCH_1):PAGE17
   C81    2      B Q_CAP_0402-0.1UF,25V,10%,X7R,CA   I151 @SCM_LIB.SCM(SCH_1):PAGE17
   C80    2      B Q_CAP_C0402-1UF,25V,10%,X6S,CHA   I153 @SCM_LIB.SCM(SCH_1):PAGE17
   C79    2      B Q_CAP_0402-0.1UF,25V,10%,X7R,CA   I157 @SCM_LIB.SCM(SCH_1):PAGE17
   C78    2      B Q_CAP_C0402-1UF,25V,10%,X6S,CHA   I160 @SCM_LIB.SCM(SCH_1):PAGE17
  C130    2      B Q_CAP_0402-0.1UF,25V,10%,X7R,CA   I163 @SCM_LIB.SCM(SCH_1):PAGE17
  C128    2      B Q_CAP_C0402-1UF,25V,10%,X6S,CHA   I165 @SCM_LIB.SCM(SCH_1):PAGE17
   C97    2      B Q_CAP_0402-0.1UF,25V,10%,X7R,CA   I169 @SCM_LIB.SCM(SCH_1):PAGE17
   C90    2      B Q_CAP_C0402-1UF,25V,10%,X6S,CHA   I173 @SCM_LIB.SCM(SCH_1):PAGE17
   C96    2      B Q_CAP_0402-0.1UF,25V,10%,X7R,CA   I178 @SCM_LIB.SCM(SCH_1):PAGE17
  C224    2      B Q_CAP_C0402-10UF,6.3V,20%,X6S,A   I180 @SCM_LIB.SCM(SCH_1):PAGE17
   Q10    S SOURCE MOSFET_N_GSD-DMG6968U-7,SMLF,IA   I227 @SCM_LIB.SCM(SCH_1):PAGE17
  C273    2      B Q_CAP_0402-1UF,16V,10%,EMPTY,TA   I234 @SCM_LIB.SCM(SCH_1):PAGE17
  C270    2      B Q_CAP_0402-1UF,16V,10%,EMPTY,TA   I239 @SCM_LIB.SCM(SCH_1):PAGE17
  C284    2      B Q_CAP_0402-0.1UF,25V,10%,X7R,CA   I250 @SCM_LIB.SCM(SCH_1):PAGE17
  C282    2      B Q_CAP_C0402-1UF,25V,10%,X6S,CHA   I252 @SCM_LIB.SCM(SCH_1):PAGE17
  C277    2      B Q_CAP_C0402-1UF,25V,10%,X6S,CHA   I253 @SCM_LIB.SCM(SCH_1):PAGE17
  C279    2      B Q_CAP_0402-0.1UF,25V,10%,X7R,CA   I255 @SCM_LIB.SCM(SCH_1):PAGE17
  R493    2      B Q_RES_0402LF-150K,1%,1/16W,EMPA   I284 @SCM_LIB.SCM(SCH_1):PAGE17
    U5   A1 GND_A1 AST2600A3GP-AST2600A3-GP,SMLF,A   I286 @SCM_LIB.SCM(SCH_1):PAGE17
    U5   A5 GND_A5 AST2600A3GP-AST2600A3-GP,SMLF,A   I286 @SCM_LIB.SCM(SCH_1):PAGE17
    U5  A26 GND_A26 AST2600A3GP-AST2600A3-GP,SMLF,A   I286 @SCM_LIB.SCM(SCH_1):PAGE17
    U5  AA1 GND_AA1 AST2600A3GP-AST2600A3-GP,SMLF,A   I286 @SCM_LIB.SCM(SCH_1):PAGE17
    U5  AA3 GND_AA3 AST2600A3GP-AST2600A3-GP,SMLF,A   I286 @SCM_LIB.SCM(SCH_1):PAGE17
    U5  AA6 GND_AA6 AST2600A3GP-AST2600A3-GP,SMLF,A   I286 @SCM_LIB.SCM(SCH_1):PAGE17
    U5  AA7 GND_AA7 AST2600A3GP-AST2600A3-GP,SMLF,A   I286 @SCM_LIB.SCM(SCH_1):PAGE17
    U5  AA8 GND_AA8 AST2600A3GP-AST2600A3-GP,SMLF,A   I286 @SCM_LIB.SCM(SCH_1):PAGE17
    U5 AA10 GND_AA10 AST2600A3GP-AST2600A3-GP,SMLF,A   I286 @SCM_LIB.SCM(SCH_1):PAGE17
    U5 AA14 GND_AA14 AST2600A3GP-AST2600A3-GP,SMLF,A   I286 @SCM_LIB.SCM(SCH_1):PAGE17
    U5 AA15 GND_AA15 AST2600A3GP-AST2600A3-GP,SMLF,A   I286 @SCM_LIB.SCM(SCH_1):PAGE17
    U5 AA19 GND_AA19 AST2600A3GP-AST2600A3-GP,SMLF,A   I286 @SCM_LIB.SCM(SCH_1):PAGE17
    U5 AA20 GND_AA20 AST2600A3GP-AST2600A3-GP,SMLF,A   I286 @SCM_LIB.SCM(SCH_1):PAGE17
    U5 AA22 GND_AA22 AST2600A3GP-AST2600A3-GP,SMLF,A   I286 @SCM_LIB.SCM(SCH_1):PAGE17
    U5  AC2 GND_AC2 AST2600A3GP-AST2600A3-GP,SMLF,A   I286 @SCM_LIB.SCM(SCH_1):PAGE17
    U5  AC6 GND_AC6 AST2600A3GP-AST2600A3-GP,SMLF,A   I286 @SCM_LIB.SCM(SCH_1):PAGE17
    U5 AC25 GND_AC25 AST2600A3GP-AST2600A3-GP,SMLF,A   I286 @SCM_LIB.SCM(SCH_1):PAGE17
    U5  AD1 GND_AD1 AST2600A3GP-AST2600A3-GP,SMLF,A   I286 @SCM_LIB.SCM(SCH_1):PAGE17
    U5  AD4 GND_AD4 AST2600A3GP-AST2600A3-GP,SMLF,A   I286 @SCM_LIB.SCM(SCH_1):PAGE17
    U5  AE3 GND_AE3 AST2600A3GP-AST2600A3-GP,SMLF,A   I286 @SCM_LIB.SCM(SCH_1):PAGE17
    U5  AE6 GND_AE6 AST2600A3GP-AST2600A3-GP,SMLF,A   I286 @SCM_LIB.SCM(SCH_1):PAGE17
    U5  AE9 GND_AE9 AST2600A3GP-AST2600A3-GP,SMLF,A   I286 @SCM_LIB.SCM(SCH_1):PAGE17
    U5 AE13 GND_AE13 AST2600A3GP-AST2600A3-GP,SMLF,A   I286 @SCM_LIB.SCM(SCH_1):PAGE17
    U5 AE17 GND_AE17 AST2600A3GP-AST2600A3-GP,SMLF,A   I286 @SCM_LIB.SCM(SCH_1):PAGE17
    U5 AE20 GND_AE20 AST2600A3GP-AST2600A3-GP,SMLF,A   I286 @SCM_LIB.SCM(SCH_1):PAGE17
    U5 AE23 GND_AE23 AST2600A3GP-AST2600A3-GP,SMLF,A   I286 @SCM_LIB.SCM(SCH_1):PAGE17
    U5  AF1 GND_AF1 AST2600A3GP-AST2600A3-GP,SMLF,A   I286 @SCM_LIB.SCM(SCH_1):PAGE17
    U5  AF4 GND_AF4 AST2600A3GP-AST2600A3-GP,SMLF,A   I286 @SCM_LIB.SCM(SCH_1):PAGE17
    U5 AF26 GND_AF26 AST2600A3GP-AST2600A3-GP,SMLF,A   I286 @SCM_LIB.SCM(SCH_1):PAGE17
    U5   B5 GND_B5 AST2600A3GP-AST2600A3-GP,SMLF,A   I286 @SCM_LIB.SCM(SCH_1):PAGE17
    U5  B11 GND_B11 AST2600A3GP-AST2600A3-GP,SMLF,A   I286 @SCM_LIB.SCM(SCH_1):PAGE17
    U5  B15 GND_B15 AST2600A3GP-AST2600A3-GP,SMLF,A   I286 @SCM_LIB.SCM(SCH_1):PAGE17
    U5  B19 GND_B19 AST2600A3GP-AST2600A3-GP,SMLF,A   I286 @SCM_LIB.SCM(SCH_1):PAGE17
    U5  B23 GND_B23 AST2600A3GP-AST2600A3-GP,SMLF,A   I286 @SCM_LIB.SCM(SCH_1):PAGE17
    U5   C3 GND_C3 AST2600A3GP-AST2600A3-GP,SMLF,A   I286 @SCM_LIB.SCM(SCH_1):PAGE17
    U5  D25 GND_D25 AST2600A3GP-AST2600A3-GP,SMLF,A   I286 @SCM_LIB.SCM(SCH_1):PAGE17
    U5   E8 GND_E8 AST2600A3GP-AST2600A3-GP,SMLF,A   I286 @SCM_LIB.SCM(SCH_1):PAGE17
    U5   F6 GND_F6 AST2600A3GP-AST2600A3-GP,SMLF,A   I286 @SCM_LIB.SCM(SCH_1):PAGE17
    U5   F8 GND_F8 AST2600A3GP-AST2600A3-GP,SMLF,A   I286 @SCM_LIB.SCM(SCH_1):PAGE17
    U5  F10 GND_F10 AST2600A3GP-AST2600A3-GP,SMLF,A   I286 @SCM_LIB.SCM(SCH_1):PAGE17
    U5  F12 GND_F12 AST2600A3GP-AST2600A3-GP,SMLF,A   I286 @SCM_LIB.SCM(SCH_1):PAGE17
    U5  F14 GND_F14 AST2600A3GP-AST2600A3-GP,SMLF,A   I286 @SCM_LIB.SCM(SCH_1):PAGE17
    U5  F16 GND_F16 AST2600A3GP-AST2600A3-GP,SMLF,A   I286 @SCM_LIB.SCM(SCH_1):PAGE17
    U5  F17 GND_F17 AST2600A3GP-AST2600A3-GP,SMLF,A   I286 @SCM_LIB.SCM(SCH_1):PAGE17
    U5  F18 GND_F18 AST2600A3GP-AST2600A3-GP,SMLF,A   I286 @SCM_LIB.SCM(SCH_1):PAGE17
    U5  F21 GND_F21 AST2600A3GP-AST2600A3-GP,SMLF,A   I286 @SCM_LIB.SCM(SCH_1):PAGE17
    U5   G2 GND_G2 AST2600A3GP-AST2600A3-GP,SMLF,A   I286 @SCM_LIB.SCM(SCH_1):PAGE17
    U5  G25 GND_G25 AST2600A3GP-AST2600A3-GP,SMLF,A   I286 @SCM_LIB.SCM(SCH_1):PAGE17
    U5   H4 GND_H4 AST2600A3GP-AST2600A3-GP,SMLF,A   I286 @SCM_LIB.SCM(SCH_1):PAGE17
    U5   H9 GND_H9 AST2600A3GP-AST2600A3-GP,SMLF,A   I286 @SCM_LIB.SCM(SCH_1):PAGE17
    U5  H10 GND_H10 AST2600A3GP-AST2600A3-GP,SMLF,A   I286 @SCM_LIB.SCM(SCH_1):PAGE17
    U5  H11 GND_H11 AST2600A3GP-AST2600A3-GP,SMLF,A   I286 @SCM_LIB.SCM(SCH_1):PAGE17
    U5  H13 GND_H13 AST2600A3GP-AST2600A3-GP,SMLF,A   I286 @SCM_LIB.SCM(SCH_1):PAGE17
    U5   J2 GND_J2 AST2600A3GP-AST2600A3-GP,SMLF,A   I286 @SCM_LIB.SCM(SCH_1):PAGE17
    U5  J11 GND_J11 AST2600A3GP-AST2600A3-GP,SMLF,A   I286 @SCM_LIB.SCM(SCH_1):PAGE17
    U5  J13 GND_J13 AST2600A3GP-AST2600A3-GP,SMLF,A   I286 @SCM_LIB.SCM(SCH_1):PAGE17
    U5  J14 GND_J14 AST2600A3GP-AST2600A3-GP,SMLF,A   I286 @SCM_LIB.SCM(SCH_1):PAGE17
    U5  J15 GND_J15 AST2600A3GP-AST2600A3-GP,SMLF,A   I286 @SCM_LIB.SCM(SCH_1):PAGE17
    U5  J16 GND_J16 AST2600A3GP-AST2600A3-GP,SMLF,A   I286 @SCM_LIB.SCM(SCH_1):PAGE17
    U5  J17 GND_J17 AST2600A3GP-AST2600A3-GP,SMLF,A   I286 @SCM_LIB.SCM(SCH_1):PAGE17
    U5  J18 GND_J18 AST2600A3GP-AST2600A3-GP,SMLF,A   I286 @SCM_LIB.SCM(SCH_1):PAGE17
    U5  J19 GND_J19 AST2600A3GP-AST2600A3-GP,SMLF,A   I286 @SCM_LIB.SCM(SCH_1):PAGE17
    U5   K4 GND_K4 AST2600A3GP-AST2600A3-GP,SMLF,A   I286 @SCM_LIB.SCM(SCH_1):PAGE17
    U5   K8 GND_K8 AST2600A3GP-AST2600A3-GP,SMLF,A   I286 @SCM_LIB.SCM(SCH_1):PAGE17
    U5   K9 GND_K9 AST2600A3GP-AST2600A3-GP,SMLF,A   I286 @SCM_LIB.SCM(SCH_1):PAGE17
    U5  K13 GND_K13 AST2600A3GP-AST2600A3-GP,SMLF,A   I286 @SCM_LIB.SCM(SCH_1):PAGE17
    U5  K14 GND_K14 AST2600A3GP-AST2600A3-GP,SMLF,A   I286 @SCM_LIB.SCM(SCH_1):PAGE17
    U5  K15 GND_K15 AST2600A3GP-AST2600A3-GP,SMLF,A   I286 @SCM_LIB.SCM(SCH_1):PAGE17
    U5  K22 GND_K22 AST2600A3GP-AST2600A3-GP,SMLF,A   I286 @SCM_LIB.SCM(SCH_1):PAGE17
    U5   L2 GND_L2 AST2600A3GP-AST2600A3-GP,SMLF,A   I286 @SCM_LIB.SCM(SCH_1):PAGE17
    U5   L8 GND_L8 AST2600A3GP-AST2600A3-GP,SMLF,A   I286 @SCM_LIB.SCM(SCH_1):PAGE17
    U5  L11 GND_L11 AST2600A3GP-AST2600A3-GP,SMLF,A   I286 @SCM_LIB.SCM(SCH_1):PAGE17
    U5  L12 GND_L12 AST2600A3GP-AST2600A3-GP,SMLF,A   I286 @SCM_LIB.SCM(SCH_1):PAGE17
    U5  L15 GND_L15 AST2600A3GP-AST2600A3-GP,SMLF,A   I286 @SCM_LIB.SCM(SCH_1):PAGE17
    U5  L16 GND_L16 AST2600A3GP-AST2600A3-GP,SMLF,A   I286 @SCM_LIB.SCM(SCH_1):PAGE17
    U5  L17 GND_L17 AST2600A3GP-AST2600A3-GP,SMLF,A   I286 @SCM_LIB.SCM(SCH_1):PAGE17
    U5  L18 GND_L18 AST2600A3GP-AST2600A3-GP,SMLF,A   I286 @SCM_LIB.SCM(SCH_1):PAGE17
    U5  L19 GND_L19 AST2600A3GP-AST2600A3-GP,SMLF,A   I286 @SCM_LIB.SCM(SCH_1):PAGE17
    U5  L25 GND_L25 AST2600A3GP-AST2600A3-GP,SMLF,A   I286 @SCM_LIB.SCM(SCH_1):PAGE17
    U5   M4 GND_M4 AST2600A3GP-AST2600A3-GP,SMLF,A   I286 @SCM_LIB.SCM(SCH_1):PAGE17
    U5   M9 GND_M9 AST2600A3GP-AST2600A3-GP,SMLF,A   I286 @SCM_LIB.SCM(SCH_1):PAGE17
    U5  M10 GND_M10 AST2600A3GP-AST2600A3-GP,SMLF,A   I286 @SCM_LIB.SCM(SCH_1):PAGE17
    U5  M12 GND_M12 AST2600A3GP-AST2600A3-GP,SMLF,A   I286 @SCM_LIB.SCM(SCH_1):PAGE17
    U5  M15 GND_M15 AST2600A3GP-AST2600A3-GP,SMLF,A   I286 @SCM_LIB.SCM(SCH_1):PAGE17
    U5  M16 GND_M16 AST2600A3GP-AST2600A3-GP,SMLF,A   I286 @SCM_LIB.SCM(SCH_1):PAGE17
    U5  M17 GND_M17 AST2600A3GP-AST2600A3-GP,SMLF,A   I286 @SCM_LIB.SCM(SCH_1):PAGE17
    U5  M18 GND_M18 AST2600A3GP-AST2600A3-GP,SMLF,A   I286 @SCM_LIB.SCM(SCH_1):PAGE17
    U5  M19 GND_M19 AST2600A3GP-AST2600A3-GP,SMLF,A   I286 @SCM_LIB.SCM(SCH_1):PAGE17
    U5   N2 GND_N2 AST2600A3GP-AST2600A3-GP,SMLF,A   I286 @SCM_LIB.SCM(SCH_1):PAGE17
    U5   N6 GND_N6 AST2600A3GP-AST2600A3-GP,SMLF,A   I286 @SCM_LIB.SCM(SCH_1):PAGE17
    U5   N9 GND_N9 AST2600A3GP-AST2600A3-GP,SMLF,A   I286 @SCM_LIB.SCM(SCH_1):PAGE17
    U5  N10 GND_N10 AST2600A3GP-AST2600A3-GP,SMLF,A   I286 @SCM_LIB.SCM(SCH_1):PAGE17
    U5  N15 GND_N15 AST2600A3GP-AST2600A3-GP,SMLF,A   I286 @SCM_LIB.SCM(SCH_1):PAGE17
    U5  N16 GND_N16 AST2600A3GP-AST2600A3-GP,SMLF,A   I286 @SCM_LIB.SCM(SCH_1):PAGE17
    U5  N17 GND_N17 AST2600A3GP-AST2600A3-GP,SMLF,A   I286 @SCM_LIB.SCM(SCH_1):PAGE17
    U5  N18 GND_N18 AST2600A3GP-AST2600A3-GP,SMLF,A   I286 @SCM_LIB.SCM(SCH_1):PAGE17
    U5  N19 GND_N19 AST2600A3GP-AST2600A3-GP,SMLF,A   I286 @SCM_LIB.SCM(SCH_1):PAGE17
    U5   P4 GND_P4 AST2600A3GP-AST2600A3-GP,SMLF,A   I286 @SCM_LIB.SCM(SCH_1):PAGE17
    U5   P9 GND_P9 AST2600A3GP-AST2600A3-GP,SMLF,A   I286 @SCM_LIB.SCM(SCH_1):PAGE17
    U5  P10 GND_P10 AST2600A3GP-AST2600A3-GP,SMLF,A   I286 @SCM_LIB.SCM(SCH_1):PAGE17
    U5  P15 GND_P15 AST2600A3GP-AST2600A3-GP,SMLF,A   I286 @SCM_LIB.SCM(SCH_1):PAGE17
    U5  P16 GND_P16 AST2600A3GP-AST2600A3-GP,SMLF,A   I286 @SCM_LIB.SCM(SCH_1):PAGE17
    U5  P17 GND_P17 AST2600A3GP-AST2600A3-GP,SMLF,A   I286 @SCM_LIB.SCM(SCH_1):PAGE17
    U5  P18 GND_P18 AST2600A3GP-AST2600A3-GP,SMLF,A   I286 @SCM_LIB.SCM(SCH_1):PAGE17
    U5  P19 GND_P19 AST2600A3GP-AST2600A3-GP,SMLF,A   I286 @SCM_LIB.SCM(SCH_1):PAGE17
    U5   R2 GND_R2 AST2600A3GP-AST2600A3-GP,SMLF,A   I286 @SCM_LIB.SCM(SCH_1):PAGE17
    U5   R8 GND_R8 AST2600A3GP-AST2600A3-GP,SMLF,A   I286 @SCM_LIB.SCM(SCH_1):PAGE17
    U5  R11 GND_R11 AST2600A3GP-AST2600A3-GP,SMLF,A   I286 @SCM_LIB.SCM(SCH_1):PAGE17
    U5  R15 GND_R15 AST2600A3GP-AST2600A3-GP,SMLF,A   I286 @SCM_LIB.SCM(SCH_1):PAGE17
    U5  R16 GND_R16 AST2600A3GP-AST2600A3-GP,SMLF,A   I286 @SCM_LIB.SCM(SCH_1):PAGE17
    U5  R17 GND_R17 AST2600A3GP-AST2600A3-GP,SMLF,A   I286 @SCM_LIB.SCM(SCH_1):PAGE17
    U5  R18 GND_R18 AST2600A3GP-AST2600A3-GP,SMLF,A   I286 @SCM_LIB.SCM(SCH_1):PAGE17
    U5  R19 GND_R19 AST2600A3GP-AST2600A3-GP,SMLF,A   I286 @SCM_LIB.SCM(SCH_1):PAGE17
    U5  R25 GND_R25 AST2600A3GP-AST2600A3-GP,SMLF,A   I286 @SCM_LIB.SCM(SCH_1):PAGE17
    U5   T4 GND_T4 AST2600A3GP-AST2600A3-GP,SMLF,A   I286 @SCM_LIB.SCM(SCH_1):PAGE17
    U5  T11 GND_T11 AST2600A3GP-AST2600A3-GP,SMLF,A   I286 @SCM_LIB.SCM(SCH_1):PAGE17
    U5  T12 GND_T12 AST2600A3GP-AST2600A3-GP,SMLF,A   I286 @SCM_LIB.SCM(SCH_1):PAGE17
    U5  T15 GND_T15 AST2600A3GP-AST2600A3-GP,SMLF,A   I286 @SCM_LIB.SCM(SCH_1):PAGE17
    U5  T16 GND_T16 AST2600A3GP-AST2600A3-GP,SMLF,A   I286 @SCM_LIB.SCM(SCH_1):PAGE17
    U5  T17 GND_T17 AST2600A3GP-AST2600A3-GP,SMLF,A   I286 @SCM_LIB.SCM(SCH_1):PAGE17
    U5  T18 GND_T18 AST2600A3GP-AST2600A3-GP,SMLF,A   I286 @SCM_LIB.SCM(SCH_1):PAGE17
    U5  T19 GND_T19 AST2600A3GP-AST2600A3-GP,SMLF,A   I286 @SCM_LIB.SCM(SCH_1):PAGE17
    U5   U2 GND_U2 AST2600A3GP-AST2600A3-GP,SMLF,A   I286 @SCM_LIB.SCM(SCH_1):PAGE17
    U5   U8 GND_U8 AST2600A3GP-AST2600A3-GP,SMLF,A   I286 @SCM_LIB.SCM(SCH_1):PAGE17
    U5   U9 GND_U9 AST2600A3GP-AST2600A3-GP,SMLF,A   I286 @SCM_LIB.SCM(SCH_1):PAGE17
    U5  U10 GND_U10 AST2600A3GP-AST2600A3-GP,SMLF,A   I286 @SCM_LIB.SCM(SCH_1):PAGE17
    U5  U11 GND_U11 AST2600A3GP-AST2600A3-GP,SMLF,A   I286 @SCM_LIB.SCM(SCH_1):PAGE17
    U5  U12 GND_U12 AST2600A3GP-AST2600A3-GP,SMLF,A   I286 @SCM_LIB.SCM(SCH_1):PAGE17
    U5  U14 GND_U14 AST2600A3GP-AST2600A3-GP,SMLF,A   I286 @SCM_LIB.SCM(SCH_1):PAGE17
    U5  U19 GND_U19 AST2600A3GP-AST2600A3-GP,SMLF,A   I286 @SCM_LIB.SCM(SCH_1):PAGE17
    U5  U22 GND_U22 AST2600A3GP-AST2600A3-GP,SMLF,A   I286 @SCM_LIB.SCM(SCH_1):PAGE17
    U5  U23 GND_U23 AST2600A3GP-AST2600A3-GP,SMLF,A   I286 @SCM_LIB.SCM(SCH_1):PAGE17
    U5   V5 GND_V5 AST2600A3GP-AST2600A3-GP,SMLF,A   I286 @SCM_LIB.SCM(SCH_1):PAGE17
    U5  V11 GND_V11 AST2600A3GP-AST2600A3-GP,SMLF,A   I286 @SCM_LIB.SCM(SCH_1):PAGE17
    U5  V12 GND_V12 AST2600A3GP-AST2600A3-GP,SMLF,A   I286 @SCM_LIB.SCM(SCH_1):PAGE17
    U5  V14 GND_V14 AST2600A3GP-AST2600A3-GP,SMLF,A   I286 @SCM_LIB.SCM(SCH_1):PAGE17
    U5  V15 GND_V15 AST2600A3GP-AST2600A3-GP,SMLF,A   I286 @SCM_LIB.SCM(SCH_1):PAGE17
    U5  V16 GND_V16 AST2600A3GP-AST2600A3-GP,SMLF,A   I286 @SCM_LIB.SCM(SCH_1):PAGE17
    U5  V17 GND_V17 AST2600A3GP-AST2600A3-GP,SMLF,A   I286 @SCM_LIB.SCM(SCH_1):PAGE17
    U5  V18 GND_V18 AST2600A3GP-AST2600A3-GP,SMLF,A   I286 @SCM_LIB.SCM(SCH_1):PAGE17
    U5  V19 GND_V19 AST2600A3GP-AST2600A3-GP,SMLF,A   I286 @SCM_LIB.SCM(SCH_1):PAGE17
    U5   W5 GND_W5 AST2600A3GP-AST2600A3-GP,SMLF,A   I286 @SCM_LIB.SCM(SCH_1):PAGE17
    U5   W6 GND_W6 AST2600A3GP-AST2600A3-GP,SMLF,A   I286 @SCM_LIB.SCM(SCH_1):PAGE17
    U5   W8 GND_W8 AST2600A3GP-AST2600A3-GP,SMLF,A   I286 @SCM_LIB.SCM(SCH_1):PAGE17
    U5   W9 GND_W9 AST2600A3GP-AST2600A3-GP,SMLF,A   I286 @SCM_LIB.SCM(SCH_1):PAGE17
    U5  W10 GND_W10 AST2600A3GP-AST2600A3-GP,SMLF,A   I286 @SCM_LIB.SCM(SCH_1):PAGE17
    U5  W11 GND_W11 AST2600A3GP-AST2600A3-GP,SMLF,A   I286 @SCM_LIB.SCM(SCH_1):PAGE17
    U5  W12 GND_W12 AST2600A3GP-AST2600A3-GP,SMLF,A   I286 @SCM_LIB.SCM(SCH_1):PAGE17
    U5  W22 GND_W22 AST2600A3GP-AST2600A3-GP,SMLF,A   I286 @SCM_LIB.SCM(SCH_1):PAGE17
    U5  W25 GND_W25 AST2600A3GP-AST2600A3-GP,SMLF,A   I286 @SCM_LIB.SCM(SCH_1):PAGE17
    U5   Y6 GND_Y6 AST2600A3GP-AST2600A3-GP,SMLF,A   I286 @SCM_LIB.SCM(SCH_1):PAGE17
    U5  Y22 GND_Y22 AST2600A3GP-AST2600A3-GP,SMLF,A   I286 @SCM_LIB.SCM(SCH_1):PAGE17
    C1    2      B Q_CAP_C0603-4.7UF,25V,10%,X6S,A     I4 @SCM_LIB.SCM(SCH_1):PAGE20
    C2    2      B Q_CAP_C0402-1UF,25V,10%,X6S,CHA     I5 @SCM_LIB.SCM(SCH_1):PAGE20
    C3    2      B Q_CAP_C0402-1UF,25V,10%,X6S,CHA     I6 @SCM_LIB.SCM(SCH_1):PAGE20
    C4    2      B Q_CAP_C0402-1UF,25V,10%,X6S,CHA     I7 @SCM_LIB.SCM(SCH_1):PAGE20
    R2    2      B Q_RES_0402LF-0,5%,1/16W,CHIP,CA    I13 @SCM_LIB.SCM(SCH_1):PAGE20
    R3    2      B Q_RES_0402LF-0,5%,1/16W,CHIP,CA    I17 @SCM_LIB.SCM(SCH_1):PAGE20
    C6    2      B Q_CAP_0402-0.1UF,25V,10%,X7R,CA    I19 @SCM_LIB.SCM(SCH_1):PAGE20
    C8    2      B Q_CAP_0402-0.1UF,25V,10%,X7R,CA    I21 @SCM_LIB.SCM(SCH_1):PAGE20
    C5    2      B Q_CAP_C0402-1UF,25V,10%,X6S,CHA    I23 @SCM_LIB.SCM(SCH_1):PAGE20
    C7    2      B Q_CAP_0402-0.1UF,25V,10%,X7R,CA    I24 @SCM_LIB.SCM(SCH_1):PAGE20
    C9    2      B Q_CAP_0402-100PF,50V,5%,NPO,CHA    I25 @SCM_LIB.SCM(SCH_1):PAGE20
  R325    2      B Q_RES_0402LF-1K,1%,1/16W,CHIP,A    I27 @SCM_LIB.SCM(SCH_1):PAGE20
  C168    2      B Q_CAP_0402-0.1UF,25V,10%,X7R,CA    I32 @SCM_LIB.SCM(SCH_1):PAGE20
  C170    2      B Q_CAP_C0402-0.01UF,50V,10%,X7RA    I33 @SCM_LIB.SCM(SCH_1):PAGE20
   C10    2      B Q_CAP_0402-0.1UF,25V,10%,X7R,CA    I85 @SCM_LIB.SCM(SCH_1):PAGE20
   C12    2      B Q_CAP_0402-0.22UF,16V,10%,X7R,A   I106 @SCM_LIB.SCM(SCH_1):PAGE20
   C16    2      B Q_CAP_C0402-10UF,6.3V,20%,X6S,A   I113 @SCM_LIB.SCM(SCH_1):PAGE20
  R350    1      A Q_RES_0402LF-120,1%,1/16W,EMPTA   I114 @SCM_LIB.SCM(SCH_1):PAGE20
  R349    1      A Q_RES_0402LF-120,1%,1/16W,CHIPA   I116 @SCM_LIB.SCM(SCH_1):PAGE20
  R347    1      A Q_RES_0402LF-120,1%,1/16W,CHIPA   I117 @SCM_LIB.SCM(SCH_1):PAGE20
  R348    1      A Q_RES_0402LF-120,1%,1/16W,CHIPA   I118 @SCM_LIB.SCM(SCH_1):PAGE20
  R345    1      A Q_RES_0402LF-120,1%,1/16W,CHIPA   I119 @SCM_LIB.SCM(SCH_1):PAGE20
  R346    1      A Q_RES_0402LF-120,1%,1/16W,CHIPA   I120 @SCM_LIB.SCM(SCH_1):PAGE20
  R344    1      A Q_RES_0402LF-120,1%,1/16W,CHIPA   I121 @SCM_LIB.SCM(SCH_1):PAGE20
  R342    1      A Q_RES_0402LF-120,1%,1/16W,CHIPA   I122 @SCM_LIB.SCM(SCH_1):PAGE20
  R343    1      A Q_RES_0402LF-120,1%,1/16W,CHIPA   I123 @SCM_LIB.SCM(SCH_1):PAGE20
  R340    1      A Q_RES_0402LF-120,1%,1/16W,CHIPA   I124 @SCM_LIB.SCM(SCH_1):PAGE20
  R341    1      A Q_RES_0402LF-120,1%,1/16W,CHIPA   I125 @SCM_LIB.SCM(SCH_1):PAGE20
   C15    2      B Q_CAP_C0402-10UF,6.3V,20%,X6S,A   I134 @SCM_LIB.SCM(SCH_1):PAGE20
    R4    2      B Q_RES_0402LF-1K,1%,1/16W,CHIP,A   I141 @SCM_LIB.SCM(SCH_1):PAGE20
    R5    2      B Q_RES_0402LF-1K,1%,1/16W,CHIP,A   I142 @SCM_LIB.SCM(SCH_1):PAGE20
    R6    2      B Q_RES_0402LF-240,1%,1/16W,CHIPA   I143 @SCM_LIB.SCM(SCH_1):PAGE20
  R339    1      A Q_RES_0402LF-120,1%,1/16W,CHIPA   I159 @SCM_LIB.SCM(SCH_1):PAGE20
  R338    1      A Q_RES_0402LF-120,1%,1/16W,CHIPA   I160 @SCM_LIB.SCM(SCH_1):PAGE20
  R337    1      A Q_RES_0402LF-120,1%,1/16W,CHIPA   I161 @SCM_LIB.SCM(SCH_1):PAGE20
  R336    1      A Q_RES_0402LF-120,1%,1/16W,CHIPA   I162 @SCM_LIB.SCM(SCH_1):PAGE20
  R335    1      A Q_RES_0402LF-120,1%,1/16W,CHIPA   I163 @SCM_LIB.SCM(SCH_1):PAGE20
  R334    1      A Q_RES_0402LF-120,1%,1/16W,CHIPA   I164 @SCM_LIB.SCM(SCH_1):PAGE20
  R332    1      A Q_RES_0402LF-120,1%,1/16W,CHIPA   I171 @SCM_LIB.SCM(SCH_1):PAGE20
  R333    1      A Q_RES_0402LF-120,1%,1/16W,CHIPA   I172 @SCM_LIB.SCM(SCH_1):PAGE20
  R331    1      A Q_RES_0402LF-120,1%,1/16W,CHIPA   I173 @SCM_LIB.SCM(SCH_1):PAGE20
  R330    1      A Q_RES_0402LF-120,1%,1/16W,CHIPA   I174 @SCM_LIB.SCM(SCH_1):PAGE20
  R329    1      A Q_RES_0402LF-120,1%,1/16W,CHIPA   I175 @SCM_LIB.SCM(SCH_1):PAGE20
  R328    1      A Q_RES_0402LF-120,1%,1/16W,CHIPA   I176 @SCM_LIB.SCM(SCH_1):PAGE20
  R327    1      A Q_RES_0402LF-120,1%,1/16W,CHIPA   I177 @SCM_LIB.SCM(SCH_1):PAGE20
   C13    2      B Q_CAP_0402-0.1UF,25V,10%,X7R,CA   I186 @SCM_LIB.SCM(SCH_1):PAGE20
   C14    2      B Q_CAP_0402-0.1UF,25V,10%,X7R,CA   I187 @SCM_LIB.SCM(SCH_1):PAGE20
   C17    2      B Q_CAP_0402-0.1UF,25V,10%,X7R,CA   I190 @SCM_LIB.SCM(SCH_1):PAGE20
   C18    2      B Q_CAP_0402-0.1UF,25V,10%,X7R,CA   I192 @SCM_LIB.SCM(SCH_1):PAGE20
  R326    1      A Q_RES_0402LF-120,1%,1/16W,CHIPA   I193 @SCM_LIB.SCM(SCH_1):PAGE20
    U1   T7    NC1 K4A8G165WCBCTD-K4A8G165WC-BCTDA   I196 @SCM_LIB.SCM(SCH_1):PAGE20
    U1   B2   VSS0 K4A8G165WCBCTD-K4A8G165WC-BCTDA   I196 @SCM_LIB.SCM(SCH_1):PAGE20
    U1   E1   VSS1 K4A8G165WCBCTD-K4A8G165WC-BCTDA   I196 @SCM_LIB.SCM(SCH_1):PAGE20
    U1   G8   VSS3 K4A8G165WCBCTD-K4A8G165WC-BCTDA   I196 @SCM_LIB.SCM(SCH_1):PAGE20
    U1   K1   VSS4 K4A8G165WCBCTD-K4A8G165WC-BCTDA   I196 @SCM_LIB.SCM(SCH_1):PAGE20
    U1   K9   VSS5 K4A8G165WCBCTD-K4A8G165WC-BCTDA   I196 @SCM_LIB.SCM(SCH_1):PAGE20
    U1   N1   VSS7 K4A8G165WCBCTD-K4A8G165WC-BCTDA   I196 @SCM_LIB.SCM(SCH_1):PAGE20
    U1   T1   VSS8 K4A8G165WCBCTD-K4A8G165WC-BCTDA   I196 @SCM_LIB.SCM(SCH_1):PAGE20
    U1   A2  VSSQ0 K4A8G165WCBCTD-K4A8G165WC-BCTDA   I196 @SCM_LIB.SCM(SCH_1):PAGE20
    U1   A8  VSSQ1 K4A8G165WCBCTD-K4A8G165WC-BCTDA   I196 @SCM_LIB.SCM(SCH_1):PAGE20
    U1   C9  VSSQ2 K4A8G165WCBCTD-K4A8G165WC-BCTDA   I196 @SCM_LIB.SCM(SCH_1):PAGE20
    U1   D2  VSSQ3 K4A8G165WCBCTD-K4A8G165WC-BCTDA   I196 @SCM_LIB.SCM(SCH_1):PAGE20
    U1   D8  VSSQ4 K4A8G165WCBCTD-K4A8G165WC-BCTDA   I196 @SCM_LIB.SCM(SCH_1):PAGE20
    U1   E3  VSSQ5 K4A8G165WCBCTD-K4A8G165WC-BCTDA   I196 @SCM_LIB.SCM(SCH_1):PAGE20
    U1   E8  VSSQ6 K4A8G165WCBCTD-K4A8G165WC-BCTDA   I196 @SCM_LIB.SCM(SCH_1):PAGE20
    U1   F1  VSSQ7 K4A8G165WCBCTD-K4A8G165WC-BCTDA   I196 @SCM_LIB.SCM(SCH_1):PAGE20
    U1   H1  VSSQ8 K4A8G165WCBCTD-K4A8G165WC-BCTDA   I196 @SCM_LIB.SCM(SCH_1):PAGE20
    U1   H9  VSSQ9 K4A8G165WCBCTD-K4A8G165WC-BCTDA   I196 @SCM_LIB.SCM(SCH_1):PAGE20
  C225    2      B Q_CAP_0402-0.1UF,25V,10%,X7R,CA   I197 @SCM_LIB.SCM(SCH_1):PAGE20
  C222    2      B Q_CAP_0402-0.1UF,25V,10%,X7R,CA   I198 @SCM_LIB.SCM(SCH_1):PAGE20
  C221    2      B Q_CAP_0402-0.1UF,25V,10%,X7R,CA   I199 @SCM_LIB.SCM(SCH_1):PAGE20
  C228    2      B Q_CAP_0402-0.1UF,25V,10%,EMPTYA    I21 @SCM_LIB.SCM(SCH_1):PAGE21
  C235    2      B Q_CAP_0402-0.1UF,25V,10%,EMPTYA    I80 @SCM_LIB.SCM(SCH_1):PAGE21
  C234    2      B Q_CAP_C0603-22UF,10V,20%,EMPTYA    I81 @SCM_LIB.SCM(SCH_1):PAGE21
    Q1    E      2 MMBT39047F-MMBT3904-7-F,SMLF,IA     I2 @SCM_LIB.SCM(SCH_1):PAGE22
    Q3    E      2 MMBT39047F-MMBT3904-7-F,SMLF,IA     I4 @SCM_LIB.SCM(SCH_1):PAGE22
   U12    S SOURCE MOSFET_N_SMLF-BSS138K,BSS138K,A    I14 @SCM_LIB.SCM(SCH_1):PAGE22
  C147    2      B Q_CAP_0402-0.1UF,25V,10%,EMPTYA    I17 @SCM_LIB.SCM(SCH_1):PAGE22
  R314    2      B Q_RES_0402LF-100K,1%,1/16W,CHIA    I26 @SCM_LIB.SCM(SCH_1):PAGE22
  R313    2      B Q_RES_0402LF-470K,1%,1/16W,CHIA    I30 @SCM_LIB.SCM(SCH_1):PAGE22
  R614    2      B Q_RES_0402LF-100K,1%,1/16W,CHIA    I35 @SCM_LIB.SCM(SCH_1):PAGE22
   C34    2      B Q_CAP_0402-0.1UF,25V,10%,X7R,CA    I42 @SCM_LIB.SCM(SCH_1):PAGE22
  C223    2      B Q_CAP_C0402-4700P,25V,10%,EMPTA    I46 @SCM_LIB.SCM(SCH_1):PAGE22
  C253    2      B Q_CAP_0402-0.1UF,25V,10%,X7R,CA    I57 @SCM_LIB.SCM(SCH_1):PAGE22
  C264    2      B Q_CAP_0402-0.1UF,25V,10%,X7R,CA    I59 @SCM_LIB.SCM(SCH_1):PAGE22
    U6    2    GND 74LVC2G07DW7-74LVC2G07DW-7,SMLA    I87 @SCM_LIB.SCM(SCH_1):PAGE22
   U13    3    GND MC74VHC1G07DFT2G-MC74VHC1G07DFA    I89 @SCM_LIB.SCM(SCH_1):PAGE22
  C202    2      B Q_CAP_0402-0.1UF,25V,10%,X7R,CA    I11 @SCM_LIB.SCM(SCH_1):PAGE23
  C203    2      B Q_CAP_0402-0.1UF,25V,10%,X7R,CA    I12 @SCM_LIB.SCM(SCH_1):PAGE23
  C205    2      B Q_CAP_0402-15PF,50V,5%,C0G,CH0A    I25 @SCM_LIB.SCM(SCH_1):PAGE23
  C206    2      B Q_CAP_0402-15PF,50V,5%,C0G,CH0A    I26 @SCM_LIB.SCM(SCH_1):PAGE23
  C207    2      B Q_CAP_0402-15PF,50V,5%,C0G,CH0A    I29 @SCM_LIB.SCM(SCH_1):PAGE23
   U33    3    GND 74HC1G126GW-74HC1G126GW,SMLF,IA    I32 @SCM_LIB.SCM(SCH_1):PAGE23
   U26    3    GND 74HC1G126GW-74HC1G126GW,SMLF,IA    I33 @SCM_LIB.SCM(SCH_1):PAGE23
  C204    2      B Q_CAP_0603-1UF,16V,10%,EMPTY,TA    I45 @SCM_LIB.SCM(SCH_1):PAGE23
  C209    2      B Q_CAP_0402-18PF,50V,5%,C0G,CH0A    I54 @SCM_LIB.SCM(SCH_1):PAGE23
   R87    2      B Q_RES_0402LF-150,1%,1/16W,CHIPA    I57 @SCM_LIB.SCM(SCH_1):PAGE23
   R88    2      B Q_RES_0402LF-150,1%,1/16W,CHIPA    I59 @SCM_LIB.SCM(SCH_1):PAGE23
   R89    2      B Q_RES_0402LF-150,1%,1/16W,CHIPA    I65 @SCM_LIB.SCM(SCH_1):PAGE23
  C211    2      B Q_CAP_0402-10PF,50V,1%,NPO,TMPA    I67 @SCM_LIB.SCM(SCH_1):PAGE23
   D12    2      2 BZA462A-BZA462A,SMLF,EMPTY,BCZA    I74 @SCM_LIB.SCM(SCH_1):PAGE23
   D12    5      5 BZA462A-BZA462A,SMLF,EMPTY,BCZA    I74 @SCM_LIB.SCM(SCH_1):PAGE23
  C212    2      B Q_CAP_0402-10PF,50V,1%,NPO,TMPA    I77 @SCM_LIB.SCM(SCH_1):PAGE23
  C213    2      B Q_CAP_0402-100PF,50V,5%,EMPTY,A    I83 @SCM_LIB.SCM(SCH_1):PAGE23
  C214    2      B Q_CAP_0402-100PF,50V,5%,EMPTY,A    I84 @SCM_LIB.SCM(SCH_1):PAGE23
   U35    3   VSS1 DT1240E04LP7-DT1240E-04LP-7,SMA   I155 @SCM_LIB.SCM(SCH_1):PAGE23
   U35    8   VSS2 DT1240E04LP7-DT1240E-04LP-7,SMA   I155 @SCM_LIB.SCM(SCH_1):PAGE23
   U34    3   VSS1 DT1240E04LP7-DT1240E-04LP-7,SMA   I156 @SCM_LIB.SCM(SCH_1):PAGE23
   U34    8   VSS2 DT1240E04LP7-DT1240E-04LP-7,SMA   I156 @SCM_LIB.SCM(SCH_1):PAGE23
   U44    3    GND SN74LVC1G07DCKR-SN74LVC1G07DCKA    I61 @SCM_LIB.SCM(SCH_1):PAGE25
  C304    2      B Q_CAP_0402-0.1UF,25V,10%,X7R,CA    I65 @SCM_LIB.SCM(SCH_1):PAGE25
  R411    2      B Q_RES_0402LF-100,1%,1/16W,CHIPA     I6 @SCM_LIB.SCM(SCH_1):PAGE26
  R412    2      B Q_RES_0402LF-100,1%,1/16W,CHIPA     I8 @SCM_LIB.SCM(SCH_1):PAGE26
  R413    2      B Q_RES_0402LF-100,1%,1/16W,CHIPA    I12 @SCM_LIB.SCM(SCH_1):PAGE26
   U19    4    VSS M24128BWDW6TP-M24128-BWDW6TP,SA    I15 @SCM_LIB.SCM(SCH_1):PAGE26
  C192    2      B Q_CAP_0402-0.1UF,25V,10%,X7R,CA    I17 @SCM_LIB.SCM(SCH_1):PAGE26
   R15    2      B Q_RES_0402LF-1K,1%,1/16W,CHIP,A    I32 @SCM_LIB.SCM(SCH_1):PAGE26
  R419    2      B Q_RES_0402LF-1K,1%,1/16W,CHIP,A    I37 @SCM_LIB.SCM(SCH_1):PAGE26
  R417    2      B Q_RES_0402LF-1K,1%,1/16W,EMPTYA    I39 @SCM_LIB.SCM(SCH_1):PAGE26
  C191    2      B Q_CAP_0402-0.1UF,25V,10%,X7R,CA    I54 @SCM_LIB.SCM(SCH_1):PAGE26
  C267    2      B Q_CAP_0402-1UF,16V,10%,EMPTY,TA   I166 @SCM_LIB.SCM(SCH_1):PAGE27
  R770    1      A Q_RES_0402LF-4.7K,1%,1/16W,EMPA   I217 @SCM_LIB.SCM(SCH_1):PAGE27
  C172    2      B Q_CAP_0402-470PF,50V,10%,X7R,TA    I35 @SCM_LIB.SCM(SCH_1):PAGE28
  C171    2      B Q_CAP_C0805-22UF,10V,20%,X6S,CA    I38 @SCM_LIB.SCM(SCH_1):PAGE28
  R378    2      B Q_RES_0402LF-20K,1%,1/16W,CHIPA    I54 @SCM_LIB.SCM(SCH_1):PAGE28
  R377    2      B Q_RES_0402LF-10K,1%,1/16W,EMPTA    I63 @SCM_LIB.SCM(SCH_1):PAGE28
  C159    2      B Q_CAP_0402-0.1UF,25V,10%,X7R,CA    I98 @SCM_LIB.SCM(SCH_1):PAGE28
   U37    4    GND PCA9517ADP_SMLF-PCA9517ADP,IC,A    I99 @SCM_LIB.SCM(SCH_1):PAGE28
  C158    2      B Q_CAP_0402-0.1UF,25V,10%,X7R,CA   I101 @SCM_LIB.SCM(SCH_1):PAGE28
  R296    2      B Q_RES_0402LF-100K,1%,1/16W,EMPA   I105 @SCM_LIB.SCM(SCH_1):PAGE28
   U40   12    VSS PCA9555PW_SMLF-PCA9555PW,IC,TMA   I141 @SCM_LIB.SCM(SCH_1):PAGE28
  C300    2      B Q_CAP_0402-0.1UF,25V,10%,X7R,CA   I146 @SCM_LIB.SCM(SCH_1):PAGE28
    Q8    S      S 2N7002A7-2N7002A-7,SMLF,IC,BAMA   I163 @SCM_LIB.SCM(SCH_1):PAGE28
  R745    2      B Q_RES_0402LF-100,1%,1/16W,EMPTA   I172 @SCM_LIB.SCM(SCH_1):PAGE28
  R744    2      B Q_RES_0402LF-100,1%,1/16W,EMPTA   I173 @SCM_LIB.SCM(SCH_1):PAGE28
  R743    2      B Q_RES_0402LF-100,1%,1/16W,EMPTA   I175 @SCM_LIB.SCM(SCH_1):PAGE28
   U10    2    GND NCP380HSNAJAAT1G-NCP380HSNAJAAA   I179 @SCM_LIB.SCM(SCH_1):PAGE28
   U23    3    GND 74LVC1G07W57-74LVC1G07W5-7,SMLA   I180 @SCM_LIB.SCM(SCH_1):PAGE28
  C157    2      B Q_CAP_0402-0.1UF,25V,10%,X7R,CA   I181 @SCM_LIB.SCM(SCH_1):PAGE28
   U38    1    GND PRTR5V0U2X-PRTR5V0U2X,SMLF,IC,A    I99 @SCM_LIB.SCM(SCH_1):PAGE29
  C237    2      B Q_CAP_0402-0.1UF,25V,10%,X7R,CA   I146 @SCM_LIB.SCM(SCH_1):PAGE29
  C236    2      B Q_CAP_0402-0.1UF,25V,10%,X7R,CA   I148 @SCM_LIB.SCM(SCH_1):PAGE29
  C219    2      B Q_CAP_0402-0.1UF,25V,10%,X7R,CA   I150 @SCM_LIB.SCM(SCH_1):PAGE29
  R694    2      B Q_RES_0402LF-100,1%,1/16W,CHIPA   I155 @SCM_LIB.SCM(SCH_1):PAGE29
  C149    2      B Q_CAP_0402-0.1UF,25V,10%,X7R,CA   I161 @SCM_LIB.SCM(SCH_1):PAGE29
   U36    3    GND 74HC1G126GW-74HC1G126GW,SMLF,IA   I164 @SCM_LIB.SCM(SCH_1):PAGE29
  R219    2      B Q_RES_0402LF-100K,1%,1/16W,EMPA   I170 @SCM_LIB.SCM(SCH_1):PAGE29
  C148    2      B Q_CAP_0402-0.1UF,25V,10%,X7R,CA   I172 @SCM_LIB.SCM(SCH_1):PAGE29
   U29    3    GND 74HC1G126GW-74HC1G126GW,SMLF,IA   I174 @SCM_LIB.SCM(SCH_1):PAGE29
  R205    2      B Q_RES_0402LF-20K,1%,1/16W,CHIPA   I184 @SCM_LIB.SCM(SCH_1):PAGE29
  C179    2      B Q_CAP_0402-470PF,50V,10%,X7R,TA   I193 @SCM_LIB.SCM(SCH_1):PAGE29
  C178    2      B Q_CAP_0402-470PF,50V,10%,X7R,TA   I194 @SCM_LIB.SCM(SCH_1):PAGE29
    Q6    S      S 2N7002A7-2N7002A-7,SMLF,IC,BAMA   I202 @SCM_LIB.SCM(SCH_1):PAGE29
   U22   20   GND0 PI3PCIE3212ZBEX-PI3PCIE3212ZBEA   I206 @SCM_LIB.SCM(SCH_1):PAGE29
   U22    5   GND1 PI3PCIE3212ZBEX-PI3PCIE3212ZBEA   I206 @SCM_LIB.SCM(SCH_1):PAGE29
   U22   11   GND2 PI3PCIE3212ZBEX-PI3PCIE3212ZBEA   I206 @SCM_LIB.SCM(SCH_1):PAGE29
   U27    3   VSS1 DT1240E04LP7-DT1240E-04LP-7,SMA   I211 @SCM_LIB.SCM(SCH_1):PAGE29
   U27    8   VSS2 DT1240E04LP7-DT1240E-04LP-7,SMA   I211 @SCM_LIB.SCM(SCH_1):PAGE29
  C175    2      B Q_CAP_0402-0.1UF,25V,10%,X7R,CA   I151 @SCM_LIB.SCM(SCH_1):PAGE30
    J6    2      2 SCONN3_21291035BR2-SCONN3_212-A   I184 @SCM_LIB.SCM(SCH_1):PAGE30
  C268    2      B Q_CAP_0402-0.1UF,25V,10%,X7R,CA   I229 @SCM_LIB.SCM(SCH_1):PAGE30
   U24    2    GND 74LVC2G07DW7-74LVC2G07DW-7,SMLA   I246 @SCM_LIB.SCM(SCH_1):PAGE30
   U47    2    GND 74LVC2G07DW7-74LVC2G07DW-7,SMLA   I247 @SCM_LIB.SCM(SCH_1):PAGE30
    U2    4    GND FSA3357K8X-FSA3357K8X,SMLF,IC,A   I250 @SCM_LIB.SCM(SCH_1):PAGE30
    U3    4    GND FSA3357K8X-FSA3357K8X,SMLF,IC,A   I251 @SCM_LIB.SCM(SCH_1):PAGE30
   C20    2      B Q_CAP_0402-0.1UF,25V,10%,X7R,CA   I254 @SCM_LIB.SCM(SCH_1):PAGE30
   C19    2      B Q_CAP_0402-0.1UF,25V,10%,X7R,CA   I261 @SCM_LIB.SCM(SCH_1):PAGE30
  C501    2      B Q_CAP_0402-0.1UF,25V,10%,X7R,CA    I11 @SCM_LIB.SCM(SCH_1):PAGE31
  C500    2      B Q_CAP_0402-0.1UF,25V,10%,X7R,CA    I17 @SCM_LIB.SCM(SCH_1):PAGE31
   U50    2    GND NC7SB3157_SMLF-NC7SB3157P6X,NCA    I23 @SCM_LIB.SCM(SCH_1):PAGE31
   U51    2    GND NC7SB3157_SMLF-NC7SB3157P6X,NCA    I24 @SCM_LIB.SCM(SCH_1):PAGE31
  C217    2      B Q_CAP_0402-0.1UF,25V,10%,X7R,CA    I21 @SCM_LIB.SCM(SCH_1):PAGE32
  C215    2      B Q_CAP_C0402-10UF,6.3V,20%,X6S,A    I22 @SCM_LIB.SCM(SCH_1):PAGE32
  R229    1      A Q_RES_0402LF-4.7K,1%,1/16W,EMPA   I106 @SCM_LIB.SCM(SCH_1):PAGE32
  R228    1      A Q_RES_0402LF-10K,1%,1/16W,EMPTA   I107 @SCM_LIB.SCM(SCH_1):PAGE32
    J7    7      7 CONN8_210HP1080BR1-CONN8_210-HA   I132 @SCM_LIB.SCM(SCH_1):PAGE32
  C318    2      B Q_CAP_0402-0.1UF,25V,10%,X7R,CA   I122 @SCM_LIB.SCM(SCH_1):PAGE34
  OSC2    2    GND OSC4_7X25000018-25MHZ,SMLF,MISA   I127 @SCM_LIB.SCM(SCH_1):PAGE34
   U25   B2 GND_B2 LCMXO3LF2100C5BG256C-LCMXO3LF-A     I1 @SCM_LIB.SCM(SCH_1):PAGE40
   U25  B15 GND_B15 LCMXO3LF2100C5BG256C-LCMXO3LF-A     I1 @SCM_LIB.SCM(SCH_1):PAGE40
   U25   C3 GND_C3 LCMXO3LF2100C5BG256C-LCMXO3LF-A     I1 @SCM_LIB.SCM(SCH_1):PAGE40
   U25  C14 GND_C14 LCMXO3LF2100C5BG256C-LCMXO3LF-A     I1 @SCM_LIB.SCM(SCH_1):PAGE40
   U25   D4 GND_D4 LCMXO3LF2100C5BG256C-LCMXO3LF-A     I1 @SCM_LIB.SCM(SCH_1):PAGE40
   U25  D13 GND_D13 LCMXO3LF2100C5BG256C-LCMXO3LF-A     I1 @SCM_LIB.SCM(SCH_1):PAGE40
   U25   E5 GND_E5 LCMXO3LF2100C5BG256C-LCMXO3LF-A     I1 @SCM_LIB.SCM(SCH_1):PAGE40
   U25  E12 GND_E12 LCMXO3LF2100C5BG256C-LCMXO3LF-A     I1 @SCM_LIB.SCM(SCH_1):PAGE40
   U25   F6 GND_F6 LCMXO3LF2100C5BG256C-LCMXO3LF-A     I1 @SCM_LIB.SCM(SCH_1):PAGE40
   U25  F11 GND_F11 LCMXO3LF2100C5BG256C-LCMXO3LF-A     I1 @SCM_LIB.SCM(SCH_1):PAGE40
   U25   H8 GND_H8 LCMXO3LF2100C5BG256C-LCMXO3LF-A     I1 @SCM_LIB.SCM(SCH_1):PAGE40
   U25   H9 GND_H9 LCMXO3LF2100C5BG256C-LCMXO3LF-A     I1 @SCM_LIB.SCM(SCH_1):PAGE40
   U25   J8 GND_J8 LCMXO3LF2100C5BG256C-LCMXO3LF-A     I1 @SCM_LIB.SCM(SCH_1):PAGE40
   U25   J9 GND_J9 LCMXO3LF2100C5BG256C-LCMXO3LF-A     I1 @SCM_LIB.SCM(SCH_1):PAGE40
   U25   L6 GND_L6 LCMXO3LF2100C5BG256C-LCMXO3LF-A     I1 @SCM_LIB.SCM(SCH_1):PAGE40
   U25  L11 GND_L11 LCMXO3LF2100C5BG256C-LCMXO3LF-A     I1 @SCM_LIB.SCM(SCH_1):PAGE40
   U25   M5 GND_M5 LCMXO3LF2100C5BG256C-LCMXO3LF-A     I1 @SCM_LIB.SCM(SCH_1):PAGE40
   U25  M12 GND_M12 LCMXO3LF2100C5BG256C-LCMXO3LF-A     I1 @SCM_LIB.SCM(SCH_1):PAGE40
   U25   N4 GND_N4 LCMXO3LF2100C5BG256C-LCMXO3LF-A     I1 @SCM_LIB.SCM(SCH_1):PAGE40
   U25  N13 GND_N13 LCMXO3LF2100C5BG256C-LCMXO3LF-A     I1 @SCM_LIB.SCM(SCH_1):PAGE40
   U25   P3 GND_P3 LCMXO3LF2100C5BG256C-LCMXO3LF-A     I1 @SCM_LIB.SCM(SCH_1):PAGE40
   U25  P14 GND_P14 LCMXO3LF2100C5BG256C-LCMXO3LF-A     I1 @SCM_LIB.SCM(SCH_1):PAGE40
   U25   R2 GND_R2 LCMXO3LF2100C5BG256C-LCMXO3LF-A     I1 @SCM_LIB.SCM(SCH_1):PAGE40
   U25  R15 GND_R15 LCMXO3LF2100C5BG256C-LCMXO3LF-A     I1 @SCM_LIB.SCM(SCH_1):PAGE40
  C242    2      B Q_CAP_0402-0.1UF,25V,10%,X7R,CA     I1 @SCM_LIB.SCM(SCH_1):PAGE41
  C166    2      B Q_CAP_C0402-1UF,25V,10%,X6S,CHA     I8 @SCM_LIB.SCM(SCH_1):PAGE41
  C247    2      B Q_CAP_0402-0.1UF,25V,10%,X7R,CA    I77 @SCM_LIB.SCM(SCH_1):PAGE41
  C189    2      B Q_CAP_0402-0.1UF,25V,10%,X7R,CA    I78 @SCM_LIB.SCM(SCH_1):PAGE41
  C261    2      B Q_CAP_0402-0.1UF,25V,10%,X7R,CA    I79 @SCM_LIB.SCM(SCH_1):PAGE41
  C167    2      B Q_CAP_0402-0.1UF,25V,10%,X7R,CA    I80 @SCM_LIB.SCM(SCH_1):PAGE41
  C243    2      B Q_CAP_0402-0.1UF,25V,10%,X7R,CA    I81 @SCM_LIB.SCM(SCH_1):PAGE41
  C254    2      B Q_CAP_0402-0.1UF,25V,10%,X7R,CA    I82 @SCM_LIB.SCM(SCH_1):PAGE41
  C141    2      B Q_CAP_0402-0.1UF,25V,10%,X7R,CA    I83 @SCM_LIB.SCM(SCH_1):PAGE41
  C187    2      B Q_CAP_0402-0.1UF,25V,10%,X7R,CA    I84 @SCM_LIB.SCM(SCH_1):PAGE41
  C245    2      B Q_CAP_0402-0.1UF,25V,10%,X7R,CA    I85 @SCM_LIB.SCM(SCH_1):PAGE41
  C188    2      B Q_CAP_0402-0.1UF,25V,10%,X7R,CA    I86 @SCM_LIB.SCM(SCH_1):PAGE41
  C260    2      B Q_CAP_0402-0.1UF,25V,10%,X7R,CA    I87 @SCM_LIB.SCM(SCH_1):PAGE41
  C152    2      B Q_CAP_0402-0.1UF,25V,10%,X7R,CA    I88 @SCM_LIB.SCM(SCH_1):PAGE41
  C160    2      B Q_CAP_0402-0.1UF,25V,10%,X7R,CA    I89 @SCM_LIB.SCM(SCH_1):PAGE41
  C220    2      B Q_CAP_0402-0.1UF,25V,10%,X7R,CA    I90 @SCM_LIB.SCM(SCH_1):PAGE41
  C162    2      B Q_CAP_0402-0.1UF,25V,10%,X7R,CA    I91 @SCM_LIB.SCM(SCH_1):PAGE41
  C164    2      B Q_CAP_C0402-1UF,25V,10%,X6S,CHA    I92 @SCM_LIB.SCM(SCH_1):PAGE41
  C165    2      B Q_CAP_C0402-1UF,25V,10%,X6S,CHA    I93 @SCM_LIB.SCM(SCH_1):PAGE41
  C216    2      B Q_CAP_C0402-1UF,25V,10%,X6S,CHA    I94 @SCM_LIB.SCM(SCH_1):PAGE41
  C218    2      B Q_CAP_C0402-1UF,25V,10%,X6S,CHA    I95 @SCM_LIB.SCM(SCH_1):PAGE41
  C195    2      B Q_CAP_C0402-1UF,25V,10%,X6S,CHA    I96 @SCM_LIB.SCM(SCH_1):PAGE41
  C145    2      B Q_CAP_C0402-1UF,25V,10%,X6S,CHA    I99 @SCM_LIB.SCM(SCH_1):PAGE41
  C194    2      B Q_CAP_C0603-10UF,16V,20%,X6S,CA   I101 @SCM_LIB.SCM(SCH_1):PAGE41
  C176    2      B Q_CAP_C0402-1UF,25V,10%,X6S,CHA   I108 @SCM_LIB.SCM(SCH_1):PAGE41
  C193    2      B Q_CAP_0402-0.1UF,25V,10%,X7R,CA   I109 @SCM_LIB.SCM(SCH_1):PAGE41
  C250    2      B Q_CAP_0402-0.1UF,25V,10%,X7R,CA   I115 @SCM_LIB.SCM(SCH_1):PAGE41
  C190    2      B Q_CAP_0402-0.1UF,25V,10%,X7R,CA   I116 @SCM_LIB.SCM(SCH_1):PAGE41
  C263    2      B Q_CAP_0402-0.1UF,25V,10%,X7R,CA   I117 @SCM_LIB.SCM(SCH_1):PAGE41
  C269    2      B Q_CAP_0402-0.1UF,25V,10%,X7R,CA   I118 @SCM_LIB.SCM(SCH_1):PAGE41
  C266    2      B Q_CAP_0402-0.1UF,25V,10%,X7R,CA   I119 @SCM_LIB.SCM(SCH_1):PAGE41
  C163    2      B Q_CAP_C0603-10UF,16V,20%,X6S,CA   I122 @SCM_LIB.SCM(SCH_1):PAGE41
  C286    2      B Q_CAP_C0402-0.01UF,50V,10%,EMPA   I123 @SCM_LIB.SCM(SCH_1):PAGE41
  C285    2      B Q_CAP_C0402-0.01UF,50V,10%,EMPA   I124 @SCM_LIB.SCM(SCH_1):PAGE41
  C281    2      B Q_CAP_C0402-0.01UF,50V,10%,EMPA   I125 @SCM_LIB.SCM(SCH_1):PAGE41
  C283    2      B Q_CAP_C0402-0.01UF,50V,10%,EMPA   I126 @SCM_LIB.SCM(SCH_1):PAGE41
  R642    1      A Q_RES_0402LF-100K,1%,1/16W,CHIA    I58 @SCM_LIB.SCM(SCH_1):PAGE42
   U30    8    GND IDTQS3VH257PAG_SMLF-IDTQS3VH25A   I271 @SCM_LIB.SCM(SCH_1):PAGE44
  C255    2      B Q_CAP_0402-0.1UF,25V,10%,X7R,CA   I278 @SCM_LIB.SCM(SCH_1):PAGE44
  C146    2      B Q_CAP_0402-0.1UF,25V,10%,X7R,CA   I292 @SCM_LIB.SCM(SCH_1):PAGE44
   U21    8    GND IDTQS3VH257PAG_SMLF-IDTQS3VH25A   I296 @SCM_LIB.SCM(SCH_1):PAGE44
  R866    2      B Q_RES_0402LF-10K,1%,1/16W,CHIPA   I311 @SCM_LIB.SCM(SCH_1):PAGE44
  R467    2      B Q_RES_0402LF-2K,1%,1/16W,CHIP,A   I313 @SCM_LIB.SCM(SCH_1):PAGE44
  C244    2      B Q_CAP_C0402-1UF,25V,10%,X6S,CHA    I42 @SCM_LIB.SCM(SCH_1):PAGE45
  C246    2      B Q_CAP_C0402-0.01UF,50V,10%,X7RA    I45 @SCM_LIB.SCM(SCH_1):PAGE45
  R487    2      B Q_RES_0402LF-4.7K,1%,1/16W,EMPA    I51 @SCM_LIB.SCM(SCH_1):PAGE45
   J40   10    GND SCONN16_ACASPI006P06-SCONN16_AA    I53 @SCM_LIB.SCM(SCH_1):PAGE45
    J5   11     11 SCONN11_9192031111LF-SCONN11_9A    I56 @SCM_LIB.SCM(SCH_1):PAGE46
    J5   G1     G1 SCONN11_9192031111LF-SCONN11_9A    I56 @SCM_LIB.SCM(SCH_1):PAGE46
    J5   G2     G2 SCONN11_9192031111LF-SCONN11_9A    I56 @SCM_LIB.SCM(SCH_1):PAGE46
  C249    2      B Q_CAP_0402-0.1UF,25V,10%,X7R,CA    I67 @SCM_LIB.SCM(SCH_1):PAGE46
  C248    2      B Q_CAP_C0402-10UF,6.3V,20%,X6S,A    I69 @SCM_LIB.SCM(SCH_1):PAGE46
  C144    2      B Q_CAP_0402-0.1UF,25V,10%,X7R,CA   I102 @SCM_LIB.SCM(SCH_1):PAGE46
  C143    2      B Q_CAP_C0402-10UF,6.3V,20%,X6S,A   I108 @SCM_LIB.SCM(SCH_1):PAGE46
   J10   11     11 SCONN11_9192031111LF-SCONN11_9A   I113 @SCM_LIB.SCM(SCH_1):PAGE46
   J10   G1     G1 SCONN11_9192031111LF-SCONN11_9A   I113 @SCM_LIB.SCM(SCH_1):PAGE46
   J10   G2     G2 SCONN11_9192031111LF-SCONN11_9A   I113 @SCM_LIB.SCM(SCH_1):PAGE46
    D7    C      C Q_LED_SMLF-LED_RED,19-217/R6C-A     I5 @SCM_LIB.SCM(SCH_1):PAGE47
    D0    C      C Q_LED_SMLF-LED_GREEN,19-213/GVA     I7 @SCM_LIB.SCM(SCH_1):PAGE47
    D1    C      C Q_LED_SMLF-LED_GREEN,19-213/GVA     I9 @SCM_LIB.SCM(SCH_1):PAGE47
    D4    C      C Q_LED_SMLF-LED_RED,19-217/R6C-A    I10 @SCM_LIB.SCM(SCH_1):PAGE47
    D2    C      C Q_LED_SMLF-LED_GREEN,19-213/GVA    I11 @SCM_LIB.SCM(SCH_1):PAGE47
    D5    C      C Q_LED_SMLF-LED_RED,19-217/R6C-A    I12 @SCM_LIB.SCM(SCH_1):PAGE47
    D3    C      C Q_LED_SMLF-LED_GREEN,19-213/GVA    I13 @SCM_LIB.SCM(SCH_1):PAGE47
    D6    C      C Q_LED_SMLF-LED_RED,19-217/R6C-A    I14 @SCM_LIB.SCM(SCH_1):PAGE47
    U9    3    GND MC74VHC1G32DTT1G-MC74VHC1G32DTA     I5 @SCM_LIB.SCM(SCH_1):PAGE49
    Q9    1     S1 MOSFET_NCH_DUAL-PJT138K,SMLF,IA     I6 @SCM_LIB.SCM(SCH_1):PAGE49
  R306    2      B Q_RES_0402LF-10K,1%,1/16W,CHIPA     I8 @SCM_LIB.SCM(SCH_1):PAGE49
    U8    3    GND 74LVC1G126SE7-74LVC1G126SE-7,SA    I11 @SCM_LIB.SCM(SCH_1):PAGE49
  C274    2      B Q_CAP_0402-0.1UF,25V,10%,X7R,CA    I13 @SCM_LIB.SCM(SCH_1):PAGE49
  R839    2      B Q_RES_0402LF-8.2K,5%,1/16W,CHIA    I22 @SCM_LIB.SCM(SCH_1):PAGE49
   Q12    1     S1 MOSFET_DUAL_6P-2N7002KDW,SMLF,A    I24 @SCM_LIB.SCM(SCH_1):PAGE49
   Q12    4     S2 MOSFET_DUAL_6P-2N7002KDW,SMLF,A    I24 @SCM_LIB.SCM(SCH_1):PAGE49
  R619    2      B Q_RES_0402LF-8.2K,5%,1/16W,EMPA    I26 @SCM_LIB.SCM(SCH_1):PAGE49
  C324    2      B Q_CAP_0402-470PF,50V,10%,X7R,TA    I37 @SCM_LIB.SCM(SCH_1):PAGE49
  C326    2      B Q_CAP_0402-470PF,50V,10%,X7R,TA    I38 @SCM_LIB.SCM(SCH_1):PAGE49
  C321    2      B Q_CAP_0402-0.1UF,25V,10%,X7R,CA    I43 @SCM_LIB.SCM(SCH_1):PAGE49
  C197    2      B Q_CAP_0402-0.1UF,25V,10%,X7R,CA    I45 @SCM_LIB.SCM(SCH_1):PAGE49
  C276    2      B Q_CAP_0402-0.1UF,25V,10%,X7R,CA    I75 @SCM_LIB.SCM(SCH_1):PAGE49
  C200    2      B Q_CAP_0402-0.1UF,25V,10%,X7R,CA    I43 @SCM_LIB.SCM(SCH_1):PAGE50
  C198    2      B Q_CAP_C0402-1UF,25V,10%,X6S,CHA    I44 @SCM_LIB.SCM(SCH_1):PAGE50
   U32    3    GND 74LVC1G17GW-74LVC1G17GW,SMLF,IA    I49 @SCM_LIB.SCM(SCH_1):PAGE50
  C201    2      B Q_CAP_0402-0.1UF,25V,10%,X7R,CA    I51 @SCM_LIB.SCM(SCH_1):PAGE50
  C199    2      B Q_CAP_C0402-1UF,25V,10%,X6S,CHA    I55 @SCM_LIB.SCM(SCH_1):PAGE50
   U31    3    GND 74LVC1G07GW-74LVC1G07GW,SMLF,IA   I151 @SCM_LIB.SCM(SCH_1):PAGE50
  C196    2      B Q_CAP_C0402-1UF,25V,10%,X6S,CHA   I165 @SCM_LIB.SCM(SCH_1):PAGE50
 PC205    2      B Q_CAP_0402-0.1UF,25V,10%,X7R,CA     I1 @SCM_LIB.SCM(SCH_1):PAGE51
 PR522    2      B Q_RES_0402LF-100K,1%,1/16W,CHIA     I3 @SCM_LIB.SCM(SCH_1):PAGE51
 PR525    2      B Q_RES_0402LF-20.5K,1%,1/16W,CHA     I9 @SCM_LIB.SCM(SCH_1):PAGE51
 PC208    2      B Q_CAP_C0402-1UF,25V,10%,X6S,CHA    I13 @SCM_LIB.SCM(SCH_1):PAGE51
 PC271    2      B Q_CAP_0402-0.1UF,25V,10%,X7R,CA    I22 @SCM_LIB.SCM(SCH_1):PAGE51
 PR526    2      B Q_RES_0402LF-12.4K,1%,1/16W,CHA    I26 @SCM_LIB.SCM(SCH_1):PAGE51
 PC212    2      B Q_CAP_0402-0.1UF,25V,10%,X7R,CA    I31 @SCM_LIB.SCM(SCH_1):PAGE51
 PC213    2      B Q_CAP_C0805-22UF,10V,20%,X6S,CA    I32 @SCM_LIB.SCM(SCH_1):PAGE51
 PC214    2      B Q_CAP_C0805-22UF,10V,20%,X6S,CA    I33 @SCM_LIB.SCM(SCH_1):PAGE51
 PC215    2      B Q_CAP_C0805-22UF,10V,20%,X6S,CA    I36 @SCM_LIB.SCM(SCH_1):PAGE51
 PC217    2      B Q_CAP_C0805-22UF,10V,20%,X6S,CA    I37 @SCM_LIB.SCM(SCH_1):PAGE51
  PU38    2   AGND MPQ8633AGLEC807Z-MPQ8633AGLE-CA    I42 @SCM_LIB.SCM(SCH_1):PAGE51
  PU38    4   MODE MPQ8633AGLEC807Z-MPQ8633AGLE-CA    I42 @SCM_LIB.SCM(SCH_1):PAGE51
  PU38 11_18   PGND MPQ8633AGLEC807Z-MPQ8633AGLE-CA    I42 @SCM_LIB.SCM(SCH_1):PAGE51
  PU38    6   RGND MPQ8633AGLEC807Z-MPQ8633AGLE-CA    I42 @SCM_LIB.SCM(SCH_1):PAGE51
 PR245    2      B Q_RES_0402LF-100K,1%,1/16W,EMPA    I43 @SCM_LIB.SCM(SCH_1):PAGE51
 PC210    2      B Q_CAP_0402-0.1UF,25V,10%,X7R,CA    I45 @SCM_LIB.SCM(SCH_1):PAGE51
 PC206    2      B Q_CAP_C0805-22UF,16V,20%,X6S,CA    I47 @SCM_LIB.SCM(SCH_1):PAGE51
 PC207    2      B Q_CAP_C0805-22UF,16V,20%,X6S,CA    I48 @SCM_LIB.SCM(SCH_1):PAGE51
  C150    2      B Q_CAP_C0402-0.001UF,50V,10%,EMA    I49 @SCM_LIB.SCM(SCH_1):PAGE51
  C241    2      B Q_CAP_0402-0.1UF,25V,10%,X7R,CA    I52 @SCM_LIB.SCM(SCH_1):PAGE51
 PC221    2      B Q_CAP_C0402-1UF,25V,10%,X6S,CHA     I9 @SCM_LIB.SCM(SCH_1):PAGE52
 PC223    2      B Q_CAP_0402-0.1UF,25V,10%,X7R,CA    I11 @SCM_LIB.SCM(SCH_1):PAGE52
 PR530    1      A Q_RES_0402LF-12.4K,1%,1/16W,CHA    I17 @SCM_LIB.SCM(SCH_1):PAGE52
 PC225    2      B Q_CAP_0402-0.1UF,25V,10%,X7R,CA    I23 @SCM_LIB.SCM(SCH_1):PAGE52
 PC226    2      B Q_CAP_C0805-22UF,10V,20%,X6S,CA    I35 @SCM_LIB.SCM(SCH_1):PAGE52
 PC227    2      B Q_CAP_C0805-22UF,10V,20%,X6S,CA    I36 @SCM_LIB.SCM(SCH_1):PAGE52
 PC228    2      B Q_CAP_C0805-22UF,10V,20%,X6S,CA    I37 @SCM_LIB.SCM(SCH_1):PAGE52
 PC229    2      B Q_CAP_C0805-22UF,10V,20%,X6S,CA    I38 @SCM_LIB.SCM(SCH_1):PAGE52
  C240    2      B Q_CAP_0402-0.1UF,25V,10%,X7R,CA    I63 @SCM_LIB.SCM(SCH_1):PAGE52
  C251    2      B Q_CAP_0402-0.1UF,25V,10%,X7R,CA    I66 @SCM_LIB.SCM(SCH_1):PAGE52
  C252    2      B Q_CAP_C0402-1UF,25V,10%,EMPTY,A    I73 @SCM_LIB.SCM(SCH_1):PAGE52
   U14    2    GND AP22811AW57-AP22811AW5-7,SMLF,A    I79 @SCM_LIB.SCM(SCH_1):PAGE52
 PC219    2      B Q_CAP_C0805-22UF,16V,20%,X6S,CA    I80 @SCM_LIB.SCM(SCH_1):PAGE52
 PC218    2      B Q_CAP_C0805-22UF,16V,20%,X6S,CA    I81 @SCM_LIB.SCM(SCH_1):PAGE52
   PU1    7   AGND MPQ8626GDZ-MPQ8626GD-Z,SMLF,ICA    I82 @SCM_LIB.SCM(SCH_1):PAGE52
   PU1    1  PGND1 MPQ8626GDZ-MPQ8626GD-Z,SMLF,ICA    I82 @SCM_LIB.SCM(SCH_1):PAGE52
   PU1   14  PGND2 MPQ8626GDZ-MPQ8626GD-Z,SMLF,ICA    I82 @SCM_LIB.SCM(SCH_1):PAGE52
 PC273    2      B Q_CAP_0402-3300PF,50V,10%,X7R,A    I86 @SCM_LIB.SCM(SCH_1):PAGE52
 PR276    1      A Q_RES_0402LF-5.49K,1%,1/16W,CHA    I87 @SCM_LIB.SCM(SCH_1):PAGE52
 PR532    1      A Q_RES_0402LF-60.4K,1%,1/16W,CHA    I88 @SCM_LIB.SCM(SCH_1):PAGE52
  C151    2      B Q_CAP_C0402-0.001UF,50V,10%,EMA    I93 @SCM_LIB.SCM(SCH_1):PAGE52
  C262    2      B Q_CAP_0402-0.1UF,25V,10%,X7R,CA   I101 @SCM_LIB.SCM(SCH_1):PAGE52
  C265    2      B Q_CAP_C0805-22UF,16V,20%,X6S,CA   I102 @SCM_LIB.SCM(SCH_1):PAGE52
   U39   TH     EP RT9059GQW-RT9059GQW,SMLF,IC,ALA    I60 @SCM_LIB.SCM(SCH_1):PAGE53
  R830    2      B Q_RES_0402LF-12K,1%,1/16W,CHIPA    I61 @SCM_LIB.SCM(SCH_1):PAGE53
  C153    2      B Q_CAP_C0402-0.001UF,50V,10%,EMA    I64 @SCM_LIB.SCM(SCH_1):PAGE53
   U41   TH     EP RT9059GQW-RT9059GQW,SMLF,IC,ALA    I96 @SCM_LIB.SCM(SCH_1):PAGE54
  R832    2      B Q_RES_0402LF-12K,1%,1/16W,CHIPA    I97 @SCM_LIB.SCM(SCH_1):PAGE54
  C154    2      B Q_CAP_C0402-0.001UF,50V,10%,EMA   I100 @SCM_LIB.SCM(SCH_1):PAGE54
 PR496    2      B Q_RES_0402LF-150K,1%,1/16W,CHIA     I6 @SCM_LIB.SCM(SCH_1):PAGE55
 PC250    2      B Q_CAP_C0402-1UF,25V,10%,X6S,CHA     I7 @SCM_LIB.SCM(SCH_1):PAGE55
  PU41   11   AGND NB695GDZ-NB695GD-Z,SMLF,IC,AL0A    I15 @SCM_LIB.SCM(SCH_1):PAGE55
  PU41    4     C0 NB695GDZ-NB695GD-Z,SMLF,IC,AL0A    I15 @SCM_LIB.SCM(SCH_1):PAGE55
  PU41    3     C1 NB695GDZ-NB695GD-Z,SMLF,IC,AL0A    I15 @SCM_LIB.SCM(SCH_1):PAGE55
  PU41    2   PGND NB695GDZ-NB695GD-Z,SMLF,IC,AL0A    I15 @SCM_LIB.SCM(SCH_1):PAGE55
 PC253    2      B Q_CAP_0402-0.1UF,25V,10%,X7R,CA    I16 @SCM_LIB.SCM(SCH_1):PAGE55
 PC255    2      B Q_CAP_0402-0.1UF,25V,10%,X7R,CA    I23 @SCM_LIB.SCM(SCH_1):PAGE55
 PC256    2      B Q_CAP_0805-22UF,4V,20%,X6S,TMPA    I24 @SCM_LIB.SCM(SCH_1):PAGE55
 PC257    2      B Q_CAP_0805-22UF,4V,20%,X6S,TMPA    I25 @SCM_LIB.SCM(SCH_1):PAGE55
 PC258    2      B Q_CAP_0805-22UF,4V,20%,X6S,TMPA    I28 @SCM_LIB.SCM(SCH_1):PAGE55
 PC259    2      B Q_CAP_0805-22UF,4V,20%,X6S,TMPA    I29 @SCM_LIB.SCM(SCH_1):PAGE55
 PC252    2      B Q_CAP_C0805-10UF,25V,10%,X6S,CA    I42 @SCM_LIB.SCM(SCH_1):PAGE55
 PC251    2      B Q_CAP_C0805-10UF,25V,10%,X6S,CA    I43 @SCM_LIB.SCM(SCH_1):PAGE55
  C155    2      B Q_CAP_C0402-0.001UF,50V,10%,EMA    I52 @SCM_LIB.SCM(SCH_1):PAGE55
  C278    2      B Q_CAP_0402-0.1UF,25V,10%,X7R,CA    I54 @SCM_LIB.SCM(SCH_1):PAGE55
 PC260    2      B Q_CAP_C0402-1UF,25V,10%,X6S,CHA     I7 @SCM_LIB.SCM(SCH_1):PAGE56
  PU42   11   AGND NB695GDZ-NB695GD-Z,SMLF,IC,AL0A    I15 @SCM_LIB.SCM(SCH_1):PAGE56
  PU42    4     C0 NB695GDZ-NB695GD-Z,SMLF,IC,AL0A    I15 @SCM_LIB.SCM(SCH_1):PAGE56
  PU42    2   PGND NB695GDZ-NB695GD-Z,SMLF,IC,AL0A    I15 @SCM_LIB.SCM(SCH_1):PAGE56
 PC263    2      B Q_CAP_0402-0.1UF,25V,10%,X7R,CA    I16 @SCM_LIB.SCM(SCH_1):PAGE56
 PC266    2      B Q_CAP_0402-0.1UF,25V,10%,X7R,CA    I23 @SCM_LIB.SCM(SCH_1):PAGE56
 PC267    2      B Q_CAP_0805-22UF,4V,20%,X6S,TMPA    I24 @SCM_LIB.SCM(SCH_1):PAGE56
 PC268    2      B Q_CAP_0805-22UF,4V,20%,X6S,TMPA    I25 @SCM_LIB.SCM(SCH_1):PAGE56
 PC269    2      B Q_CAP_0805-22UF,4V,20%,X6S,TMPA    I28 @SCM_LIB.SCM(SCH_1):PAGE56
 PC270    2      B Q_CAP_0805-22UF,4V,20%,X6S,TMPA    I29 @SCM_LIB.SCM(SCH_1):PAGE56
 PC262    2      B Q_CAP_C0805-10UF,25V,10%,X6S,CA    I43 @SCM_LIB.SCM(SCH_1):PAGE56
 PC261    2      B Q_CAP_C0805-10UF,25V,10%,X6S,CA    I44 @SCM_LIB.SCM(SCH_1):PAGE56
  C156    2      B Q_CAP_C0402-0.001UF,50V,10%,EMA    I51 @SCM_LIB.SCM(SCH_1):PAGE56
  C280    2      B Q_CAP_0402-0.1UF,25V,10%,X7R,CA    I58 @SCM_LIB.SCM(SCH_1):PAGE56
    H5    1      1 HOLE_TH-EMPTY,HOLE1211    I35 @SCM_LIB.SCM(SCH_1):PAGE57
    H9    1      1 HOLE_TH-EMPTY,HOLE1211    I36 @SCM_LIB.SCM(SCH_1):PAGE57
    H3    1      1 HOLE_TH-EMPTY,HOLE620    I38 @SCM_LIB.SCM(SCH_1):PAGE57
    H4    1      1 HOLE_TH-EMPTY,HOLE620    I40 @SCM_LIB.SCM(SCH_1):PAGE57
   R53    2      B Q_RES_0402LF-1K,1%,1/16W,EMPTYA    I66 @SCM_LIB.SCM(SCH_1):PAGE26
    J8    2      2 SCONN13_502280130CV01-SCONN13_A   I165 @SCM_LIB.SCM(SCH_1):PAGE23
    J8    4      4 SCONN13_502280130CV01-SCONN13_A   I165 @SCM_LIB.SCM(SCH_1):PAGE23
    J8    6      6 SCONN13_502280130CV01-SCONN13_A   I165 @SCM_LIB.SCM(SCH_1):PAGE23
    J8    8      8 SCONN13_502280130CV01-SCONN13_A   I165 @SCM_LIB.SCM(SCH_1):PAGE23
    J8   10     10 SCONN13_502280130CV01-SCONN13_A   I165 @SCM_LIB.SCM(SCH_1):PAGE23
    J8   G1     G1 SCONN13_502280130CV01-SCONN13_A   I165 @SCM_LIB.SCM(SCH_1):PAGE23
    J8   G2     G2 SCONN13_502280130CV01-SCONN13_A   I165 @SCM_LIB.SCM(SCH_1):PAGE23
  R202    1      A Q_RES_0402LF-10K,1%,1/16W,EMPTA   I140 @SCM_LIB.SCM(SCH_1):PAGE32
  R285    2      B Q_RES_0402LF-4.7K,1%,1/16W,CHIA   I141 @SCM_LIB.SCM(SCH_1):PAGE32
   C22    2      B Q_CAP_0402-0.1UF,25V,10%,X7R,CA   I448 @SCM_LIB.SCM(SCH_1):PAGE12
  R312    2      B Q_RES_0402LF-47K,1%,1/16W,CHIPA   I456 @SCM_LIB.SCM(SCH_1):PAGE12
  C142    2      B Q_CAP_C0805-10UF,25V,10%,X6S,CA   I104 @SCM_LIB.SCM(SCH_1):PAGE54
  C294    2      B Q_CAP_0402-0.1UF,25V,10%,X7R,CA   I105 @SCM_LIB.SCM(SCH_1):PAGE54
  C293    2      B Q_CAP_C0805-10UF,25V,10%,X6S,CA   I106 @SCM_LIB.SCM(SCH_1):PAGE54
  C292    2      B Q_CAP_C0402-1UF,25V,10%,X6S,CHA   I107 @SCM_LIB.SCM(SCH_1):PAGE54
  C287    2      B Q_CAP_C0402-1UF,25V,10%,X6S,CHA    I67 @SCM_LIB.SCM(SCH_1):PAGE53
  C289    2      B Q_CAP_C0805-10UF,25V,10%,X6S,CA    I69 @SCM_LIB.SCM(SCH_1):PAGE53
  C291    2      B Q_CAP_0402-0.1UF,25V,10%,X7R,CA    I70 @SCM_LIB.SCM(SCH_1):PAGE53
  C288    2      B Q_CAP_C0805-10UF,25V,10%,X6S,CA    I71 @SCM_LIB.SCM(SCH_1):PAGE53
  R206    1      A Q_RES_0402LF-10K,1%,1/16W,CHIPA   I143 @SCM_LIB.SCM(SCH_1):PAGE32
  R441    2      B Q_RES_0402LF-49.9,1%,1/16W,EMPA   I353 @SCM_LIB.SCM(SCH_1):PAGE15
  R440    2      B Q_RES_0402LF-49.9,1%,1/16W,EMPA   I354 @SCM_LIB.SCM(SCH_1):PAGE15
   U17   10    GND MX25L51245GMI10G-MX25L51245GMIA    I54 @SCM_LIB.SCM(SCH_1):PAGE45
  C298    2      B Q_CAP_0402-0.1UF,25V,10%,X7R,CA   I112 @SCM_LIB.SCM(SCH_1):PAGE54
   U49    3    GND MC74VHC1G32DTT1G-MC74VHC1G32DTA   I116 @SCM_LIB.SCM(SCH_1):PAGE54
  C302    2      B Q_CAP_0402-0.1UF,25V,10%,X7R,CA    I64 @SCM_LIB.SCM(SCH_1):PAGE56
   U53    3    GND 74LVC1G08GW_SM-74LVC1G08GW,IC,A    I66 @SCM_LIB.SCM(SCH_1):PAGE56
  C301    2      B Q_CAP_0402-0.1UF,25V,10%,X7R,CA    I61 @SCM_LIB.SCM(SCH_1):PAGE55
   U52    3    GND 74LVC1G08GW_SM-74LVC1G08GW,IC,A    I63 @SCM_LIB.SCM(SCH_1):PAGE55
   U42    3    GND MC74VHC1G32DTT1G-MC74VHC1G32DTA   I104 @SCM_LIB.SCM(SCH_1):PAGE52
  C297    2      B Q_CAP_0402-0.1UF,25V,10%,X7R,CA   I107 @SCM_LIB.SCM(SCH_1):PAGE52
   U18    3    GND 74LVC1G08GW_SM-74LVC1G08GW,IC,A   I114 @SCM_LIB.SCM(SCH_1):PAGE52
  C296    2      B Q_CAP_0402-0.1UF,25V,10%,X7R,CA   I119 @SCM_LIB.SCM(SCH_1):PAGE52
  C305    2      B Q_CAP_C0402-1UF,25V,10%,X6S,CHA   I125 @SCM_LIB.SCM(SCH_1):PAGE52
  C310    2      B Q_CAP_C0402-1UF,25V,10%,X6S,CHA   I130 @SCM_LIB.SCM(SCH_1):PAGE54
   U54    4    GND 74LVC1G74DP-74LVC1G74DP,SMLF,IA   I138 @SCM_LIB.SCM(SCH_1):PAGE25
  R182    1      A Q_RES_0402LF-0,5%,1/16W,CHIP,CA   I142 @SCM_LIB.SCM(SCH_1):PAGE25
  R545    1      A Q_RES_0402LF-0,5%,1/16W,CHIP,CA   I143 @SCM_LIB.SCM(SCH_1):PAGE25
  C312    2      B Q_CAP_0402-0.1UF,25V,10%,X7R,CA   I146 @SCM_LIB.SCM(SCH_1):PAGE25
   U55    3    GND SN74LVC1G14DCKR_SMLF-IC,SN74LVA   I150 @SCM_LIB.SCM(SCH_1):PAGE25
  C313    2      B Q_CAP_0402-0.1UF,25V,10%,X7R,CA   I154 @SCM_LIB.SCM(SCH_1):PAGE25
   U43    2    GND TPS3808G18DBVR-TPS3808G01DBVR,A    I90 @SCM_LIB.SCM(SCH_1):PAGE22
    J4    1      1 SCONN67_NASA0S6730TS67-SCONN67A    I84 @SCM_LIB.SCM(SCH_1):PAGE21
    J4    7      7 SCONN67_NASA0S6730TS67-SCONN67A    I84 @SCM_LIB.SCM(SCH_1):PAGE21
    J4   18     18 SCONN67_NASA0S6730TS67-SCONN67A    I84 @SCM_LIB.SCM(SCH_1):PAGE21
    J4   23     23 SCONN67_NASA0S6730TS67-SCONN67A    I84 @SCM_LIB.SCM(SCH_1):PAGE21
    J4   24     24 SCONN67_NASA0S6730TS67-SCONN67A    I84 @SCM_LIB.SCM(SCH_1):PAGE21
    J4   29     29 SCONN67_NASA0S6730TS67-SCONN67A    I84 @SCM_LIB.SCM(SCH_1):PAGE21
    J4   30     30 SCONN67_NASA0S6730TS67-SCONN67A    I84 @SCM_LIB.SCM(SCH_1):PAGE21
    J4   33     33 SCONN67_NASA0S6730TS67-SCONN67A    I84 @SCM_LIB.SCM(SCH_1):PAGE21
    J4   36     36 SCONN67_NASA0S6730TS67-SCONN67A    I84 @SCM_LIB.SCM(SCH_1):PAGE21
    J4   39     39 SCONN67_NASA0S6730TS67-SCONN67A    I84 @SCM_LIB.SCM(SCH_1):PAGE21
    J4   45     45 SCONN67_NASA0S6730TS67-SCONN67A    I84 @SCM_LIB.SCM(SCH_1):PAGE21
    J4   51     51 SCONN67_NASA0S6730TS67-SCONN67A    I84 @SCM_LIB.SCM(SCH_1):PAGE21
    J4   57     57 SCONN67_NASA0S6730TS67-SCONN67A    I84 @SCM_LIB.SCM(SCH_1):PAGE21
    J4   63     63 SCONN67_NASA0S6730TS67-SCONN67A    I84 @SCM_LIB.SCM(SCH_1):PAGE21
    J4   69     69 SCONN67_NASA0S6730TS67-SCONN67A    I84 @SCM_LIB.SCM(SCH_1):PAGE21
    J4   75     75 SCONN67_NASA0S6730TS67-SCONN67A    I84 @SCM_LIB.SCM(SCH_1):PAGE21
    J4   G1     G1 SCONN67_NASA0S6730TS67-SCONN67A    I84 @SCM_LIB.SCM(SCH_1):PAGE21
    J4   G2     G2 SCONN67_NASA0S6730TS67-SCONN67A    I84 @SCM_LIB.SCM(SCH_1):PAGE21
   SW7    1      1 SW_PUSHBUTTON4P_12_G34_H2-SW4SA   I204 @SCM_LIB.SCM(SCH_1):PAGE50
   SW7    3      3 SW_PUSHBUTTON4P_12_G34_H2-SW4SA   I204 @SCM_LIB.SCM(SCH_1):PAGE50
   SW7    4      4 SW_PUSHBUTTON4P_12_G34_H2-SW4SA   I204 @SCM_LIB.SCM(SCH_1):PAGE50
  R665    2      B Q_RES_0402LF-1K,1%,1/16W,EMPTYB   I125 @SCM_LIB.SCM(SCH_1):PAGE21
  R664    2      B Q_RES_0402LF-1K,1%,1/16W,EMPTYB   I128 @SCM_LIB.SCM(SCH_1):PAGE21
    U7    2    GND NC7SB3157_SMLF-NC7SB3157P6X,NCA    I27 @SCM_LIB.SCM(SCH_1):PAGE31
   C11    2      B Q_CAP_0402-0.1UF,25V,10%,X7R,CA    I31 @SCM_LIB.SCM(SCH_1):PAGE31
   U20    2    GND NC7SB3157_SMLF-NC7SB3157P6X,NCA    I38 @SCM_LIB.SCM(SCH_1):PAGE31
  C231    2      B Q_CAP_0402-0.1UF,25V,10%,X7R,CA    I45 @SCM_LIB.SCM(SCH_1):PAGE31
  C256    2      B Q_CAP_C0402-1UF,25V,10%,X6S,CHA   I140 @SCM_LIB.SCM(SCH_1):PAGE34
  C257    2      B Q_CAP_0402-0.1UF,25V,10%,X7R,CA   I144 @SCM_LIB.SCM(SCH_1):PAGE34
 PR543    2      B Q_RES_0402LF-100K,1%,1/16W,CHIA    I71 @SCM_LIB.SCM(SCH_1):PAGE56
   C40    2      B Q_CAP_C0603-4.7UF,25V,10%,X6S,A   I368 @SCM_LIB.SCM(SCH_1):PAGE15
   C44    2      B Q_CAP_C0603-4.7UF,25V,10%,X6S,A   I369 @SCM_LIB.SCM(SCH_1):PAGE15
  C113    2      B Q_CAP_C0603-22UF,6.3V,20%,X6S,A   I189 @SCM_LIB.SCM(SCH_1):PAGE16
  C120    2      B Q_CAP_C0603-22UF,6.3V,20%,X6S,A   I190 @SCM_LIB.SCM(SCH_1):PAGE16
  C125    2      B Q_CAP_C0603-22UF,6.3V,20%,X6S,A   I191 @SCM_LIB.SCM(SCH_1):PAGE16
  C131    2      B Q_CAP_C0603-22UF,6.3V,20%,X6S,A   I192 @SCM_LIB.SCM(SCH_1):PAGE16
  C132    2      B Q_CAP_C0603-22UF,6.3V,20%,X6S,A   I193 @SCM_LIB.SCM(SCH_1):PAGE16
  C329    2      B Q_CAP_C0805-22UF,16V,20%,X6S,CA   I573 @SCM_LIB.SCM(SCH_1):PAGE10
  C330    2      B Q_CAP_C0805-22UF,16V,20%,X6S,CA   I574 @SCM_LIB.SCM(SCH_1):PAGE10
  C177    2      B Q_CAP_C1206-47UF,6.3V,20%,X6S,A   I219 @SCM_LIB.SCM(SCH_1):PAGE29
  C327    2      B Q_CAP_C1206-47UF,6.3V,20%,X6S,A   I220 @SCM_LIB.SCM(SCH_1):PAGE29
   J13    3      3 SCONN3_212H9103GBR1-SCONN3_212B    I61 @SCM_LIB.SCM(SCH_1):PAGE31
    H1    1      1 HOLE_TH-EMPTY,HOLE1248    I49 @SCM_LIB.SCM(SCH_1):PAGE57
    H6    1      1 HOLE_TH-EMPTY,TMP-C_HOLE8    I50 @SCM_LIB.SCM(SCH_1):PAGE57
    H7    1      1 HOLE_TH-EMPTY,TMP-C_HOLE8    I51 @SCM_LIB.SCM(SCH_1):PAGE57
  R620    2      B Q_RES_0402LF-100K,1%,1/16W,CHIA    I39 @SCM_LIB.SCM(SCH_1):PAGE48
  R507    2      B Q_RES_0402LF-100,1%,1/16W,EMPTA    I52 @SCM_LIB.SCM(SCH_1):PAGE48
  R506    2      B Q_RES_0402LF-100,1%,1/16W,EMPTA    I53 @SCM_LIB.SCM(SCH_1):PAGE48
  R431    2      B Q_RES_0402LF-100,1%,1/16W,EMPTA    I56 @SCM_LIB.SCM(SCH_1):PAGE48
  R164    2      B Q_RES_0402LF-100,1%,1/16W,EMPTA   I244 @SCM_LIB.SCM(SCH_1):PAGE27
   U56    2    GND AP2205W57-AP2205-W5-7,SMLF,IC,A    I56 @SCM_LIB.SCM(SCH_1):PAGE51
  R677    2      B Q_RES_0402LF-10K,1%,1/16W,CHIPA    I57 @SCM_LIB.SCM(SCH_1):PAGE51
  C226    2      B Q_CAP_C0402-1UF,25V,10%,X6S,CHA    I60 @SCM_LIB.SCM(SCH_1):PAGE51
   R94    2      B Q_RES_0402LF-4.7K,1%,1/16W,CHIA   I246 @SCM_LIB.SCM(SCH_1):PAGE27
  R387    1      A Q_RES_0402LF-100K,1%,1/16W,CHIA   I508 @SCM_LIB.SCM(SCH_1):PAGE12
   U15    3    GND 74LVC1G08GW_SM-74LVC1G08GW,IC,A   I393 @SCM_LIB.SCM(SCH_1):PAGE15
   C26    2      B Q_CAP_0402-0.1UF,25V,10%,X7R,CA   I398 @SCM_LIB.SCM(SCH_1):PAGE15
   C27    2      B Q_CAP_0402-0.1UF,25V,10%,X7R,CA   I212 @SCM_LIB.SCM(SCH_1):PAGE50
   Q13    1     S1 MOSFET_NCH_DUAL-PJT138K,SMLF,IA   I218 @SCM_LIB.SCM(SCH_1):PAGE50
   U16    3    GND 74LVC1G07GW-74LVC1G07GW,SMLF,EA   I227 @SCM_LIB.SCM(SCH_1):PAGE50
   C29    2      B Q_CAP_0402-0.1UF,25V,10%,EMPTYA   I232 @SCM_LIB.SCM(SCH_1):PAGE50
   C28    2      B Q_CAP_C0402-1UF,25V,10%,EMPTY,A   I236 @SCM_LIB.SCM(SCH_1):PAGE50
  R855    2      B Q_RES_0402LF-1K,1%,1/16W,CHIP,A   I223 @SCM_LIB.SCM(SCH_1):PAGE14
  R857    2      B Q_RES_0402LF-1K,1%,1/16W,EMPTYA   I224 @SCM_LIB.SCM(SCH_1):PAGE14
  R865    2      B Q_RES_0402LF-1K,1%,1/16W,EMPTYA   I225 @SCM_LIB.SCM(SCH_1):PAGE14
   U28    3    GND 74LVC1G66GV-74LVC1G66GV,SMLF,IA   I435 @SCM_LIB.SCM(SCH_1):PAGE13
  C180    2      B Q_CAP_0402-0.1UF,25V,10%,X7R,CA   I440 @SCM_LIB.SCM(SCH_1):PAGE13
   D10    C      C DIODE_BIDIRECTIONAL-UCLAMP0511A   I244 @SCM_LIB.SCM(SCH_1):PAGE50
  C181    2      B Q_CAP_0402-0.1UF,25V,10%,X7R,CA   I246 @SCM_LIB.SCM(SCH_1):PAGE50
   J14    8      8 CONN8_TSW10407FD-CONN8_TSW-104A    I71 @SCM_LIB.SCM(SCH_1):PAGE26
    J2   G1     G1 CONN9_GSB3111315HR-CONN9_GSB31A   I221 @SCM_LIB.SCM(SCH_1):PAGE29
    J2   G2     G2 CONN9_GSB3111315HR-CONN9_GSB31A   I221 @SCM_LIB.SCM(SCH_1):PAGE29
    J2    4    GND CONN9_GSB3111315HR-CONN9_GSB31A   I221 @SCM_LIB.SCM(SCH_1):PAGE29
   U57    3    GND 74LVC1G07GW-74LVC1G07GW,SMLF,IA   I278 @SCM_LIB.SCM(SCH_1):PAGE50
  C336    2      B Q_CAP_0402-0.1UF,25V,10%,X7R,CA   I281 @SCM_LIB.SCM(SCH_1):PAGE50
  C335    2      B Q_CAP_C0402-1UF,25V,10%,X6S,CHA   I285 @SCM_LIB.SCM(SCH_1):PAGE50
   SW6    1      1 SW_PUSHBUTTON4P_12_G34_H2-SW4SA   I292 @SCM_LIB.SCM(SCH_1):PAGE50
   SW6    3      3 SW_PUSHBUTTON4P_12_G34_H2-SW4SA   I292 @SCM_LIB.SCM(SCH_1):PAGE50
   SW6    4      4 SW_PUSHBUTTON4P_12_G34_H2-SW4SA   I292 @SCM_LIB.SCM(SCH_1):PAGE50
   SW8    1      1 SW_PUSHBUTTON4P_12_G34_H2-SW4SA   I293 @SCM_LIB.SCM(SCH_1):PAGE50
   SW8    3      3 SW_PUSHBUTTON4P_12_G34_H2-SW4SA   I293 @SCM_LIB.SCM(SCH_1):PAGE50
   SW8    4      4 SW_PUSHBUTTON4P_12_G34_H2-SW4SA   I293 @SCM_LIB.SCM(SCH_1):PAGE50
   D21    C      C Q_LED_THLF-LED_BLUE,HV-312470/A   I294 @SCM_LIB.SCM(SCH_1):PAGE50
   U58    3    GND MC74VHC1G32DTT1G-MC74VHC1G32DTA    I94 @SCM_LIB.SCM(SCH_1):PAGE22
  C337    2      B Q_CAP_0402-0.1UF,25V,10%,X7R,CA    I97 @SCM_LIB.SCM(SCH_1):PAGE22
  C227    2      B Q_CAP_C0402-2.2UF,10V,10%,X6S,A    I68 @SCM_LIB.SCM(SCH_1):PAGE51
  C208    2      B Q_CAP_0402-22PF,50V,5%,NPO,TMPA   I169 @SCM_LIB.SCM(SCH_1):PAGE23
  C210    2      B Q_CAP_0402-22PF,50V,5%,NPO,TMPA   I170 @SCM_LIB.SCM(SCH_1):PAGE23
  C173    2      B Q_CAP_0402-2200PF,50V,10%,X7R,A   I107 @SCM_LIB.SCM(SCH_1):PAGE22

GND_P1 @SCM_LIB.SCM(SCH_1):GND_P1
    X1    2     P1 TP_TDR_4P_FTS_TH-TP_TDR_4P_DIPA    I13 @SCM_LIB.SCM(SCH_1):PAGE60
    X1    3     P2 TP_TDR_4P_FTS_TH-TP_TDR_4P_DIPA    I13 @SCM_LIB.SCM(SCH_1):PAGE60
    X7    2     P1 TP_TDR_4P_FTS_TH-TP_TDR_4P_DIPA    I14 @SCM_LIB.SCM(SCH_1):PAGE60
    X7    3     P2 TP_TDR_4P_FTS_TH-TP_TDR_4P_DIPA    I14 @SCM_LIB.SCM(SCH_1):PAGE60
   X12    2     P1 TP_TDR_4P_FTS_TH-TP_TDR_4P_DIPA    I18 @SCM_LIB.SCM(SCH_1):PAGE60
   X12    3     P2 TP_TDR_4P_FTS_TH-TP_TDR_4P_DIPA    I18 @SCM_LIB.SCM(SCH_1):PAGE60
    X6    2     P1 TP_TDR_4P_FTS_TH-TP_TDR_4P_DIPA    I19 @SCM_LIB.SCM(SCH_1):PAGE60
    X6    3     P2 TP_TDR_4P_FTS_TH-TP_TDR_4P_DIPA    I19 @SCM_LIB.SCM(SCH_1):PAGE60
   X11    2     P1 TP_TDR_4P_FTS_TH-TP_TDR_4P_DIPA    I22 @SCM_LIB.SCM(SCH_1):PAGE60
   X11    3     P2 TP_TDR_4P_FTS_TH-TP_TDR_4P_DIPA    I22 @SCM_LIB.SCM(SCH_1):PAGE60
    X5    2     P1 TP_TDR_4P_FTS_TH-TP_TDR_4P_DIPA    I23 @SCM_LIB.SCM(SCH_1):PAGE60
    X5    3     P2 TP_TDR_4P_FTS_TH-TP_TDR_4P_DIPA    I23 @SCM_LIB.SCM(SCH_1):PAGE60
    X8    2     P1 TP_TDR_4P_FTS_TH-TP_TDR_4P_DIPA    I34 @SCM_LIB.SCM(SCH_1):PAGE60
    X8    3     P2 TP_TDR_4P_FTS_TH-TP_TDR_4P_DIPA    I34 @SCM_LIB.SCM(SCH_1):PAGE60
    X2    2     P1 TP_TDR_4P_FTS_TH-TP_TDR_4P_DIPA    I35 @SCM_LIB.SCM(SCH_1):PAGE60
    X2    3     P2 TP_TDR_4P_FTS_TH-TP_TDR_4P_DIPA    I35 @SCM_LIB.SCM(SCH_1):PAGE60
   X19    2     P1 TP_TDR_4P_FTS_TH-TP_TDR_4P_DIPA    I38 @SCM_LIB.SCM(SCH_1):PAGE60
   X19    3     P2 TP_TDR_4P_FTS_TH-TP_TDR_4P_DIPA    I38 @SCM_LIB.SCM(SCH_1):PAGE60
   X13    2     P1 TP_TDR_4P_FTS_TH-TP_TDR_4P_DIPA    I39 @SCM_LIB.SCM(SCH_1):PAGE60
   X13    3     P2 TP_TDR_4P_FTS_TH-TP_TDR_4P_DIPA    I39 @SCM_LIB.SCM(SCH_1):PAGE60
   X18    2     P1 TP_TDR_4P_FTS_TH-TP_TDR_4P_DIPA    I42 @SCM_LIB.SCM(SCH_1):PAGE60
   X18    3     P2 TP_TDR_4P_FTS_TH-TP_TDR_4P_DIPA    I42 @SCM_LIB.SCM(SCH_1):PAGE60
   X24    2     P1 TP_TDR_4P_FTS_TH-TP_TDR_4P_DIPA    I43 @SCM_LIB.SCM(SCH_1):PAGE60
   X24    3     P2 TP_TDR_4P_FTS_TH-TP_TDR_4P_DIPA    I43 @SCM_LIB.SCM(SCH_1):PAGE60
   X17    2     P1 TP_TDR_4P_FTS_TH-TP_TDR_4P_DIPA    I46 @SCM_LIB.SCM(SCH_1):PAGE60
   X17    3     P2 TP_TDR_4P_FTS_TH-TP_TDR_4P_DIPA    I46 @SCM_LIB.SCM(SCH_1):PAGE60
   X23    2     P1 TP_TDR_4P_FTS_TH-TP_TDR_4P_DIPA    I47 @SCM_LIB.SCM(SCH_1):PAGE60
   X23    3     P2 TP_TDR_4P_FTS_TH-TP_TDR_4P_DIPA    I47 @SCM_LIB.SCM(SCH_1):PAGE60
   X14    2     P1 TP_TDR_4P_FTS_TH-TP_TDR_4P_DIPA    I58 @SCM_LIB.SCM(SCH_1):PAGE60
   X14    3     P2 TP_TDR_4P_FTS_TH-TP_TDR_4P_DIPA    I58 @SCM_LIB.SCM(SCH_1):PAGE60
   X20    2     P1 TP_TDR_4P_FTS_TH-TP_TDR_4P_DIPA    I59 @SCM_LIB.SCM(SCH_1):PAGE60
   X20    3     P2 TP_TDR_4P_FTS_TH-TP_TDR_4P_DIPA    I59 @SCM_LIB.SCM(SCH_1):PAGE60
    J9    3    3_G PICOPROBE_BXA-DELTA-L 4.0,SMLFA    I55 @SCM_LIB.SCM(SCH_1):PAGE58
   J11    3    3_G PICOPROBE_BXA-DELTA-L 4.0,SMLFA    I57 @SCM_LIB.SCM(SCH_1):PAGE58
   J16    3    3_G PICOPROBE_BXA-DELTA-L 4.0,SMLFA    I58 @SCM_LIB.SCM(SCH_1):PAGE58
   J17    3    3_G PICOPROBE_BXA-DELTA-L 4.0,SMLFA    I59 @SCM_LIB.SCM(SCH_1):PAGE58
   J25    3    3_G PICOPROBE_BXA-DELTA-L 4.0,SMLFA    I60 @SCM_LIB.SCM(SCH_1):PAGE58
   J28    3    3_G PICOPROBE_BXA-DELTA-L 4.0,SMLFA    I61 @SCM_LIB.SCM(SCH_1):PAGE58
   J26    3    3_G PICOPROBE_BXA-DELTA-L 4.0,SMLFA    I62 @SCM_LIB.SCM(SCH_1):PAGE58
   J27    3    3_G PICOPROBE_BXA-DELTA-L 4.0,SMLFA    I63 @SCM_LIB.SCM(SCH_1):PAGE58
   J12    3    3_G PICOPROBE_BXA-DELTA-L 4.0,SMLFA    I64 @SCM_LIB.SCM(SCH_1):PAGE58
   J29    3    3_G PICOPROBE_BXA-DELTA-L 4.0,SMLFA    I65 @SCM_LIB.SCM(SCH_1):PAGE58
   J22    3    3_G PICOPROBE_BXA-DELTA-L 4.0,SMLFA    I66 @SCM_LIB.SCM(SCH_1):PAGE58
   J30    3    3_G PICOPROBE_BXA-DELTA-L 4.0,SMLFA    I67 @SCM_LIB.SCM(SCH_1):PAGE58
   J24    3    3_G PICOPROBE_BXA-DELTA-L 4.0,SMLFA    I68 @SCM_LIB.SCM(SCH_1):PAGE58
   J23    3    3_G PICOPROBE_BXA-DELTA-L 4.0,SMLFA    I69 @SCM_LIB.SCM(SCH_1):PAGE58
   J20    3    3_G PICOPROBE_BXA-DELTA-L 4.0,SMLFA    I70 @SCM_LIB.SCM(SCH_1):PAGE58
   J19    3    3_G PICOPROBE_BXA-DELTA-L 4.0,SMLFA    I71 @SCM_LIB.SCM(SCH_1):PAGE58

GPU_FPGA_RST_N @SCM_LIB.SCM(SCH_1):GPU_FPGA_RST_N
    U5  F23 RGMII3RXD0||RMII3RXD0||GPIOD0 AST2600A3GP-AST2600A3-GP,SMLF,A   I363 @SCM_LIB.SCM(SCH_1):PAGE13
   U25   P8  PB12A LCMXO3LF2100C5BG256C-LCMXO3LF-A     I1 @SCM_LIB.SCM(SCH_1):PAGE36

GPU_NVS_PWR_BRAKE_R_N @SCM_LIB.SCM(SCH_1):GPU_NVS_PWR_BRAKE_R_N
    U5  Y24 GPIOQ2||TACH2 AST2600A3GP-AST2600A3-GP,SMLF,A   I350 @SCM_LIB.SCM(SCH_1):PAGE15
   U25   R7   PB9A LCMXO3LF2100C5BG256C-LCMXO3LF-A     I1 @SCM_LIB.SCM(SCH_1):PAGE36

GPU_WP_HW_CTRL_R_N @SCM_LIB.SCM(SCH_1):GPU_WP_HW_CTRL_R_N
    U5 AB26 GPIOQ3||TACH3 AST2600A3GP-AST2600A3-GP,SMLF,A   I350 @SCM_LIB.SCM(SCH_1):PAGE15
   U25   P7   PB9B LCMXO3LF2100C5BG256C-LCMXO3LF-A     I1 @SCM_LIB.SCM(SCH_1):PAGE36

HDD_LED_BUF @SCM_LIB.SCM(SCH_1):HDD_LED_BUF
   Q12    3     D2 MOSFET_DUAL_6P-2N7002KDW,SMLF,A    I24 @SCM_LIB.SCM(SCH_1):PAGE49
  R813    1      A Q_RES_0402LF-33.2,1%,1/16W,CHIA    I35 @SCM_LIB.SCM(SCH_1):PAGE49

HDD_LED_BUF_R @SCM_LIB.SCM(SCH_1):HDD_LED_BUF_R
  R813    2      B Q_RES_0402LF-33.2,1%,1/16W,CHIA    I35 @SCM_LIB.SCM(SCH_1):PAGE49
  C324    1      A Q_CAP_0402-470PF,50V,10%,X7R,TA    I37 @SCM_LIB.SCM(SCH_1):PAGE49
  R815    2      B Q_RES_0402LF-10K,1%,1/16W,CHIPA    I40 @SCM_LIB.SCM(SCH_1):PAGE49
   D15    C      C Q_LED_THLF-LED_BLUE,HV-312470/A    I95 @SCM_LIB.SCM(SCH_1):PAGE49

HDD_LED_N @SCM_LIB.SCM(SCH_1):HDD_LED_N
   Q12    5     G2 MOSFET_DUAL_6P-2N7002KDW,SMLF,A    I24 @SCM_LIB.SCM(SCH_1):PAGE49
  R619    1      A Q_RES_0402LF-8.2K,5%,1/16W,EMPA    I26 @SCM_LIB.SCM(SCH_1):PAGE49
  R564    1      A Q_RES_0402LF-0,5%,1/16W,EMPTY,A   I562 @SCM_LIB.SCM(SCH_1):PAGE10
  R838    1      A Q_RES_0402LF-0,5%,1/16W,CHIP,CA   I568 @SCM_LIB.SCM(SCH_1):PAGE10

HDD_LED_P5V_AUX @SCM_LIB.SCM(SCH_1):HDD_LED_P5V_AUX
  C197    1      A Q_CAP_0402-0.1UF,25V,10%,X7R,CA    I45 @SCM_LIB.SCM(SCH_1):PAGE49
  R569    1      A Q_RES_0402LF-220,1%,1/16W,CHIPA    I60 @SCM_LIB.SCM(SCH_1):PAGE49
   D15    A      A Q_LED_THLF-LED_BLUE,HV-312470/A    I95 @SCM_LIB.SCM(SCH_1):PAGE49

HDD_LED_R_N @SCM_LIB.SCM(SCH_1):HDD_LED_R_N
   GF1  B68 PCIE_HPM_TXP_3 FCONN168_ME1016810202011_SCM-FA   I553 @SCM_LIB.SCM(SCH_1):PAGE10
  R564    2      B Q_RES_0402LF-0,5%,1/16W,EMPTY,A   I562 @SCM_LIB.SCM(SCH_1):PAGE10

H_CPU0_MEMTRIP_LVC1_N @SCM_LIB.SCM(SCH_1):H_CPU0_MEMTRIP_LVC1_N
    U5 AB23 GPIOP5||PWM13||THRUOUT2 AST2600A3GP-AST2600A3-GP,SMLF,A   I350 @SCM_LIB.SCM(SCH_1):PAGE15
   U25  D14   PR1A LCMXO3LF2100C5BG256C-LCMXO3LF-A     I1 @SCM_LIB.SCM(SCH_1):PAGE35

H_CPU0_PROCHOT_LVC1_N @SCM_LIB.SCM(SCH_1):H_CPU0_PROCHOT_LVC1_N
    U5  D14 GPIOM0||NCTS1 AST2600A3GP-AST2600A3-GP,SMLF,A   I363 @SCM_LIB.SCM(SCH_1):PAGE13
   R51    1      A Q_RES_0402LF-0,5%,1/16W,CHIP,CA    I80 @SCM_LIB.SCM(SCH_1):PAGE35

H_CPU0_PROCHOT_LVC1_R_N @SCM_LIB.SCM(SCH_1):H_CPU0_PROCHOT_LVC1_R_N
   U25  J14   PR7D LCMXO3LF2100C5BG256C-LCMXO3LF-A     I1 @SCM_LIB.SCM(SCH_1):PAGE35
   R51    2      B Q_RES_0402LF-0,5%,1/16W,CHIP,CA    I80 @SCM_LIB.SCM(SCH_1):PAGE35

H_CPU1_MEMTRIP_LVC1_N @SCM_LIB.SCM(SCH_1):H_CPU1_MEMTRIP_LVC1_N
    U5 AB24 GPIOP6||PWM14 AST2600A3GP-AST2600A3-GP,SMLF,A   I350 @SCM_LIB.SCM(SCH_1):PAGE15
   U25  D16   PR2A LCMXO3LF2100C5BG256C-LCMXO3LF-A     I1 @SCM_LIB.SCM(SCH_1):PAGE35

H_CPU1_PROCHOT_LVC1_N @SCM_LIB.SCM(SCH_1):H_CPU1_PROCHOT_LVC1_N
  R177    1      A Q_RES_0402LF-33.2,1%,1/16W,CHIA    I87 @SCM_LIB.SCM(SCH_1):PAGE13
    U5  P24 GPIOS5||RXD10 AST2600A3GP-AST2600A3-GP,SMLF,A   I363 @SCM_LIB.SCM(SCH_1):PAGE13

H_CPU1_PROCHOT_LVC1_R_N @SCM_LIB.SCM(SCH_1):H_CPU1_PROCHOT_LVC1_R_N
  R177    2      B Q_RES_0402LF-33.2,1%,1/16W,CHIA    I87 @SCM_LIB.SCM(SCH_1):PAGE13
   U25   E9  PT17D LCMXO3LF2100C5BG256C-LCMXO3LF-A     I1 @SCM_LIB.SCM(SCH_1):PAGE34

H_CPU_CATERR_LVC2_R2_N @SCM_LIB.SCM(SCH_1):H_CPU_CATERR_LVC2_R2_N
   GF1 OB13 SPI0_MOSI FCONN168_ME1016810202011_SCM-FA   I553 @SCM_LIB.SCM(SCH_1):PAGE10
    U5  F22 RGMII3TXD3||GPIOC5 AST2600A3GP-AST2600A3-GP,SMLF,A   I363 @SCM_LIB.SCM(SCH_1):PAGE13

I3C1_SCL_R @SCM_LIB.SCM(SCH_1):I3C1_SCL_R
    U5 AF23 I3C1SCL AST2600A3GP-AST2600A3-GP,SMLF,A   I149 @SCM_LIB.SCM(SCH_1):PAGE14
  R184    2      B Q_RES_0402LF-110,1%,1/16W,CHIPA   I232 @SCM_LIB.SCM(SCH_1):PAGE14

I3C1_SDA_R @SCM_LIB.SCM(SCH_1):I3C1_SDA_R
    U5 AE24 I3C1SDA AST2600A3GP-AST2600A3-GP,SMLF,A   I149 @SCM_LIB.SCM(SCH_1):PAGE14
  R185    2      B Q_RES_0402LF-33.2,1%,1/16W,CHIA   I236 @SCM_LIB.SCM(SCH_1):PAGE14

I3C1_SPD_SCL @SCM_LIB.SCM(SCH_1):I3C1_SPD_SCL
   GF1  OA5 I3C_0_SCL FCONN168_ME1016810202011_SCM-FA   I553 @SCM_LIB.SCM(SCH_1):PAGE10
  R194    2      B Q_RES_0402LF-1K,1%,1/16W,CHIP,A   I171 @SCM_LIB.SCM(SCH_1):PAGE14
  R184    1      A Q_RES_0402LF-110,1%,1/16W,CHIPA   I232 @SCM_LIB.SCM(SCH_1):PAGE14

I3C1_SPD_SDA @SCM_LIB.SCM(SCH_1):I3C1_SPD_SDA
   GF1  OA6 I3C_0_SDA FCONN168_ME1016810202011_SCM-FA   I553 @SCM_LIB.SCM(SCH_1):PAGE10
  R195    2      B Q_RES_0402LF-1K,1%,1/16W,CHIP,A   I172 @SCM_LIB.SCM(SCH_1):PAGE14
  R185    1      A Q_RES_0402LF-33.2,1%,1/16W,CHIA   I236 @SCM_LIB.SCM(SCH_1):PAGE14

I3C2_SCL_R @SCM_LIB.SCM(SCH_1):I3C2_SCL_R
    U5 AF22 I3C2SCL AST2600A3GP-AST2600A3-GP,SMLF,A   I149 @SCM_LIB.SCM(SCH_1):PAGE14
  R186    2      B Q_RES_0402LF-110,1%,1/16W,CHIPA   I233 @SCM_LIB.SCM(SCH_1):PAGE14

I3C2_SDA_R @SCM_LIB.SCM(SCH_1):I3C2_SDA_R
    U5 AE22 I3C2SDA AST2600A3GP-AST2600A3-GP,SMLF,A   I149 @SCM_LIB.SCM(SCH_1):PAGE14
  R187    2      B Q_RES_0402LF-33.2,1%,1/16W,CHIA   I237 @SCM_LIB.SCM(SCH_1):PAGE14

I3C2_SPD_SCL @SCM_LIB.SCM(SCH_1):I3C2_SPD_SCL
   GF1  OA7 I3C_1_SCL FCONN168_ME1016810202011_SCM-FA   I553 @SCM_LIB.SCM(SCH_1):PAGE10
  R190    2      B Q_RES_0402LF-1K,1%,1/16W,CHIP,A   I173 @SCM_LIB.SCM(SCH_1):PAGE14
  R186    1      A Q_RES_0402LF-110,1%,1/16W,CHIPA   I233 @SCM_LIB.SCM(SCH_1):PAGE14

I3C2_SPD_SDA @SCM_LIB.SCM(SCH_1):I3C2_SPD_SDA
   GF1  OA8 I3C_1_SDA FCONN168_ME1016810202011_SCM-FA   I553 @SCM_LIB.SCM(SCH_1):PAGE10
  R191    2      B Q_RES_0402LF-1K,1%,1/16W,CHIP,A   I174 @SCM_LIB.SCM(SCH_1):PAGE14
  R187    1      A Q_RES_0402LF-33.2,1%,1/16W,CHIA   I237 @SCM_LIB.SCM(SCH_1):PAGE14

I3C3_SCL_R @SCM_LIB.SCM(SCH_1):I3C3_SCL_R
    U5 AF25 I3C3SCL||FSI1CLK AST2600A3GP-AST2600A3-GP,SMLF,A   I149 @SCM_LIB.SCM(SCH_1):PAGE14
  R198    1      A Q_RES_0402LF-110,1%,1/16W,CHIPA   I234 @SCM_LIB.SCM(SCH_1):PAGE14

I3C3_SDA_R @SCM_LIB.SCM(SCH_1):I3C3_SDA_R
    U5 AE26 I3C3SDA||FSI1DATA AST2600A3GP-AST2600A3-GP,SMLF,A   I149 @SCM_LIB.SCM(SCH_1):PAGE14
  R199    1      A Q_RES_0402LF-33.2,1%,1/16W,CHIA   I238 @SCM_LIB.SCM(SCH_1):PAGE14

I3C3_SPD_SCL @SCM_LIB.SCM(SCH_1):I3C3_SPD_SCL
   GF1  OA9 I3C_2_SCL FCONN168_ME1016810202011_SCM-FA   I553 @SCM_LIB.SCM(SCH_1):PAGE10
  R188    2      B Q_RES_0402LF-1K,1%,1/16W,CHIP,A   I183 @SCM_LIB.SCM(SCH_1):PAGE14
  R198    2      B Q_RES_0402LF-110,1%,1/16W,CHIPA   I234 @SCM_LIB.SCM(SCH_1):PAGE14

I3C3_SPD_SDA @SCM_LIB.SCM(SCH_1):I3C3_SPD_SDA
   GF1 OA10 I3C_2_SDA FCONN168_ME1016810202011_SCM-FA   I553 @SCM_LIB.SCM(SCH_1):PAGE10
  R189    2      B Q_RES_0402LF-1K,1%,1/16W,CHIP,A   I188 @SCM_LIB.SCM(SCH_1):PAGE14
  R199    2      B Q_RES_0402LF-33.2,1%,1/16W,CHIA   I238 @SCM_LIB.SCM(SCH_1):PAGE14

I3C4_SCL_R @SCM_LIB.SCM(SCH_1):I3C4_SCL_R
    U5 AE25 I3C4SCL||FSI2CLK AST2600A3GP-AST2600A3-GP,SMLF,A   I149 @SCM_LIB.SCM(SCH_1):PAGE14
  R200    1      A Q_RES_0402LF-110,1%,1/16W,CHIPA   I235 @SCM_LIB.SCM(SCH_1):PAGE14

I3C4_SDA_R @SCM_LIB.SCM(SCH_1):I3C4_SDA_R
    U5 AF24 I3C4SDA||FSI2DATA AST2600A3GP-AST2600A3-GP,SMLF,A   I149 @SCM_LIB.SCM(SCH_1):PAGE14
  R201    1      A Q_RES_0402LF-33.2,1%,1/16W,CHIA   I239 @SCM_LIB.SCM(SCH_1):PAGE14

I3C4_SPD_SCL @SCM_LIB.SCM(SCH_1):I3C4_SPD_SCL
   GF1 OA11 I3C_3_SCL FCONN168_ME1016810202011_SCM-FA   I553 @SCM_LIB.SCM(SCH_1):PAGE10
  R196    2      B Q_RES_0402LF-1K,1%,1/16W,CHIP,A   I189 @SCM_LIB.SCM(SCH_1):PAGE14
  R200    2      B Q_RES_0402LF-110,1%,1/16W,CHIPA   I235 @SCM_LIB.SCM(SCH_1):PAGE14

I3C4_SPD_SDA @SCM_LIB.SCM(SCH_1):I3C4_SPD_SDA
   GF1 OA12 I3C_3_SDA FCONN168_ME1016810202011_SCM-FA   I553 @SCM_LIB.SCM(SCH_1):PAGE10
  R197    2      B Q_RES_0402LF-1K,1%,1/16W,CHIP,A   I190 @SCM_LIB.SCM(SCH_1):PAGE14
  R201    2      B Q_RES_0402LF-33.2,1%,1/16W,CHIA   I239 @SCM_LIB.SCM(SCH_1):PAGE14

IBMC_MIOZ @SCM_LIB.SCM(SCH_1):IBMC_MIOZ
  R127    2      B Q_RES_0402LF-240,1%,1/16W,CHIPA    I46 @SCM_LIB.SCM(SCH_1):PAGE12
    U5   P5   MIOZ AST2600A3GP-AST2600A3-GP,SMLF,A   I436 @SCM_LIB.SCM(SCH_1):PAGE12

ID_LED_BUF @SCM_LIB.SCM(SCH_1):ID_LED_BUF
    U9    4  OUT_Y MC74VHC1G32DTT1G-MC74VHC1G32DTA     I5 @SCM_LIB.SCM(SCH_1):PAGE49
    Q9    2     G1 MOSFET_NCH_DUAL-PJT138K,SMLF,IA     I6 @SCM_LIB.SCM(SCH_1):PAGE49

ID_LED_D_P3V3_AUX @SCM_LIB.SCM(SCH_1):ID_LED_D_P3V3_AUX
    Q9    6     D1 MOSFET_NCH_DUAL-PJT138K,SMLF,IA     I6 @SCM_LIB.SCM(SCH_1):PAGE49
   D13    C      C Q_LED_THLF-LED_YELLOW,LTL-R42FA    I97 @SCM_LIB.SCM(SCH_1):PAGE49

ID_LED_P3V3_AUX @SCM_LIB.SCM(SCH_1):ID_LED_P3V3_AUX
   R43    1      A Q_RES_0402LF-220,1%,1/16W,CHIPA    I79 @SCM_LIB.SCM(SCH_1):PAGE49
   D13    A      A Q_LED_THLF-LED_YELLOW,LTL-R42FA    I97 @SCM_LIB.SCM(SCH_1):PAGE49

ID_RST_BTN_BMC_N @SCM_LIB.SCM(SCH_1):ID_RST_BTN_BMC_N
   U32    4      Y 74LVC1G17GW-74LVC1G17GW,SMLF,IA    I49 @SCM_LIB.SCM(SCH_1):PAGE50
  R565    2      B Q_RES_0402LF-100,1%,1/16W,CHIPA   I406 @SCM_LIB.SCM(SCH_1):PAGE15

ID_RST_BTN_BMC_R_N @SCM_LIB.SCM(SCH_1):ID_RST_BTN_BMC_R_N
    U5 AA23 GPIOP2||PWM10||THRUIN1 AST2600A3GP-AST2600A3-GP,SMLF,A   I350 @SCM_LIB.SCM(SCH_1):PAGE15
  R565    1      A Q_RES_0402LF-100,1%,1/16W,CHIPA   I406 @SCM_LIB.SCM(SCH_1):PAGE15

IRQ_BMC_CPU_NMI @SCM_LIB.SCM(SCH_1):IRQ_BMC_CPU_NMI
  R166    2      B Q_RES_0402LF-33.2,1%,1/16W,CHIA    I50 @SCM_LIB.SCM(SCH_1):PAGE13
    U5  J24 GPIOB7||RXD4 AST2600A3GP-AST2600A3-GP,SMLF,A   I363 @SCM_LIB.SCM(SCH_1):PAGE13

IRQ_BMC_CPU_NMI_R @SCM_LIB.SCM(SCH_1):IRQ_BMC_CPU_NMI_R
  R166    1      A Q_RES_0402LF-33.2,1%,1/16W,CHIA    I50 @SCM_LIB.SCM(SCH_1):PAGE13
   U25   B3   PT9C LCMXO3LF2100C5BG256C-LCMXO3LF-A     I1 @SCM_LIB.SCM(SCH_1):PAGE34

IRQ_BMC_LPC_SERIRQ_ESPI_GF @SCM_LIB.SCM(SCH_1):IRQ_BMC_LPC_SERIRQ_ESPI_GF
   GF1   B3 ESPI_ALERT_N FCONN168_ME1016810202011_SCM-FA   I553 @SCM_LIB.SCM(SCH_1):PAGE10
  R116    2      B Q_RES_0402LF-4.7K,1%,1/16W,CHIA     I3 @SCM_LIB.SCM(SCH_1):PAGE12
  R119    1      A Q_RES_0402LF-33.2,1%,1/16W,CHIA    I34 @SCM_LIB.SCM(SCH_1):PAGE12

IRQ_BMC_PCH_NMI_N @SCM_LIB.SCM(SCH_1):IRQ_BMC_PCH_NMI_N
   R61    2      B Q_RES_0402LF-4.7K,1%,1/16W,CHIA   I204 @SCM_LIB.SCM(SCH_1):PAGE13
    U5  R23 GPIOS0||MDC1 AST2600A3GP-AST2600A3-GP,SMLF,A   I363 @SCM_LIB.SCM(SCH_1):PAGE13
  R571    1      A Q_RES_0402LF-0,5%,1/16W,CHIP,CA    I35 @SCM_LIB.SCM(SCH_1):PAGE34

IRQ_BMC_PCH_NMI_R_N @SCM_LIB.SCM(SCH_1):IRQ_BMC_PCH_NMI_R_N
   U25   A8 PT17B||PCLKC0_1 LCMXO3LF2100C5BG256C-LCMXO3LF-A     I1 @SCM_LIB.SCM(SCH_1):PAGE34
  R571    2      B Q_RES_0402LF-0,5%,1/16W,CHIP,CA    I35 @SCM_LIB.SCM(SCH_1):PAGE34

IRQ_BMC_TPM_SPI_R_N @SCM_LIB.SCM(SCH_1):IRQ_BMC_TPM_SPI_R_N
  R113    2      B Q_RES_0402LF-0,5%,1/16W,CHIP,CA   I105 @SCM_LIB.SCM(SCH_1):PAGE46
   J10    9      9 SCONN11_9192031111LF-SCONN11_9A   I113 @SCM_LIB.SCM(SCH_1):PAGE46

IRQ_CPU0_VRHOT_N @SCM_LIB.SCM(SCH_1):IRQ_CPU0_VRHOT_N
    U5  V26 GPIOR3||TACH11 AST2600A3GP-AST2600A3-GP,SMLF,A   I350 @SCM_LIB.SCM(SCH_1):PAGE15
   U25  F10  PT21C LCMXO3LF2100C5BG256C-LCMXO3LF-A     I1 @SCM_LIB.SCM(SCH_1):PAGE34

IRQ_CPU1_VRHOT_N @SCM_LIB.SCM(SCH_1):IRQ_CPU1_VRHOT_N
    U5  U25 GPIOR4||TACH12 AST2600A3GP-AST2600A3-GP,SMLF,A   I350 @SCM_LIB.SCM(SCH_1):PAGE15
   U25  D11  PT21D LCMXO3LF2100C5BG256C-LCMXO3LF-A     I1 @SCM_LIB.SCM(SCH_1):PAGE34

IRQ_ESPI_LPC_SERIRQ_ALERT0_N @SCM_LIB.SCM(SCH_1):IRQ_ESPI_LPC_SERIRQ_ALERT0_N
  R119    2      B Q_RES_0402LF-33.2,1%,1/16W,CHIA    I34 @SCM_LIB.SCM(SCH_1):PAGE12
    U5  AD7 GPIOW6||LSIRQ#||ESPIALT# AST2600A3GP-AST2600A3-GP,SMLF,A   I436 @SCM_LIB.SCM(SCH_1):PAGE12

IRQ_OC_DETECT_EN_N @SCM_LIB.SCM(SCH_1):IRQ_OC_DETECT_EN_N
    U5  V24 GPIOR2||TACH10 AST2600A3GP-AST2600A3-GP,SMLF,A   I350 @SCM_LIB.SCM(SCH_1):PAGE15
   U25  B13  PT22C LCMXO3LF2100C5BG256C-LCMXO3LF-A     I1 @SCM_LIB.SCM(SCH_1):PAGE34

IRQ_OC_DETECT_N @SCM_LIB.SCM(SCH_1):IRQ_OC_DETECT_N
    U5  V25 GPIOR0||TACH8 AST2600A3GP-AST2600A3-GP,SMLF,A   I350 @SCM_LIB.SCM(SCH_1):PAGE15
   U25  B11  PT22A LCMXO3LF2100C5BG256C-LCMXO3LF-A     I1 @SCM_LIB.SCM(SCH_1):PAGE34

IRQ_PCH_SCI_WHEA_N @SCM_LIB.SCM(SCH_1):IRQ_PCH_SCI_WHEA_N
  R826    2      B Q_RES_0402LF-33.2,1%,1/16W,CHIA   I351 @SCM_LIB.SCM(SCH_1):PAGE13
  R816    2      B Q_RES_0402LF-4.7K,1%,1/16W,CHIA   I353 @SCM_LIB.SCM(SCH_1):PAGE13
   U25   B9  PT19A LCMXO3LF2100C5BG256C-LCMXO3LF-A     I1 @SCM_LIB.SCM(SCH_1):PAGE34

IRQ_PCH_SCI_WHEA_R_N @SCM_LIB.SCM(SCH_1):IRQ_PCH_SCI_WHEA_R_N
  R826    1      A Q_RES_0402LF-33.2,1%,1/16W,CHIA   I351 @SCM_LIB.SCM(SCH_1):PAGE13
    U5  A15 GPIOI7||SIOSCI# AST2600A3GP-AST2600A3-GP,SMLF,A   I363 @SCM_LIB.SCM(SCH_1):PAGE13

IRQ_PCH_TPM_SPI_N @SCM_LIB.SCM(SCH_1):IRQ_PCH_TPM_SPI_N
    U5 AA25 GPIOQ0||TACH0 AST2600A3GP-AST2600A3-GP,SMLF,A   I350 @SCM_LIB.SCM(SCH_1):PAGE15
  R746    1      A Q_RES_0402LF-0,5%,1/16W,CHIP,CA    I10 @SCM_LIB.SCM(SCH_1):PAGE36
  R505    1      A Q_RES_0402LF-0,5%,1/16W,CHIP,CA    I74 @SCM_LIB.SCM(SCH_1):PAGE46
  R497    2      B Q_RES_0402LF-10K,1%,1/16W,CHIPA    I78 @SCM_LIB.SCM(SCH_1):PAGE46

IRQ_PCH_TPM_SPI_R2_N @SCM_LIB.SCM(SCH_1):IRQ_PCH_TPM_SPI_R2_N
   U25   T5   PB6A LCMXO3LF2100C5BG256C-LCMXO3LF-A     I1 @SCM_LIB.SCM(SCH_1):PAGE36
  R746    2      B Q_RES_0402LF-0,5%,1/16W,CHIP,CA    I10 @SCM_LIB.SCM(SCH_1):PAGE36

IRQ_PCH_TPM_SPI_R_N @SCM_LIB.SCM(SCH_1):IRQ_PCH_TPM_SPI_R_N
    J5    9      9 SCONN11_9192031111LF-SCONN11_9A    I56 @SCM_LIB.SCM(SCH_1):PAGE46
  R505    2      B Q_RES_0402LF-0,5%,1/16W,CHIP,CA    I74 @SCM_LIB.SCM(SCH_1):PAGE46

IRQ_SGPIO_BMC_N @SCM_LIB.SCM(SCH_1):IRQ_SGPIO_BMC_N
    U5  G24 RGMII3RXCTL||GPIOC7 AST2600A3GP-AST2600A3-GP,SMLF,A   I363 @SCM_LIB.SCM(SCH_1):PAGE13
  R689    2      B Q_RES_0402LF-33.2,1%,1/16W,EMPA   I398 @SCM_LIB.SCM(SCH_1):PAGE13

IRQ_SGPIO_N @SCM_LIB.SCM(SCH_1):IRQ_SGPIO_N
   GF1  B40 SGPIO_INTR_N FCONN168_ME1016810202011_SCM-FA   I553 @SCM_LIB.SCM(SCH_1):PAGE10
   R68    2      B Q_RES_0402LF-4.7K,1%,1/16W,CHIA   I179 @SCM_LIB.SCM(SCH_1):PAGE11
  R689    1      A Q_RES_0402LF-33.2,1%,1/16W,EMPA   I398 @SCM_LIB.SCM(SCH_1):PAGE13
  R690    2      B Q_RES_0402LF-33.2,1%,1/16W,CHIA   I149 @SCM_LIB.SCM(SCH_1):PAGE35

IRQ_SGPIO_R_N @SCM_LIB.SCM(SCH_1):IRQ_SGPIO_R_N
   U25  E14   PR2B LCMXO3LF2100C5BG256C-LCMXO3LF-A     I1 @SCM_LIB.SCM(SCH_1):PAGE35
  R690    1      A Q_RES_0402LF-33.2,1%,1/16W,CHIA   I149 @SCM_LIB.SCM(SCH_1):PAGE35

IRQ_SMI_ACTIVE_BMC_N @SCM_LIB.SCM(SCH_1):IRQ_SMI_ACTIVE_BMC_N
   R37    2      B Q_RES_0402LF-33.2,1%,1/16W,CHIA   I133 @SCM_LIB.SCM(SCH_1):PAGE13
    U5  AC9 GPIOX2||SPI2CS2# AST2600A3GP-AST2600A3-GP,SMLF,A   I363 @SCM_LIB.SCM(SCH_1):PAGE13

IRQ_SMI_ACTIVE_GF_N @SCM_LIB.SCM(SCH_1):IRQ_SMI_ACTIVE_GF_N
   GF1  A56  IRQ_N FCONN168_ME1016810202011_SCM-FA   I553 @SCM_LIB.SCM(SCH_1):PAGE10
   R37    1      A Q_RES_0402LF-33.2,1%,1/16W,CHIA   I133 @SCM_LIB.SCM(SCH_1):PAGE13

IRQ_SML0_ALERT_R_N @SCM_LIB.SCM(SCH_1):IRQ_SML0_ALERT_R_N
    U5  F24 RGMII4TXCK||RMII4RCLKO||NCTS3||GPIOD4 AST2600A3GP-AST2600A3-GP,SMLF,A   I363 @SCM_LIB.SCM(SCH_1):PAGE13
   U25   N7   PB9D LCMXO3LF2100C5BG256C-LCMXO3LF-A     I1 @SCM_LIB.SCM(SCH_1):PAGE36

IRQ_TPM_SPI_N @SCM_LIB.SCM(SCH_1):IRQ_TPM_SPI_N
    U5 AF15 GPIOV7||LPCSMI# AST2600A3GP-AST2600A3-GP,SMLF,A   I363 @SCM_LIB.SCM(SCH_1):PAGE13
   R59    2      B Q_RES_0402LF-10K,1%,1/16W,CHIPA    I98 @SCM_LIB.SCM(SCH_1):PAGE46
  R113    1      A Q_RES_0402LF-0,5%,1/16W,CHIP,CA   I105 @SCM_LIB.SCM(SCH_1):PAGE46

IRQ_UV_DETECT_N @SCM_LIB.SCM(SCH_1):IRQ_UV_DETECT_N
    U5  U24 GPIOR1||TACH9 AST2600A3GP-AST2600A3-GP,SMLF,A   I350 @SCM_LIB.SCM(SCH_1):PAGE15
   U25   B7  PT13A LCMXO3LF2100C5BG256C-LCMXO3LF-A     I1 @SCM_LIB.SCM(SCH_1):PAGE34

J7_P1 @SCM_LIB.SCM(SCH_1):J7_P1
  C217    1      A Q_CAP_0402-0.1UF,25V,10%,X7R,CA    I21 @SCM_LIB.SCM(SCH_1):PAGE32
  C215    1      A Q_CAP_C0402-10UF,6.3V,20%,X6S,A    I22 @SCM_LIB.SCM(SCH_1):PAGE32
    J7    1      1 CONN8_210HP1080BR1-CONN8_210-HA   I132 @SCM_LIB.SCM(SCH_1):PAGE32
   D20    2      C SCHOTTKY_12-1N5819HW,SMLF,IC,BA   I144 @SCM_LIB.SCM(SCH_1):PAGE32

JTAG_1_BMC_TCK_R @SCM_LIB.SCM(SCH_1):JTAG_1_BMC_TCK_R
    U5  E17 GPIOI2||MTCK2||TXD13 AST2600A3GP-AST2600A3-GP,SMLF,A   I350 @SCM_LIB.SCM(SCH_1):PAGE15
  R222    1      A Q_RES_0402LF-33.2,1%,1/16W,CHIA    I80 @SCM_LIB.SCM(SCH_1):PAGE32

JTAG_1_BMC_TDI_R @SCM_LIB.SCM(SCH_1):JTAG_1_BMC_TDI_R
    U5  A16 GPIOI1||MTDI2||RXD12 AST2600A3GP-AST2600A3-GP,SMLF,A   I350 @SCM_LIB.SCM(SCH_1):PAGE15
  R639    1      A Q_RES_0402LF-33.2,1%,1/16W,CHIA    I88 @SCM_LIB.SCM(SCH_1):PAGE32

JTAG_1_BMC_TDO @SCM_LIB.SCM(SCH_1):JTAG_1_BMC_TDO
    U5  C16 GPIOI4||MTDO2 AST2600A3GP-AST2600A3-GP,SMLF,A   I350 @SCM_LIB.SCM(SCH_1):PAGE15
  R398    1      A Q_RES_0402LF-0,5%,1/16W,CHIP,CA   I351 @SCM_LIB.SCM(SCH_1):PAGE15

JTAG_1_BMC_TDO_R @SCM_LIB.SCM(SCH_1):JTAG_1_BMC_TDO_R
  R398    2      B Q_RES_0402LF-0,5%,1/16W,CHIP,CA   I351 @SCM_LIB.SCM(SCH_1):PAGE15
  R224    1      A Q_RES_0402LF-33.2,1%,1/16W,CHIA    I87 @SCM_LIB.SCM(SCH_1):PAGE32

JTAG_1_BMC_TMS_R @SCM_LIB.SCM(SCH_1):JTAG_1_BMC_TMS_R
    U5  D16 GPIOI3||MTMS2||RXD13 AST2600A3GP-AST2600A3-GP,SMLF,A   I350 @SCM_LIB.SCM(SCH_1):PAGE15
  R223    1      A Q_RES_0402LF-33.2,1%,1/16W,CHIA    I78 @SCM_LIB.SCM(SCH_1):PAGE32

JTAG_1_BMC_TRST_R @SCM_LIB.SCM(SCH_1):JTAG_1_BMC_TRST_R
    U5  D17 GPIOI0||MNTRST2||TXD12 AST2600A3GP-AST2600A3-GP,SMLF,A   I350 @SCM_LIB.SCM(SCH_1):PAGE15
  R221    1      A Q_RES_0402LF-33.2,1%,1/16W,CHIA    I81 @SCM_LIB.SCM(SCH_1):PAGE32

JTAG_MB_TCK @SCM_LIB.SCM(SCH_1):JTAG_MB_TCK
   GF1  A34 JTAG_TCK FCONN168_ME1016810202011_SCM-FA   I553 @SCM_LIB.SCM(SCH_1):PAGE10
  R222    2      B Q_RES_0402LF-33.2,1%,1/16W,CHIA    I80 @SCM_LIB.SCM(SCH_1):PAGE32
  R228    2      B Q_RES_0402LF-10K,1%,1/16W,EMPTA   I107 @SCM_LIB.SCM(SCH_1):PAGE32

JTAG_MB_TDI @SCM_LIB.SCM(SCH_1):JTAG_MB_TDI
   GF1  A36 JTAG_TDI FCONN168_ME1016810202011_SCM-FA   I553 @SCM_LIB.SCM(SCH_1):PAGE10
  R639    2      B Q_RES_0402LF-33.2,1%,1/16W,CHIA    I88 @SCM_LIB.SCM(SCH_1):PAGE32
  R226    2      B Q_RES_0402LF-10K,1%,1/16W,CHIPA   I103 @SCM_LIB.SCM(SCH_1):PAGE32

JTAG_MB_TDO @SCM_LIB.SCM(SCH_1):JTAG_MB_TDO
   GF1  A37 JTAG_TDO FCONN168_ME1016810202011_SCM-FA   I553 @SCM_LIB.SCM(SCH_1):PAGE10
  R224    2      B Q_RES_0402LF-33.2,1%,1/16W,CHIA    I87 @SCM_LIB.SCM(SCH_1):PAGE32
  R230    2      B Q_RES_0402LF-10K,1%,1/16W,CHIPA   I105 @SCM_LIB.SCM(SCH_1):PAGE32

JTAG_MB_TMS @SCM_LIB.SCM(SCH_1):JTAG_MB_TMS
   GF1  A35 JTAG_TMS FCONN168_ME1016810202011_SCM-FA   I553 @SCM_LIB.SCM(SCH_1):PAGE10
  R223    2      B Q_RES_0402LF-33.2,1%,1/16W,CHIA    I78 @SCM_LIB.SCM(SCH_1):PAGE32
  R227    2      B Q_RES_0402LF-10K,1%,1/16W,CHIPA   I104 @SCM_LIB.SCM(SCH_1):PAGE32

JTAG_MB_TRST_N @SCM_LIB.SCM(SCH_1):JTAG_MB_TRST_N
  R221    2      B Q_RES_0402LF-33.2,1%,1/16W,CHIA    I81 @SCM_LIB.SCM(SCH_1):PAGE32
  R229    2      B Q_RES_0402LF-4.7K,1%,1/16W,EMPA   I106 @SCM_LIB.SCM(SCH_1):PAGE32

JTAG_SCM_CONN_TCK @SCM_LIB.SCM(SCH_1):JTAG_SCM_CONN_TCK
  R514    2      B Q_RES_0402LF-33.2,1%,1/16W,CHIA    I94 @SCM_LIB.SCM(SCH_1):PAGE32
    J7    8      8 CONN8_210HP1080BR1-CONN8_210-HA   I132 @SCM_LIB.SCM(SCH_1):PAGE32

JTAG_SCM_CONN_TDI @SCM_LIB.SCM(SCH_1):JTAG_SCM_CONN_TDI
  R516    2      B Q_RES_0402LF-33.2,1%,1/16W,CHIA    I95 @SCM_LIB.SCM(SCH_1):PAGE32
    J7    3      3 CONN8_210HP1080BR1-CONN8_210-HA   I132 @SCM_LIB.SCM(SCH_1):PAGE32

JTAG_SCM_CONN_TDO @SCM_LIB.SCM(SCH_1):JTAG_SCM_CONN_TDO
  R517    2      B Q_RES_0402LF-33.2,1%,1/16W,CHIA    I97 @SCM_LIB.SCM(SCH_1):PAGE32
    J7    2      2 CONN8_210HP1080BR1-CONN8_210-HA   I132 @SCM_LIB.SCM(SCH_1):PAGE32

JTAG_SCM_CONN_TMS @SCM_LIB.SCM(SCH_1):JTAG_SCM_CONN_TMS
  R515    2      B Q_RES_0402LF-33.2,1%,1/16W,CHIA    I96 @SCM_LIB.SCM(SCH_1):PAGE32
    J7    6      6 CONN8_210HP1080BR1-CONN8_210-HA   I132 @SCM_LIB.SCM(SCH_1):PAGE32

JTAG_SCM_NTRST @SCM_LIB.SCM(SCH_1):JTAG_SCM_NTRST
    U5  F11 NTRST||MNTRST1 AST2600A3GP-AST2600A3-GP,SMLF,A   I350 @SCM_LIB.SCM(SCH_1):PAGE15
  R206    2      B Q_RES_0402LF-10K,1%,1/16W,CHIPA   I143 @SCM_LIB.SCM(SCH_1):PAGE32

JTAG_SCM_PLD_JTAGEN @SCM_LIB.SCM(SCH_1):JTAG_SCM_PLD_JTAGEN
  R518    2      B Q_RES_0402LF-33.2,1%,1/16W,CHIA    I23 @SCM_LIB.SCM(SCH_1):PAGE32
  R509    2      B Q_RES_0402LF-33.2,1%,1/16W,CHIA    I50 @SCM_LIB.SCM(SCH_1):PAGE48
  R397    2      B Q_RES_0402LF-0,5%,1/16W,CHIP,CA   I167 @SCM_LIB.SCM(SCH_1):PAGE34

JTAG_SCM_PLD_R1_JTAGEN @SCM_LIB.SCM(SCH_1):JTAG_SCM_PLD_R1_JTAGEN
  R518    1      A Q_RES_0402LF-33.2,1%,1/16W,CHIA    I23 @SCM_LIB.SCM(SCH_1):PAGE32
    J7    4      4 CONN8_210HP1080BR1-CONN8_210-HA   I132 @SCM_LIB.SCM(SCH_1):PAGE32

JTAG_SCM_PLD_R_JTAGEN @SCM_LIB.SCM(SCH_1):JTAG_SCM_PLD_R_JTAGEN
   U25  C10 PT20C||JTAGENB LCMXO3LF2100C5BG256C-LCMXO3LF-A     I1 @SCM_LIB.SCM(SCH_1):PAGE34
  R397    1      A Q_RES_0402LF-0,5%,1/16W,CHIP,CA   I167 @SCM_LIB.SCM(SCH_1):PAGE34

JTAG_SCM_PLD_TCK @SCM_LIB.SCM(SCH_1):JTAG_SCM_PLD_TCK
  R514    1      A Q_RES_0402LF-33.2,1%,1/16W,CHIA    I94 @SCM_LIB.SCM(SCH_1):PAGE32
  R510    2      B Q_RES_0402LF-33.2,1%,1/16W,CHIA   I126 @SCM_LIB.SCM(SCH_1):PAGE32
   U25   A7 PT16C||TCK LCMXO3LF2100C5BG256C-LCMXO3LF-A     I1 @SCM_LIB.SCM(SCH_1):PAGE34
  R285    1      A Q_RES_0402LF-4.7K,1%,1/16W,CHIA   I141 @SCM_LIB.SCM(SCH_1):PAGE32

JTAG_SCM_PLD_TDI @SCM_LIB.SCM(SCH_1):JTAG_SCM_PLD_TDI
  R516    1      A Q_RES_0402LF-33.2,1%,1/16W,CHIA    I95 @SCM_LIB.SCM(SCH_1):PAGE32
  R512    2      B Q_RES_0402LF-33.2,1%,1/16W,CHIA   I129 @SCM_LIB.SCM(SCH_1):PAGE32
   U25   A6 PT12D||TDI LCMXO3LF2100C5BG256C-LCMXO3LF-A     I1 @SCM_LIB.SCM(SCH_1):PAGE34

JTAG_SCM_PLD_TDO @SCM_LIB.SCM(SCH_1):JTAG_SCM_PLD_TDO
  R517    1      A Q_RES_0402LF-33.2,1%,1/16W,CHIA    I97 @SCM_LIB.SCM(SCH_1):PAGE32
  R513    2      B Q_RES_0402LF-33.2,1%,1/16W,CHIA   I128 @SCM_LIB.SCM(SCH_1):PAGE32
   U25   C6 PT12C||TDO LCMXO3LF2100C5BG256C-LCMXO3LF-A     I1 @SCM_LIB.SCM(SCH_1):PAGE34

JTAG_SCM_PLD_TMS @SCM_LIB.SCM(SCH_1):JTAG_SCM_PLD_TMS
  R515    1      A Q_RES_0402LF-33.2,1%,1/16W,CHIA    I96 @SCM_LIB.SCM(SCH_1):PAGE32
  R511    2      B Q_RES_0402LF-33.2,1%,1/16W,CHIA   I127 @SCM_LIB.SCM(SCH_1):PAGE32
   U25   B8 PT16D||TMS LCMXO3LF2100C5BG256C-LCMXO3LF-A     I1 @SCM_LIB.SCM(SCH_1):PAGE34

JTAG_SCM_TCK @SCM_LIB.SCM(SCH_1):JTAG_SCM_TCK
    U5   B9 TCK||MTCK1 AST2600A3GP-AST2600A3-GP,SMLF,A   I350 @SCM_LIB.SCM(SCH_1):PAGE15
  R510    1      A Q_RES_0402LF-33.2,1%,1/16W,CHIA   I126 @SCM_LIB.SCM(SCH_1):PAGE32
  R834    2      B Q_RES_0402LF-10K,1%,1/16W,EMPTA   I131 @SCM_LIB.SCM(SCH_1):PAGE32
  R202    2      B Q_RES_0402LF-10K,1%,1/16W,EMPTA   I140 @SCM_LIB.SCM(SCH_1):PAGE32

JTAG_SCM_TDI @SCM_LIB.SCM(SCH_1):JTAG_SCM_TDI
    U5   D9 TDI||MTDI1 AST2600A3GP-AST2600A3-GP,SMLF,A   I350 @SCM_LIB.SCM(SCH_1):PAGE15
  R204    2      B Q_RES_0402LF-10K,1%,1/16W,CHIPA   I120 @SCM_LIB.SCM(SCH_1):PAGE32
  R512    1      A Q_RES_0402LF-33.2,1%,1/16W,CHIA   I129 @SCM_LIB.SCM(SCH_1):PAGE32

JTAG_SCM_TDO @SCM_LIB.SCM(SCH_1):JTAG_SCM_TDO
    U5   C9 TDO||MTDO1 AST2600A3GP-AST2600A3-GP,SMLF,A   I350 @SCM_LIB.SCM(SCH_1):PAGE15
  R523    2      B Q_RES_0402LF-10K,1%,1/16W,CHIPA   I119 @SCM_LIB.SCM(SCH_1):PAGE32
  R513    1      A Q_RES_0402LF-33.2,1%,1/16W,CHIA   I128 @SCM_LIB.SCM(SCH_1):PAGE32

JTAG_SCM_TMS @SCM_LIB.SCM(SCH_1):JTAG_SCM_TMS
    U5   A9 TMS||MTMS1 AST2600A3GP-AST2600A3-GP,SMLF,A   I350 @SCM_LIB.SCM(SCH_1):PAGE15
  R203    2      B Q_RES_0402LF-10K,1%,1/16W,CHIPA   I117 @SCM_LIB.SCM(SCH_1):PAGE32
  R511    1      A Q_RES_0402LF-33.2,1%,1/16W,CHIA   I127 @SCM_LIB.SCM(SCH_1):PAGE32

LED_D21_R1 @SCM_LIB.SCM(SCH_1):LED_D21_R1
  R286    2      B Q_RES_0402LF-316,1%,1/16W,CHIPA   I224 @SCM_LIB.SCM(SCH_1):PAGE50
  R389    1      A Q_RES_0402LF-316,1%,1/16W,CHIPA   I225 @SCM_LIB.SCM(SCH_1):PAGE50

LED_D21_R2 @SCM_LIB.SCM(SCH_1):LED_D21_R2
  R107    2      B Q_RES_0402LF-316,1%,1/16W,CHIPA   I222 @SCM_LIB.SCM(SCH_1):PAGE50
  R286    1      A Q_RES_0402LF-316,1%,1/16W,CHIPA   I224 @SCM_LIB.SCM(SCH_1):PAGE50

LED_D21_R3 @SCM_LIB.SCM(SCH_1):LED_D21_R3
  R107    1      A Q_RES_0402LF-316,1%,1/16W,CHIPA   I222 @SCM_LIB.SCM(SCH_1):PAGE50
   D21    A      A Q_LED_THLF-LED_BLUE,HV-312470/A   I294 @SCM_LIB.SCM(SCH_1):PAGE50

LED_D22_R @SCM_LIB.SCM(SCH_1):LED_D22_R
   R80    1      A Q_RES_0402LF-220,1%,1/16W,CHIPA   I210 @SCM_LIB.SCM(SCH_1):PAGE50
   C27    1      A Q_CAP_0402-0.1UF,25V,10%,X7R,CA   I212 @SCM_LIB.SCM(SCH_1):PAGE50
   D22    A      A Q_LED_THLF-LED_BLUE,HV-312470/A   I295 @SCM_LIB.SCM(SCH_1):PAGE50

LED_D22_R1 @SCM_LIB.SCM(SCH_1):LED_D22_R1
   Q13    6     D1 MOSFET_NCH_DUAL-PJT138K,SMLF,IA   I218 @SCM_LIB.SCM(SCH_1):PAGE50
   D22    C      C Q_LED_THLF-LED_BLUE,HV-312470/A   I295 @SCM_LIB.SCM(SCH_1):PAGE50

LED_POSTCODE_0 @SCM_LIB.SCM(SCH_1):LED_POSTCODE_0
    U5  P25 GPION0||NCTS2 AST2600A3GP-AST2600A3-GP,SMLF,A   I363 @SCM_LIB.SCM(SCH_1):PAGE13
  R604    1      A Q_RES_0402LF-750,1%,1/16W,CHIPA    I37 @SCM_LIB.SCM(SCH_1):PAGE47
  R700    1      A Q_RES_0402LF-0,5%,1/16W,CHIP,CA    I62 @SCM_LIB.SCM(SCH_1):PAGE47

LED_POSTCODE_0_R @SCM_LIB.SCM(SCH_1):LED_POSTCODE_0_R
    D0    A      A Q_LED_SMLF-LED_GREEN,19-213/GVA     I7 @SCM_LIB.SCM(SCH_1):PAGE47
  R604    2      B Q_RES_0402LF-750,1%,1/16W,CHIPA    I37 @SCM_LIB.SCM(SCH_1):PAGE47

LED_POSTCODE_0_R1 @SCM_LIB.SCM(SCH_1):LED_POSTCODE_0_R1
   U40    4    P00 PCA9555PW_SMLF-PCA9555PW,IC,TMA   I141 @SCM_LIB.SCM(SCH_1):PAGE28
  R700    2      B Q_RES_0402LF-0,5%,1/16W,CHIP,CA    I62 @SCM_LIB.SCM(SCH_1):PAGE47

LED_POSTCODE_1 @SCM_LIB.SCM(SCH_1):LED_POSTCODE_1
    U5  N23 GPION1||NDCD2 AST2600A3GP-AST2600A3-GP,SMLF,A   I363 @SCM_LIB.SCM(SCH_1):PAGE13
  R603    1      A Q_RES_0402LF-750,1%,1/16W,CHIPA    I35 @SCM_LIB.SCM(SCH_1):PAGE47
  R698    1      A Q_RES_0402LF-0,5%,1/16W,CHIP,CA    I60 @SCM_LIB.SCM(SCH_1):PAGE47

LED_POSTCODE_1_R @SCM_LIB.SCM(SCH_1):LED_POSTCODE_1_R
    D1    A      A Q_LED_SMLF-LED_GREEN,19-213/GVA     I9 @SCM_LIB.SCM(SCH_1):PAGE47
  R603    2      B Q_RES_0402LF-750,1%,1/16W,CHIPA    I35 @SCM_LIB.SCM(SCH_1):PAGE47

LED_POSTCODE_1_R1 @SCM_LIB.SCM(SCH_1):LED_POSTCODE_1_R1
   U40    5    P01 PCA9555PW_SMLF-PCA9555PW,IC,TMA   I141 @SCM_LIB.SCM(SCH_1):PAGE28
  R698    2      B Q_RES_0402LF-0,5%,1/16W,CHIP,CA    I60 @SCM_LIB.SCM(SCH_1):PAGE47

LED_POSTCODE_2 @SCM_LIB.SCM(SCH_1):LED_POSTCODE_2
    U5  N25 GPION2||NDSR2 AST2600A3GP-AST2600A3-GP,SMLF,A   I363 @SCM_LIB.SCM(SCH_1):PAGE13
  R602    1      A Q_RES_0402LF-750,1%,1/16W,CHIPA    I33 @SCM_LIB.SCM(SCH_1):PAGE47
  R697    1      A Q_RES_0402LF-0,5%,1/16W,CHIP,CA    I58 @SCM_LIB.SCM(SCH_1):PAGE47

LED_POSTCODE_2_R @SCM_LIB.SCM(SCH_1):LED_POSTCODE_2_R
    D2    A      A Q_LED_SMLF-LED_GREEN,19-213/GVA    I11 @SCM_LIB.SCM(SCH_1):PAGE47
  R602    2      B Q_RES_0402LF-750,1%,1/16W,CHIPA    I33 @SCM_LIB.SCM(SCH_1):PAGE47

LED_POSTCODE_2_R1 @SCM_LIB.SCM(SCH_1):LED_POSTCODE_2_R1
   U40    6    P02 PCA9555PW_SMLF-PCA9555PW,IC,TMA   I141 @SCM_LIB.SCM(SCH_1):PAGE28
  R697    2      B Q_RES_0402LF-0,5%,1/16W,CHIP,CA    I58 @SCM_LIB.SCM(SCH_1):PAGE47

LED_POSTCODE_3 @SCM_LIB.SCM(SCH_1):LED_POSTCODE_3
    U5  N24 GPION3||NRI2 AST2600A3GP-AST2600A3-GP,SMLF,A   I363 @SCM_LIB.SCM(SCH_1):PAGE13
  R601    1      A Q_RES_0402LF-750,1%,1/16W,CHIPA    I31 @SCM_LIB.SCM(SCH_1):PAGE47
  R696    1      A Q_RES_0402LF-0,5%,1/16W,CHIP,CA    I56 @SCM_LIB.SCM(SCH_1):PAGE47

LED_POSTCODE_3_R @SCM_LIB.SCM(SCH_1):LED_POSTCODE_3_R
    D3    A      A Q_LED_SMLF-LED_GREEN,19-213/GVA    I13 @SCM_LIB.SCM(SCH_1):PAGE47
  R601    2      B Q_RES_0402LF-750,1%,1/16W,CHIPA    I31 @SCM_LIB.SCM(SCH_1):PAGE47

LED_POSTCODE_3_R1 @SCM_LIB.SCM(SCH_1):LED_POSTCODE_3_R1
   U40    7    P03 PCA9555PW_SMLF-PCA9555PW,IC,TMA   I141 @SCM_LIB.SCM(SCH_1):PAGE28
  R696    2      B Q_RES_0402LF-0,5%,1/16W,CHIP,CA    I56 @SCM_LIB.SCM(SCH_1):PAGE47

LED_POSTCODE_4 @SCM_LIB.SCM(SCH_1):LED_POSTCODE_4
    U5  P26 GPION4||NDTR2 AST2600A3GP-AST2600A3-GP,SMLF,A   I363 @SCM_LIB.SCM(SCH_1):PAGE13
  R600    1      A Q_RES_0402LF-750,1%,1/16W,CHIPA    I25 @SCM_LIB.SCM(SCH_1):PAGE47
  R695    1      A Q_RES_0402LF-0,5%,1/16W,CHIP,CA    I54 @SCM_LIB.SCM(SCH_1):PAGE47

LED_POSTCODE_4_R @SCM_LIB.SCM(SCH_1):LED_POSTCODE_4_R
    D4    A      A Q_LED_SMLF-LED_RED,19-217/R6C-A    I10 @SCM_LIB.SCM(SCH_1):PAGE47
  R600    2      B Q_RES_0402LF-750,1%,1/16W,CHIPA    I25 @SCM_LIB.SCM(SCH_1):PAGE47

LED_POSTCODE_4_R1 @SCM_LIB.SCM(SCH_1):LED_POSTCODE_4_R1
   U40    8    P04 PCA9555PW_SMLF-PCA9555PW,IC,TMA   I141 @SCM_LIB.SCM(SCH_1):PAGE28
  R695    2      B Q_RES_0402LF-0,5%,1/16W,CHIP,CA    I54 @SCM_LIB.SCM(SCH_1):PAGE47

LED_POSTCODE_5 @SCM_LIB.SCM(SCH_1):LED_POSTCODE_5
    U5  M23 GPION5||NRTS2 AST2600A3GP-AST2600A3-GP,SMLF,A   I363 @SCM_LIB.SCM(SCH_1):PAGE13
  R599    1      A Q_RES_0402LF-750,1%,1/16W,CHIPA    I23 @SCM_LIB.SCM(SCH_1):PAGE47
  R676    1      A Q_RES_0402LF-0,5%,1/16W,CHIP,CA    I52 @SCM_LIB.SCM(SCH_1):PAGE47

LED_POSTCODE_5_R @SCM_LIB.SCM(SCH_1):LED_POSTCODE_5_R
    D5    A      A Q_LED_SMLF-LED_RED,19-217/R6C-A    I12 @SCM_LIB.SCM(SCH_1):PAGE47
  R599    2      B Q_RES_0402LF-750,1%,1/16W,CHIPA    I23 @SCM_LIB.SCM(SCH_1):PAGE47

LED_POSTCODE_5_R1 @SCM_LIB.SCM(SCH_1):LED_POSTCODE_5_R1
   U40    9    P05 PCA9555PW_SMLF-PCA9555PW,IC,TMA   I141 @SCM_LIB.SCM(SCH_1):PAGE28
  R676    2      B Q_RES_0402LF-0,5%,1/16W,CHIP,CA    I52 @SCM_LIB.SCM(SCH_1):PAGE47

LED_POSTCODE_6 @SCM_LIB.SCM(SCH_1):LED_POSTCODE_6
    U5  N26 GPION6||TXD2 AST2600A3GP-AST2600A3-GP,SMLF,A   I363 @SCM_LIB.SCM(SCH_1):PAGE13
  R598    1      A Q_RES_0402LF-750,1%,1/16W,CHIPA    I20 @SCM_LIB.SCM(SCH_1):PAGE47
  R674    1      A Q_RES_0402LF-0,5%,1/16W,CHIP,CA    I50 @SCM_LIB.SCM(SCH_1):PAGE47

LED_POSTCODE_6_R @SCM_LIB.SCM(SCH_1):LED_POSTCODE_6_R
    D6    A      A Q_LED_SMLF-LED_RED,19-217/R6C-A    I14 @SCM_LIB.SCM(SCH_1):PAGE47
  R598    2      B Q_RES_0402LF-750,1%,1/16W,CHIPA    I20 @SCM_LIB.SCM(SCH_1):PAGE47

LED_POSTCODE_6_R1 @SCM_LIB.SCM(SCH_1):LED_POSTCODE_6_R1
   U40   10    P06 PCA9555PW_SMLF-PCA9555PW,IC,TMA   I141 @SCM_LIB.SCM(SCH_1):PAGE28
  R674    2      B Q_RES_0402LF-0,5%,1/16W,CHIP,CA    I50 @SCM_LIB.SCM(SCH_1):PAGE47

LED_POSTCODE_7 @SCM_LIB.SCM(SCH_1):LED_POSTCODE_7
    U5  M26 GPION7||RXD2 AST2600A3GP-AST2600A3-GP,SMLF,A   I363 @SCM_LIB.SCM(SCH_1):PAGE13
  R597    1      A Q_RES_0402LF-750,1%,1/16W,CHIPA    I18 @SCM_LIB.SCM(SCH_1):PAGE47
  R669    1      A Q_RES_0402LF-0,5%,1/16W,CHIP,CA    I48 @SCM_LIB.SCM(SCH_1):PAGE47

LED_POSTCODE_7_R @SCM_LIB.SCM(SCH_1):LED_POSTCODE_7_R
    D7    A      A Q_LED_SMLF-LED_RED,19-217/R6C-A     I5 @SCM_LIB.SCM(SCH_1):PAGE47
  R597    2      B Q_RES_0402LF-750,1%,1/16W,CHIPA    I18 @SCM_LIB.SCM(SCH_1):PAGE47

LED_POSTCODE_7_R1 @SCM_LIB.SCM(SCH_1):LED_POSTCODE_7_R1
   U40   11    P07 PCA9555PW_SMLF-PCA9555PW,IC,TMA   I141 @SCM_LIB.SCM(SCH_1):PAGE28
  R669    2      B Q_RES_0402LF-0,5%,1/16W,CHIP,CA    I48 @SCM_LIB.SCM(SCH_1):PAGE47

LED_POSTCODE_A0 @SCM_LIB.SCM(SCH_1):LED_POSTCODE_A0
   U40   21     A0 PCA9555PW_SMLF-PCA9555PW,IC,TMA   I141 @SCM_LIB.SCM(SCH_1):PAGE28
  R738    2      B Q_RES_0402LF-4.7K,1%,1/16W,CHIA   I171 @SCM_LIB.SCM(SCH_1):PAGE28
  R743    1      A Q_RES_0402LF-100,1%,1/16W,EMPTA   I175 @SCM_LIB.SCM(SCH_1):PAGE28

LED_POSTCODE_A1 @SCM_LIB.SCM(SCH_1):LED_POSTCODE_A1
   U40    2     A1 PCA9555PW_SMLF-PCA9555PW,IC,TMA   I141 @SCM_LIB.SCM(SCH_1):PAGE28
  R739    2      B Q_RES_0402LF-4.7K,1%,1/16W,CHIA   I169 @SCM_LIB.SCM(SCH_1):PAGE28
  R744    1      A Q_RES_0402LF-100,1%,1/16W,EMPTA   I173 @SCM_LIB.SCM(SCH_1):PAGE28

LED_POSTCODE_A2 @SCM_LIB.SCM(SCH_1):LED_POSTCODE_A2
   U40    3     A2 PCA9555PW_SMLF-PCA9555PW,IC,TMA   I141 @SCM_LIB.SCM(SCH_1):PAGE28
  R740    2      B Q_RES_0402LF-4.7K,1%,1/16W,CHIA   I168 @SCM_LIB.SCM(SCH_1):PAGE28
  R745    1      A Q_RES_0402LF-100,1%,1/16W,EMPTA   I172 @SCM_LIB.SCM(SCH_1):PAGE28

LED_POSTCODE_INT @SCM_LIB.SCM(SCH_1):LED_POSTCODE_INT
   U40    1   INT* PCA9555PW_SMLF-PCA9555PW,IC,TMA   I141 @SCM_LIB.SCM(SCH_1):PAGE28
  R667    2      B Q_RES_0402LF-4.7K,1%,1/16W,CHIA   I147 @SCM_LIB.SCM(SCH_1):PAGE28

LPC_ESPI_SEL @SCM_LIB.SCM(SCH_1):LPC_ESPI_SEL
   GF1   B9  RSVD3 FCONN168_ME1016810202011_SCM-FA   I553 @SCM_LIB.SCM(SCH_1):PAGE10
   R41    2      B Q_RES_0402LF-10K,1%,1/16W,EMPTA   I225 @SCM_LIB.SCM(SCH_1):PAGE11
  R713    2      B Q_RES_0402LF-33.2,1%,1/16W,CHIA   I228 @SCM_LIB.SCM(SCH_1):PAGE17
  R714    1      A Q_RES_0402LF-2K,1%,1/16W,CHIP,A   I165 @SCM_LIB.SCM(SCH_1):PAGE27

LPC_ESPI_SEL_N @SCM_LIB.SCM(SCH_1):LPC_ESPI_SEL_N
   Q10    D  DRAIN MOSFET_N_GSD-DMG6968U-7,SMLF,IA   I227 @SCM_LIB.SCM(SCH_1):PAGE17
  R716    2      B Q_RES_0402LF-10K,1%,1/16W,CHIPA   I230 @SCM_LIB.SCM(SCH_1):PAGE17
  C270    1      A Q_CAP_0402-1UF,16V,10%,EMPTY,TA   I239 @SCM_LIB.SCM(SCH_1):PAGE17
    Q5    3      3 MOSFET_NCH_4D1S-NTGS4141NT1G,SA   I274 @SCM_LIB.SCM(SCH_1):PAGE17
  R493    1      A Q_RES_0402LF-150K,1%,1/16W,EMPA   I284 @SCM_LIB.SCM(SCH_1):PAGE17
    Q4    G      G MOSFET_PCH_GDS-NTR1P02LT1G,SMLA   I289 @SCM_LIB.SCM(SCH_1):PAGE17

LPC_ESPI_SEL_R @SCM_LIB.SCM(SCH_1):LPC_ESPI_SEL_R
   Q10    G   GATE MOSFET_N_GSD-DMG6968U-7,SMLF,IA   I227 @SCM_LIB.SCM(SCH_1):PAGE17
  R713    1      A Q_RES_0402LF-33.2,1%,1/16W,CHIA   I228 @SCM_LIB.SCM(SCH_1):PAGE17
  C273    1      A Q_CAP_0402-1UF,16V,10%,EMPTY,TA   I234 @SCM_LIB.SCM(SCH_1):PAGE17

LPC_ESPI_SEL_R1 @SCM_LIB.SCM(SCH_1):LPC_ESPI_SEL_R1
  R714    2      B Q_RES_0402LF-2K,1%,1/16W,CHIP,A   I165 @SCM_LIB.SCM(SCH_1):PAGE27
  C267    1      A Q_CAP_0402-1UF,16V,10%,EMPTY,TA   I166 @SCM_LIB.SCM(SCH_1):PAGE27
    Q7    G      G 2N7002A7-2N7002A-7,SMLF,IC,BAMA   I243 @SCM_LIB.SCM(SCH_1):PAGE27

MB_JTAG_PLD_R_JTAGEN @SCM_LIB.SCM(SCH_1):MB_JTAG_PLD_R_JTAGEN
  R509    1      A Q_RES_0402LF-33.2,1%,1/16W,CHIA    I50 @SCM_LIB.SCM(SCH_1):PAGE48
  R508    2      B Q_RES_0402LF-10K,1%,1/16W,CHIPA    I51 @SCM_LIB.SCM(SCH_1):PAGE48
  R507    1      A Q_RES_0402LF-100,1%,1/16W,EMPTA    I52 @SCM_LIB.SCM(SCH_1):PAGE48

M_BMC_DDR4_ALERT_N @SCM_LIB.SCM(SCH_1):M_BMC_DDR4_ALERT_N
    U5   N4 MALERT# AST2600A3GP-AST2600A3-GP,SMLF,A   I436 @SCM_LIB.SCM(SCH_1):PAGE12
    R9    1      A Q_RES_0402LF-4.7K,1%,1/16W,CHIA   I111 @SCM_LIB.SCM(SCH_1):PAGE20
    U1   P9 ALERT_N K4A8G165WCBCTD-K4A8G165WC-BCTDA   I196 @SCM_LIB.SCM(SCH_1):PAGE20

M_BMC_DDR4_BG1 @SCM_LIB.SCM(SCH_1):M_BMC_DDR4_BG1
    R2    1      A Q_RES_0402LF-0,5%,1/16W,CHIP,CA    I13 @SCM_LIB.SCM(SCH_1):PAGE20
    R1    1      A Q_RES_0402LF-0,5%,1/16W,EMPTY,A    I14 @SCM_LIB.SCM(SCH_1):PAGE20
    U1   M9   VSS6 K4A8G165WCBCTD-K4A8G165WC-BCTDA   I196 @SCM_LIB.SCM(SCH_1):PAGE20

M_BMC_DDR4_DQ<0> @SCM_LIB.SCM(SCH_1):M_BMC_DDR4_DQ(0)
    U5   T3   MDQ0 AST2600A3GP-AST2600A3-GP,SMLF,A   I436 @SCM_LIB.SCM(SCH_1):PAGE12
    U1   G2   DQL0 K4A8G165WCBCTD-K4A8G165WC-BCTDA   I196 @SCM_LIB.SCM(SCH_1):PAGE20

M_BMC_DDR4_DQ<10> @SCM_LIB.SCM(SCH_1):M_BMC_DDR4_DQ(10)
    U5   W1  MDQ10 AST2600A3GP-AST2600A3-GP,SMLF,A   I436 @SCM_LIB.SCM(SCH_1):PAGE12
    U1   C3   DQU2 K4A8G165WCBCTD-K4A8G165WC-BCTDA   I196 @SCM_LIB.SCM(SCH_1):PAGE20

M_BMC_DDR4_DQ<11> @SCM_LIB.SCM(SCH_1):M_BMC_DDR4_DQ(11)
    U5   W3  MDQ11 AST2600A3GP-AST2600A3-GP,SMLF,A   I436 @SCM_LIB.SCM(SCH_1):PAGE12
    U1   C7   DQU3 K4A8G165WCBCTD-K4A8G165WC-BCTDA   I196 @SCM_LIB.SCM(SCH_1):PAGE20

M_BMC_DDR4_DQ<12> @SCM_LIB.SCM(SCH_1):M_BMC_DDR4_DQ(12)
    U5   W4  MDQ12 AST2600A3GP-AST2600A3-GP,SMLF,A   I436 @SCM_LIB.SCM(SCH_1):PAGE12
    U1   C2   DQU4 K4A8G165WCBCTD-K4A8G165WC-BCTDA   I196 @SCM_LIB.SCM(SCH_1):PAGE20

M_BMC_DDR4_DQ<13> @SCM_LIB.SCM(SCH_1):M_BMC_DDR4_DQ(13)
    U5   U4  MDQ13 AST2600A3GP-AST2600A3-GP,SMLF,A   I436 @SCM_LIB.SCM(SCH_1):PAGE12
    U1   C8   DQU5 K4A8G165WCBCTD-K4A8G165WC-BCTDA   I196 @SCM_LIB.SCM(SCH_1):PAGE20

M_BMC_DDR4_DQ<14> @SCM_LIB.SCM(SCH_1):M_BMC_DDR4_DQ(14)
    U5   V4  MDQ14 AST2600A3GP-AST2600A3-GP,SMLF,A   I436 @SCM_LIB.SCM(SCH_1):PAGE12
    U1   D3   DQU6 K4A8G165WCBCTD-K4A8G165WC-BCTDA   I196 @SCM_LIB.SCM(SCH_1):PAGE20

M_BMC_DDR4_DQ<15> @SCM_LIB.SCM(SCH_1):M_BMC_DDR4_DQ(15)
    U5   U3  MDQ15 AST2600A3GP-AST2600A3-GP,SMLF,A   I436 @SCM_LIB.SCM(SCH_1):PAGE12
    U1   D7   DQU7 K4A8G165WCBCTD-K4A8G165WC-BCTDA   I196 @SCM_LIB.SCM(SCH_1):PAGE20

M_BMC_DDR4_DQ<1> @SCM_LIB.SCM(SCH_1):M_BMC_DDR4_DQ(1)
    U5   R4   MDQ1 AST2600A3GP-AST2600A3-GP,SMLF,A   I436 @SCM_LIB.SCM(SCH_1):PAGE12
    U1   F7   DQL1 K4A8G165WCBCTD-K4A8G165WC-BCTDA   I196 @SCM_LIB.SCM(SCH_1):PAGE20

M_BMC_DDR4_DQ<2> @SCM_LIB.SCM(SCH_1):M_BMC_DDR4_DQ(2)
    U5   U1   MDQ2 AST2600A3GP-AST2600A3-GP,SMLF,A   I436 @SCM_LIB.SCM(SCH_1):PAGE12
    U1   H3   DQL2 K4A8G165WCBCTD-K4A8G165WC-BCTDA   I196 @SCM_LIB.SCM(SCH_1):PAGE20

M_BMC_DDR4_DQ<3> @SCM_LIB.SCM(SCH_1):M_BMC_DDR4_DQ(3)
    U5   R3   MDQ3 AST2600A3GP-AST2600A3-GP,SMLF,A   I436 @SCM_LIB.SCM(SCH_1):PAGE12
    U1   H7   DQL3 K4A8G165WCBCTD-K4A8G165WC-BCTDA   I196 @SCM_LIB.SCM(SCH_1):PAGE20

M_BMC_DDR4_DQ<4> @SCM_LIB.SCM(SCH_1):M_BMC_DDR4_DQ(4)
    U5   R1   MDQ4 AST2600A3GP-AST2600A3-GP,SMLF,A   I436 @SCM_LIB.SCM(SCH_1):PAGE12
    U1   H2   DQL4 K4A8G165WCBCTD-K4A8G165WC-BCTDA   I196 @SCM_LIB.SCM(SCH_1):PAGE20

M_BMC_DDR4_DQ<5> @SCM_LIB.SCM(SCH_1):M_BMC_DDR4_DQ(5)
    U5   P1   MDQ5 AST2600A3GP-AST2600A3-GP,SMLF,A   I436 @SCM_LIB.SCM(SCH_1):PAGE12
    U1   H8   DQL5 K4A8G165WCBCTD-K4A8G165WC-BCTDA   I196 @SCM_LIB.SCM(SCH_1):PAGE20

M_BMC_DDR4_DQ<6> @SCM_LIB.SCM(SCH_1):M_BMC_DDR4_DQ(6)
    U5   P2   MDQ6 AST2600A3GP-AST2600A3-GP,SMLF,A   I436 @SCM_LIB.SCM(SCH_1):PAGE12
    U1   J3   DQL6 K4A8G165WCBCTD-K4A8G165WC-BCTDA   I196 @SCM_LIB.SCM(SCH_1):PAGE20

M_BMC_DDR4_DQ<7> @SCM_LIB.SCM(SCH_1):M_BMC_DDR4_DQ(7)
    U5   P3   MDQ7 AST2600A3GP-AST2600A3-GP,SMLF,A   I436 @SCM_LIB.SCM(SCH_1):PAGE12
    U1   J7   DQL7 K4A8G165WCBCTD-K4A8G165WC-BCTDA   I196 @SCM_LIB.SCM(SCH_1):PAGE20

M_BMC_DDR4_DQ<8> @SCM_LIB.SCM(SCH_1):M_BMC_DDR4_DQ(8)
    U5   W2   MDQ8 AST2600A3GP-AST2600A3-GP,SMLF,A   I436 @SCM_LIB.SCM(SCH_1):PAGE12
    U1   A3   DQU0 K4A8G165WCBCTD-K4A8G165WC-BCTDA   I196 @SCM_LIB.SCM(SCH_1):PAGE20

M_BMC_DDR4_DQ<9> @SCM_LIB.SCM(SCH_1):M_BMC_DDR4_DQ(9)
    U5   V3   MDQ9 AST2600A3GP-AST2600A3-GP,SMLF,A   I436 @SCM_LIB.SCM(SCH_1):PAGE12
    U1   B8   DQU1 K4A8G165WCBCTD-K4A8G165WC-BCTDA   I196 @SCM_LIB.SCM(SCH_1):PAGE20

M_BMC_DDR4_DQS0_N @SCM_LIB.SCM(SCH_1):M_BMC_DDR4_DQS0_N
    U5   T1 MDQS0# AST2600A3GP-AST2600A3-GP,SMLF,A   I436 @SCM_LIB.SCM(SCH_1):PAGE12
    U1   F3 DQSL_C K4A8G165WCBCTD-K4A8G165WC-BCTDA   I196 @SCM_LIB.SCM(SCH_1):PAGE20

M_BMC_DDR4_DQS0_P @SCM_LIB.SCM(SCH_1):M_BMC_DDR4_DQS0_P
    U5   T2  MDQS0 AST2600A3GP-AST2600A3-GP,SMLF,A   I436 @SCM_LIB.SCM(SCH_1):PAGE12
    U1   G3 DQSL_T K4A8G165WCBCTD-K4A8G165WC-BCTDA   I196 @SCM_LIB.SCM(SCH_1):PAGE20

M_BMC_DDR4_DQS1_N @SCM_LIB.SCM(SCH_1):M_BMC_DDR4_DQS1_N
    U5   V1 MDQS1# AST2600A3GP-AST2600A3-GP,SMLF,A   I436 @SCM_LIB.SCM(SCH_1):PAGE12
    U1   A7 DQSU_C K4A8G165WCBCTD-K4A8G165WC-BCTDA   I196 @SCM_LIB.SCM(SCH_1):PAGE20

M_BMC_DDR4_DQS1_P @SCM_LIB.SCM(SCH_1):M_BMC_DDR4_DQS1_P
    U5   V2  MDQS1 AST2600A3GP-AST2600A3-GP,SMLF,A   I436 @SCM_LIB.SCM(SCH_1):PAGE12
    U1   B7 DQSU_T K4A8G165WCBCTD-K4A8G165WC-BCTDA   I196 @SCM_LIB.SCM(SCH_1):PAGE20

M_BMC_DDR4_MA<0> @SCM_LIB.SCM(SCH_1):M_BMC_DDR4_MA(0)
    U5   F3    MA0 AST2600A3GP-AST2600A3-GP,SMLF,A   I436 @SCM_LIB.SCM(SCH_1):PAGE12
  R326    2      B Q_RES_0402LF-120,1%,1/16W,CHIPA   I193 @SCM_LIB.SCM(SCH_1):PAGE20
  R351    1      A Q_RES_0402LF-120,1%,1/16W,CHIPA   I194 @SCM_LIB.SCM(SCH_1):PAGE20
    U1   P3     A0 K4A8G165WCBCTD-K4A8G165WC-BCTDA   I196 @SCM_LIB.SCM(SCH_1):PAGE20

M_BMC_DDR4_MA<10> @SCM_LIB.SCM(SCH_1):M_BMC_DDR4_MA(10)
    U5   F2   MA10 AST2600A3GP-AST2600A3-GP,SMLF,A   I436 @SCM_LIB.SCM(SCH_1):PAGE12
  R336    2      B Q_RES_0402LF-120,1%,1/16W,CHIPA   I162 @SCM_LIB.SCM(SCH_1):PAGE20
  R361    1      A Q_RES_0402LF-120,1%,1/16W,CHIPA   I167 @SCM_LIB.SCM(SCH_1):PAGE20
    U1   M3 A10||AP K4A8G165WCBCTD-K4A8G165WC-BCTDA   I196 @SCM_LIB.SCM(SCH_1):PAGE20

M_BMC_DDR4_MA<11> @SCM_LIB.SCM(SCH_1):M_BMC_DDR4_MA(11)
    U5   G1   MA11 AST2600A3GP-AST2600A3-GP,SMLF,A   I436 @SCM_LIB.SCM(SCH_1):PAGE12
  R337    2      B Q_RES_0402LF-120,1%,1/16W,CHIPA   I161 @SCM_LIB.SCM(SCH_1):PAGE20
  R362    1      A Q_RES_0402LF-120,1%,1/16W,CHIPA   I168 @SCM_LIB.SCM(SCH_1):PAGE20
    U1   T2    A11 K4A8G165WCBCTD-K4A8G165WC-BCTDA   I196 @SCM_LIB.SCM(SCH_1):PAGE20

M_BMC_DDR4_MA<12> @SCM_LIB.SCM(SCH_1):M_BMC_DDR4_MA(12)
    U5   L4   MA12 AST2600A3GP-AST2600A3-GP,SMLF,A   I436 @SCM_LIB.SCM(SCH_1):PAGE12
  R338    2      B Q_RES_0402LF-120,1%,1/16W,CHIPA   I160 @SCM_LIB.SCM(SCH_1):PAGE20
  R363    1      A Q_RES_0402LF-120,1%,1/16W,CHIPA   I166 @SCM_LIB.SCM(SCH_1):PAGE20
    U1   M7 A12||BC_N K4A8G165WCBCTD-K4A8G165WC-BCTDA   I196 @SCM_LIB.SCM(SCH_1):PAGE20

M_BMC_DDR4_MA<13> @SCM_LIB.SCM(SCH_1):M_BMC_DDR4_MA(13)
    U5   K3   MA13 AST2600A3GP-AST2600A3-GP,SMLF,A   I436 @SCM_LIB.SCM(SCH_1):PAGE12
  R339    2      B Q_RES_0402LF-120,1%,1/16W,CHIPA   I159 @SCM_LIB.SCM(SCH_1):PAGE20
  R364    1      A Q_RES_0402LF-120,1%,1/16W,CHIPA   I165 @SCM_LIB.SCM(SCH_1):PAGE20
    U1   T8    A13 K4A8G165WCBCTD-K4A8G165WC-BCTDA   I196 @SCM_LIB.SCM(SCH_1):PAGE20

M_BMC_DDR4_MA<1> @SCM_LIB.SCM(SCH_1):M_BMC_DDR4_MA(1)
    U5   K5    MA1 AST2600A3GP-AST2600A3-GP,SMLF,A   I436 @SCM_LIB.SCM(SCH_1):PAGE12
  R327    2      B Q_RES_0402LF-120,1%,1/16W,CHIPA   I177 @SCM_LIB.SCM(SCH_1):PAGE20
  R352    1      A Q_RES_0402LF-120,1%,1/16W,CHIPA   I184 @SCM_LIB.SCM(SCH_1):PAGE20
    U1   P7     A1 K4A8G165WCBCTD-K4A8G165WC-BCTDA   I196 @SCM_LIB.SCM(SCH_1):PAGE20

M_BMC_DDR4_MA<2> @SCM_LIB.SCM(SCH_1):M_BMC_DDR4_MA(2)
    U5   F1    MA2 AST2600A3GP-AST2600A3-GP,SMLF,A   I436 @SCM_LIB.SCM(SCH_1):PAGE12
  R328    2      B Q_RES_0402LF-120,1%,1/16W,CHIPA   I176 @SCM_LIB.SCM(SCH_1):PAGE20
  R353    1      A Q_RES_0402LF-120,1%,1/16W,CHIPA   I183 @SCM_LIB.SCM(SCH_1):PAGE20
    U1   R3     A2 K4A8G165WCBCTD-K4A8G165WC-BCTDA   I196 @SCM_LIB.SCM(SCH_1):PAGE20

M_BMC_DDR4_MA<3> @SCM_LIB.SCM(SCH_1):M_BMC_DDR4_MA(3)
    U5   H3    MA3 AST2600A3GP-AST2600A3-GP,SMLF,A   I436 @SCM_LIB.SCM(SCH_1):PAGE12
  R329    2      B Q_RES_0402LF-120,1%,1/16W,CHIPA   I175 @SCM_LIB.SCM(SCH_1):PAGE20
  R354    1      A Q_RES_0402LF-120,1%,1/16W,CHIPA   I181 @SCM_LIB.SCM(SCH_1):PAGE20
    U1   N7     A3 K4A8G165WCBCTD-K4A8G165WC-BCTDA   I196 @SCM_LIB.SCM(SCH_1):PAGE20

M_BMC_DDR4_MA<4> @SCM_LIB.SCM(SCH_1):M_BMC_DDR4_MA(4)
    U5   J3    MA4 AST2600A3GP-AST2600A3-GP,SMLF,A   I436 @SCM_LIB.SCM(SCH_1):PAGE12
  R330    2      B Q_RES_0402LF-120,1%,1/16W,CHIPA   I174 @SCM_LIB.SCM(SCH_1):PAGE20
  R355    1      A Q_RES_0402LF-120,1%,1/16W,CHIPA   I182 @SCM_LIB.SCM(SCH_1):PAGE20
    U1   N3     A4 K4A8G165WCBCTD-K4A8G165WC-BCTDA   I196 @SCM_LIB.SCM(SCH_1):PAGE20

M_BMC_DDR4_MA<5> @SCM_LIB.SCM(SCH_1):M_BMC_DDR4_MA(5)
    U5   L1    MA5 AST2600A3GP-AST2600A3-GP,SMLF,A   I436 @SCM_LIB.SCM(SCH_1):PAGE12
  R331    2      B Q_RES_0402LF-120,1%,1/16W,CHIPA   I173 @SCM_LIB.SCM(SCH_1):PAGE20
  R356    1      A Q_RES_0402LF-120,1%,1/16W,CHIPA   I180 @SCM_LIB.SCM(SCH_1):PAGE20
    U1   P8     A5 K4A8G165WCBCTD-K4A8G165WC-BCTDA   I196 @SCM_LIB.SCM(SCH_1):PAGE20

M_BMC_DDR4_MA<6> @SCM_LIB.SCM(SCH_1):M_BMC_DDR4_MA(6)
    U5   M5    MA6 AST2600A3GP-AST2600A3-GP,SMLF,A   I436 @SCM_LIB.SCM(SCH_1):PAGE12
  R332    2      B Q_RES_0402LF-120,1%,1/16W,CHIPA   I171 @SCM_LIB.SCM(SCH_1):PAGE20
  R357    1      A Q_RES_0402LF-120,1%,1/16W,CHIPA   I179 @SCM_LIB.SCM(SCH_1):PAGE20
    U1   P2     A6 K4A8G165WCBCTD-K4A8G165WC-BCTDA   I196 @SCM_LIB.SCM(SCH_1):PAGE20

M_BMC_DDR4_MA<7> @SCM_LIB.SCM(SCH_1):M_BMC_DDR4_MA(7)
    U5   M2    MA7 AST2600A3GP-AST2600A3-GP,SMLF,A   I436 @SCM_LIB.SCM(SCH_1):PAGE12
  R333    2      B Q_RES_0402LF-120,1%,1/16W,CHIPA   I172 @SCM_LIB.SCM(SCH_1):PAGE20
  R358    1      A Q_RES_0402LF-120,1%,1/16W,CHIPA   I178 @SCM_LIB.SCM(SCH_1):PAGE20
    U1   R8     A7 K4A8G165WCBCTD-K4A8G165WC-BCTDA   I196 @SCM_LIB.SCM(SCH_1):PAGE20

M_BMC_DDR4_MA<8> @SCM_LIB.SCM(SCH_1):M_BMC_DDR4_MA(8)
    U5   M1    MA8 AST2600A3GP-AST2600A3-GP,SMLF,A   I436 @SCM_LIB.SCM(SCH_1):PAGE12
  R334    2      B Q_RES_0402LF-120,1%,1/16W,CHIPA   I164 @SCM_LIB.SCM(SCH_1):PAGE20
  R359    1      A Q_RES_0402LF-120,1%,1/16W,CHIPA   I170 @SCM_LIB.SCM(SCH_1):PAGE20
    U1   R2     A8 K4A8G165WCBCTD-K4A8G165WC-BCTDA   I196 @SCM_LIB.SCM(SCH_1):PAGE20

M_BMC_DDR4_MA<9> @SCM_LIB.SCM(SCH_1):M_BMC_DDR4_MA(9)
    U5   N1    MA9 AST2600A3GP-AST2600A3-GP,SMLF,A   I436 @SCM_LIB.SCM(SCH_1):PAGE12
  R335    2      B Q_RES_0402LF-120,1%,1/16W,CHIPA   I163 @SCM_LIB.SCM(SCH_1):PAGE20
  R360    1      A Q_RES_0402LF-120,1%,1/16W,CHIPA   I169 @SCM_LIB.SCM(SCH_1):PAGE20
    U1   R7     A9 K4A8G165WCBCTD-K4A8G165WC-BCTDA   I196 @SCM_LIB.SCM(SCH_1):PAGE20

M_BMC_DDR4_MACT_N @SCM_LIB.SCM(SCH_1):M_BMC_DDR4_MACT_N
    U5   H1 MA14||MACT# AST2600A3GP-AST2600A3-GP,SMLF,A   I436 @SCM_LIB.SCM(SCH_1):PAGE12
  R344    2      B Q_RES_0402LF-120,1%,1/16W,CHIPA   I121 @SCM_LIB.SCM(SCH_1):PAGE20
  R369    1      A Q_RES_0402LF-120,1%,1/16W,CHIPA   I132 @SCM_LIB.SCM(SCH_1):PAGE20
    U1   L3  ACT_N K4A8G165WCBCTD-K4A8G165WC-BCTDA   I196 @SCM_LIB.SCM(SCH_1):PAGE20

M_BMC_DDR4_MBA0 @SCM_LIB.SCM(SCH_1):M_BMC_DDR4_MBA0
    U5   G4   MBA0 AST2600A3GP-AST2600A3-GP,SMLF,A   I436 @SCM_LIB.SCM(SCH_1):PAGE12
  R346    2      B Q_RES_0402LF-120,1%,1/16W,CHIPA   I120 @SCM_LIB.SCM(SCH_1):PAGE20
  R371    1      A Q_RES_0402LF-120,1%,1/16W,CHIPA   I130 @SCM_LIB.SCM(SCH_1):PAGE20
    U1   N2    BA0 K4A8G165WCBCTD-K4A8G165WC-BCTDA   I196 @SCM_LIB.SCM(SCH_1):PAGE20

M_BMC_DDR4_MBA1 @SCM_LIB.SCM(SCH_1):M_BMC_DDR4_MBA1
    U5   H5   MBA1 AST2600A3GP-AST2600A3-GP,SMLF,A   I436 @SCM_LIB.SCM(SCH_1):PAGE12
  R347    2      B Q_RES_0402LF-120,1%,1/16W,CHIPA   I117 @SCM_LIB.SCM(SCH_1):PAGE20
  R372    1      A Q_RES_0402LF-120,1%,1/16W,CHIPA   I129 @SCM_LIB.SCM(SCH_1):PAGE20
    U1   N8    BA1 K4A8G165WCBCTD-K4A8G165WC-BCTDA   I196 @SCM_LIB.SCM(SCH_1):PAGE20

M_BMC_DDR4_MBG0 @SCM_LIB.SCM(SCH_1):M_BMC_DDR4_MBG0
    U5   G3 MBA2||MBG0 AST2600A3GP-AST2600A3-GP,SMLF,A   I436 @SCM_LIB.SCM(SCH_1):PAGE12
  R345    2      B Q_RES_0402LF-120,1%,1/16W,CHIPA   I119 @SCM_LIB.SCM(SCH_1):PAGE20
  R370    1      A Q_RES_0402LF-120,1%,1/16W,CHIPA   I131 @SCM_LIB.SCM(SCH_1):PAGE20
    U1   M2    BG0 K4A8G165WCBCTD-K4A8G165WC-BCTDA   I196 @SCM_LIB.SCM(SCH_1):PAGE20

M_BMC_DDR4_MBG1 @SCM_LIB.SCM(SCH_1):M_BMC_DDR4_MBG1
    U5   M3 MA15||MBG1 AST2600A3GP-AST2600A3-GP,SMLF,A   I436 @SCM_LIB.SCM(SCH_1):PAGE12
    R1    2      B Q_RES_0402LF-0,5%,1/16W,EMPTY,A    I14 @SCM_LIB.SCM(SCH_1):PAGE20
  R350    2      B Q_RES_0402LF-120,1%,1/16W,EMPTA   I114 @SCM_LIB.SCM(SCH_1):PAGE20
  R375    1      A Q_RES_0402LF-120,1%,1/16W,EMPTA   I115 @SCM_LIB.SCM(SCH_1):PAGE20

M_BMC_DDR4_MCAS_N @SCM_LIB.SCM(SCH_1):M_BMC_DDR4_MCAS_N
    U5   J4  MCAS# AST2600A3GP-AST2600A3-GP,SMLF,A   I436 @SCM_LIB.SCM(SCH_1):PAGE12
  R341    2      B Q_RES_0402LF-120,1%,1/16W,CHIPA   I125 @SCM_LIB.SCM(SCH_1):PAGE20
  R366    1      A Q_RES_0402LF-120,1%,1/16W,CHIPA   I137 @SCM_LIB.SCM(SCH_1):PAGE20
    U1   M8 CAS_N||A15 K4A8G165WCBCTD-K4A8G165WC-BCTDA   I196 @SCM_LIB.SCM(SCH_1):PAGE20

M_BMC_DDR4_MCKE @SCM_LIB.SCM(SCH_1):M_BMC_DDR4_MCKE
    U5   L5   MCKE AST2600A3GP-AST2600A3-GP,SMLF,A   I436 @SCM_LIB.SCM(SCH_1):PAGE12
  R349    2      B Q_RES_0402LF-120,1%,1/16W,CHIPA   I116 @SCM_LIB.SCM(SCH_1):PAGE20
  R374    1      A Q_RES_0402LF-120,1%,1/16W,CHIPA   I127 @SCM_LIB.SCM(SCH_1):PAGE20
    U1   K2    CKE K4A8G165WCBCTD-K4A8G165WC-BCTDA   I196 @SCM_LIB.SCM(SCH_1):PAGE20

M_BMC_DDR4_MCLK_C @SCM_LIB.SCM(SCH_1):M_BMC_DDR4_MCLK_C
    R8    2      B Q_RES_0402LF-60.4,1%,1/16W,CHIA    I89 @SCM_LIB.SCM(SCH_1):PAGE20
    R7    2      B Q_RES_0402LF-60.4,1%,1/16W,CHIA    I90 @SCM_LIB.SCM(SCH_1):PAGE20
   C12    1      A Q_CAP_0402-0.22UF,16V,10%,X7R,A   I106 @SCM_LIB.SCM(SCH_1):PAGE20
  C229    1      A Q_CAP_0402-0.22UF,16V,10%,EMPTA   I107 @SCM_LIB.SCM(SCH_1):PAGE20

M_BMC_DDR4_MCLK_DN @SCM_LIB.SCM(SCH_1):M_BMC_DDR4_MCLK_DN
    U5   K1   MCK# AST2600A3GP-AST2600A3-GP,SMLF,A   I436 @SCM_LIB.SCM(SCH_1):PAGE12
    R7    1      A Q_RES_0402LF-60.4,1%,1/16W,CHIA    I90 @SCM_LIB.SCM(SCH_1):PAGE20
    U1   K8   CK_C K4A8G165WCBCTD-K4A8G165WC-BCTDA   I196 @SCM_LIB.SCM(SCH_1):PAGE20

M_BMC_DDR4_MCLK_DP @SCM_LIB.SCM(SCH_1):M_BMC_DDR4_MCLK_DP
    U5   K2    MCK AST2600A3GP-AST2600A3-GP,SMLF,A   I436 @SCM_LIB.SCM(SCH_1):PAGE12
    R8    1      A Q_RES_0402LF-60.4,1%,1/16W,CHIA    I89 @SCM_LIB.SCM(SCH_1):PAGE20
    U1   K7   CK_T K4A8G165WCBCTD-K4A8G165WC-BCTDA   I196 @SCM_LIB.SCM(SCH_1):PAGE20

M_BMC_DDR4_MCS_N @SCM_LIB.SCM(SCH_1):M_BMC_DDR4_MCS_N
    U5   H2   MCS# AST2600A3GP-AST2600A3-GP,SMLF,A   I436 @SCM_LIB.SCM(SCH_1):PAGE12
  R343    2      B Q_RES_0402LF-120,1%,1/16W,CHIPA   I123 @SCM_LIB.SCM(SCH_1):PAGE20
  R368    1      A Q_RES_0402LF-120,1%,1/16W,CHIPA   I135 @SCM_LIB.SCM(SCH_1):PAGE20
    U1   L7   CS_N K4A8G165WCBCTD-K4A8G165WC-BCTDA   I196 @SCM_LIB.SCM(SCH_1):PAGE20

M_BMC_DDR4_MDM0 @SCM_LIB.SCM(SCH_1):M_BMC_DDR4_MDM0
    U5   N3   MDM0 AST2600A3GP-AST2600A3-GP,SMLF,A   I436 @SCM_LIB.SCM(SCH_1):PAGE12
    U1   E7 DML_N||DBIL_N K4A8G165WCBCTD-K4A8G165WC-BCTDA   I196 @SCM_LIB.SCM(SCH_1):PAGE20

M_BMC_DDR4_MDM1 @SCM_LIB.SCM(SCH_1):M_BMC_DDR4_MDM1
    U5   R5   MDM1 AST2600A3GP-AST2600A3-GP,SMLF,A   I436 @SCM_LIB.SCM(SCH_1):PAGE12
    U1   E2 DMU_N||DBIU_N K4A8G165WCBCTD-K4A8G165WC-BCTDA   I196 @SCM_LIB.SCM(SCH_1):PAGE20

M_BMC_DDR4_MODT @SCM_LIB.SCM(SCH_1):M_BMC_DDR4_MODT
    U5   J1   MODT AST2600A3GP-AST2600A3-GP,SMLF,A   I436 @SCM_LIB.SCM(SCH_1):PAGE12
  R348    2      B Q_RES_0402LF-120,1%,1/16W,CHIPA   I118 @SCM_LIB.SCM(SCH_1):PAGE20
  R373    1      A Q_RES_0402LF-120,1%,1/16W,CHIPA   I128 @SCM_LIB.SCM(SCH_1):PAGE20
    U1   K3    ODT K4A8G165WCBCTD-K4A8G165WC-BCTDA   I196 @SCM_LIB.SCM(SCH_1):PAGE20

M_BMC_DDR4_MRAS_N @SCM_LIB.SCM(SCH_1):M_BMC_DDR4_MRAS_N
    U5   J5  MRAS# AST2600A3GP-AST2600A3-GP,SMLF,A   I436 @SCM_LIB.SCM(SCH_1):PAGE12
  R342    2      B Q_RES_0402LF-120,1%,1/16W,CHIPA   I122 @SCM_LIB.SCM(SCH_1):PAGE20
  R367    1      A Q_RES_0402LF-120,1%,1/16W,CHIPA   I136 @SCM_LIB.SCM(SCH_1):PAGE20
    U1   L8  RAS_N K4A8G165WCBCTD-K4A8G165WC-BCTDA   I196 @SCM_LIB.SCM(SCH_1):PAGE20

M_BMC_DDR4_MWE_N @SCM_LIB.SCM(SCH_1):M_BMC_DDR4_MWE_N
    U5   G5   MWE# AST2600A3GP-AST2600A3-GP,SMLF,A   I436 @SCM_LIB.SCM(SCH_1):PAGE12
  R340    2      B Q_RES_0402LF-120,1%,1/16W,CHIPA   I124 @SCM_LIB.SCM(SCH_1):PAGE20
  R365    1      A Q_RES_0402LF-120,1%,1/16W,CHIPA   I138 @SCM_LIB.SCM(SCH_1):PAGE20
    U1   L2 WE_N||A14 K4A8G165WCBCTD-K4A8G165WC-BCTDA   I196 @SCM_LIB.SCM(SCH_1):PAGE20

M_BMC_DDR4_RST_N @SCM_LIB.SCM(SCH_1):M_BMC_DDR4_RST_N
    U5   L3 MRESET# AST2600A3GP-AST2600A3-GP,SMLF,A   I436 @SCM_LIB.SCM(SCH_1):PAGE12
    U1   P1 RESET_N K4A8G165WCBCTD-K4A8G165WC-BCTDA   I196 @SCM_LIB.SCM(SCH_1):PAGE20

M_BMC_DDR4_ZQU @SCM_LIB.SCM(SCH_1):M_BMC_DDR4_ZQU
    R3    1      A Q_RES_0402LF-0,5%,1/16W,CHIP,CA    I17 @SCM_LIB.SCM(SCH_1):PAGE20
    U1   E9   VSS2 K4A8G165WCBCTD-K4A8G165WC-BCTDA   I196 @SCM_LIB.SCM(SCH_1):PAGE20

NC         NC
    U5  AB4 GPIO18D0||EMMCCLK AST2600A3GP-AST2600A3-GP,SMLF,A   I149 @SCM_LIB.SCM(SCH_1):PAGE14
    U5  AA4 GPIO18D1||EMMCCMD AST2600A3GP-AST2600A3-GP,SMLF,A   I149 @SCM_LIB.SCM(SCH_1):PAGE14
    U5  AC4 GPIO18D2||EMMCDAT0 AST2600A3GP-AST2600A3-GP,SMLF,A   I149 @SCM_LIB.SCM(SCH_1):PAGE14
    U5  AA5 GPIO18D3||EMMCDAT1 AST2600A3GP-AST2600A3-GP,SMLF,A   I149 @SCM_LIB.SCM(SCH_1):PAGE14
    U5   Y5 GPIO18D4||EMMCDAT2 AST2600A3GP-AST2600A3-GP,SMLF,A   I149 @SCM_LIB.SCM(SCH_1):PAGE14
    U5  AB5 GPIO18D5||EMMCDAT3 AST2600A3GP-AST2600A3-GP,SMLF,A   I149 @SCM_LIB.SCM(SCH_1):PAGE14
    U5  AC5 GPIO18D6||EMMCCD# AST2600A3GP-AST2600A3-GP,SMLF,A   I149 @SCM_LIB.SCM(SCH_1):PAGE14
    U5  AB6 GPIO18D7||EMMCWP# AST2600A3GP-AST2600A3-GP,SMLF,A   I149 @SCM_LIB.SCM(SCH_1):PAGE14
    U5   Y1 GPIO18E0||EMMCDAT4||FWSPI18CS#||VBCS# AST2600A3GP-AST2600A3-GP,SMLF,A   I149 @SCM_LIB.SCM(SCH_1):PAGE14
    U5   Y2 GPIO18E1||EMMCDAT5||FWSPI18CK||VBCK AST2600A3GP-AST2600A3-GP,SMLF,A   I149 @SCM_LIB.SCM(SCH_1):PAGE14
    U5   Y3 GPIO18E2||EMMCDAT6||FWSPI18MOSI||VBMOSI AST2600A3GP-AST2600A3-GP,SMLF,A   I149 @SCM_LIB.SCM(SCH_1):PAGE14
    U5   Y4 GPIO18E3||EMMCDAT7||FWSPI18MISO||VBMISO AST2600A3GP-AST2600A3-GP,SMLF,A   I149 @SCM_LIB.SCM(SCH_1):PAGE14
    U5   B3 RGMII1RXCK||RMII1RCLKI||GPIO18A6 AST2600A3GP-AST2600A3-GP,SMLF,A   I149 @SCM_LIB.SCM(SCH_1):PAGE14
    U5   A2 RGMII1RXCTL||GPIO18A7 AST2600A3GP-AST2600A3-GP,SMLF,A   I149 @SCM_LIB.SCM(SCH_1):PAGE14
    U5   B2 RGMII1RXD0||RMII1RXD0||GPIO18B0 AST2600A3GP-AST2600A3-GP,SMLF,A   I149 @SCM_LIB.SCM(SCH_1):PAGE14
    U5   B1 RGMII1RXD1||RMII1RXD1||GPIO18B1 AST2600A3GP-AST2600A3-GP,SMLF,A   I149 @SCM_LIB.SCM(SCH_1):PAGE14
    U5   C4 RGMII1RXD2||RMII1CRSDV||GPIO18B2 AST2600A3GP-AST2600A3-GP,SMLF,A   I149 @SCM_LIB.SCM(SCH_1):PAGE14
    U5   E5 RGMII1RXD3||RMII1RXER||GPIO18B3 AST2600A3GP-AST2600A3-GP,SMLF,A   I149 @SCM_LIB.SCM(SCH_1):PAGE14
    U5   D6 RGMII1TXCTL||RMII1TXEN||GPIO18A1 AST2600A3GP-AST2600A3-GP,SMLF,A   I149 @SCM_LIB.SCM(SCH_1):PAGE14
    U5   D5 RGMII1TXD0||RMII1TXD0||GPIO18A2 AST2600A3GP-AST2600A3-GP,SMLF,A   I149 @SCM_LIB.SCM(SCH_1):PAGE14
    U5   A3 RGMII1TXD1||RMII1TXD1||GPIO18A3 AST2600A3GP-AST2600A3-GP,SMLF,A   I149 @SCM_LIB.SCM(SCH_1):PAGE14
    U5   C5 RGMII1TXD2||GPIO18A4 AST2600A3GP-AST2600A3-GP,SMLF,A   I149 @SCM_LIB.SCM(SCH_1):PAGE14
    U5   E6 RGMII1TXD3||GPIO18A5 AST2600A3GP-AST2600A3-GP,SMLF,A   I149 @SCM_LIB.SCM(SCH_1):PAGE14
    U5   D2 RGMII2RXCK||RMII2RCLKI||GPIO18C2 AST2600A3GP-AST2600A3-GP,SMLF,A   I149 @SCM_LIB.SCM(SCH_1):PAGE14
    U5   E3 RGMII2RXCTL||GPIO18C3 AST2600A3GP-AST2600A3-GP,SMLF,A   I149 @SCM_LIB.SCM(SCH_1):PAGE14
    U5   D1 RGMII2RXD0||RMII2RXD0||GPIO18C4 AST2600A3GP-AST2600A3-GP,SMLF,A   I149 @SCM_LIB.SCM(SCH_1):PAGE14
    U5   F4 RGMII2RXD1||RMII2RXD1||GPIO18C5 AST2600A3GP-AST2600A3-GP,SMLF,A   I149 @SCM_LIB.SCM(SCH_1):PAGE14
    U5   E2 RGMII2RXD2||RMII2CRSDV||GPIO18C6 AST2600A3GP-AST2600A3-GP,SMLF,A   I149 @SCM_LIB.SCM(SCH_1):PAGE14
    U5   E1 RGMII2RXD3||RMII2RXER||GPIO18C7 AST2600A3GP-AST2600A3-GP,SMLF,A   I149 @SCM_LIB.SCM(SCH_1):PAGE14
    U5   D4 RGMII2TXCK||RMII2RCLKO||GPIO18B4 AST2600A3GP-AST2600A3-GP,SMLF,A   I149 @SCM_LIB.SCM(SCH_1):PAGE14
    U5   C2 RGMII2TXCTL||RMII2TXEN||GPIO18B5 AST2600A3GP-AST2600A3-GP,SMLF,A   I149 @SCM_LIB.SCM(SCH_1):PAGE14
    U5   C1 RGMII2TXD0||RMII2TXD0||GPIO18B6 AST2600A3GP-AST2600A3-GP,SMLF,A   I149 @SCM_LIB.SCM(SCH_1):PAGE14
    U5 AD22 GPIOO1||PWM1 AST2600A3GP-AST2600A3-GP,SMLF,A   I350 @SCM_LIB.SCM(SCH_1):PAGE15
   U13    1    NC1 MC74VHC1G07DFT2G-MC74VHC1G07DFA    I89 @SCM_LIB.SCM(SCH_1):PAGE22
   U44    1    NC1 SN74LVC1G07DCKR-SN74LVC1G07DCKA    I61 @SCM_LIB.SCM(SCH_1):PAGE25
   U23    1    NC1 74LVC1G07W57-74LVC1G07W5-7,SMLA   I180 @SCM_LIB.SCM(SCH_1):PAGE28
   U22   TH     TH PI3PCIE3212ZBEX-PI3PCIE3212ZBEA   I206 @SCM_LIB.SCM(SCH_1):PAGE29
   U25   D9  PT18B LCMXO3LF2100C5BG256C-LCMXO3LF-A     I1 @SCM_LIB.SCM(SCH_1):PAGE34
   U25  A10  PT19B LCMXO3LF2100C5BG256C-LCMXO3LF-A     I1 @SCM_LIB.SCM(SCH_1):PAGE34
   U25   F9  PT19C LCMXO3LF2100C5BG256C-LCMXO3LF-A     I1 @SCM_LIB.SCM(SCH_1):PAGE34
   U25  D10  PT20A LCMXO3LF2100C5BG256C-LCMXO3LF-A     I1 @SCM_LIB.SCM(SCH_1):PAGE34
   U25  F16   PR4B LCMXO3LF2100C5BG256C-LCMXO3LF-A     I1 @SCM_LIB.SCM(SCH_1):PAGE35
   U25  G15   PR5A LCMXO3LF2100C5BG256C-LCMXO3LF-A     I1 @SCM_LIB.SCM(SCH_1):PAGE35
   U25  G14   PR5B LCMXO3LF2100C5BG256C-LCMXO3LF-A     I1 @SCM_LIB.SCM(SCH_1):PAGE35
   U25  H14 PR7A||PCLKT1_0 LCMXO3LF2100C5BG256C-LCMXO3LF-A     I1 @SCM_LIB.SCM(SCH_1):PAGE35
   U25  H16 PR7B||PCLKC1_0 LCMXO3LF2100C5BG256C-LCMXO3LF-A     I1 @SCM_LIB.SCM(SCH_1):PAGE35
   U25  K16   PR9B LCMXO3LF2100C5BG256C-LCMXO3LF-A     I1 @SCM_LIB.SCM(SCH_1):PAGE35
   U25  J11  PR10C LCMXO3LF2100C5BG256C-LCMXO3LF-A     I1 @SCM_LIB.SCM(SCH_1):PAGE35
   U25  L15  PR12A LCMXO3LF2100C5BG256C-LCMXO3LF-A     I1 @SCM_LIB.SCM(SCH_1):PAGE35
   U25  M16  PR12B LCMXO3LF2100C5BG256C-LCMXO3LF-A     I1 @SCM_LIB.SCM(SCH_1):PAGE35
   U25  P16  PR13D LCMXO3LF2100C5BG256C-LCMXO3LF-A     I1 @SCM_LIB.SCM(SCH_1):PAGE35
   U25  P15  PR14C LCMXO3LF2100C5BG256C-LCMXO3LF-A     I1 @SCM_LIB.SCM(SCH_1):PAGE35
   U25   T4   PB3B LCMXO3LF2100C5BG256C-LCMXO3LF-A     I1 @SCM_LIB.SCM(SCH_1):PAGE36
   U25   R9  PB18A LCMXO3LF2100C5BG256C-LCMXO3LF-A     I1 @SCM_LIB.SCM(SCH_1):PAGE36
   U25  T10  PB18B LCMXO3LF2100C5BG256C-LCMXO3LF-A     I1 @SCM_LIB.SCM(SCH_1):PAGE36
   U25  P10  PB19A LCMXO3LF2100C5BG256C-LCMXO3LF-A     I1 @SCM_LIB.SCM(SCH_1):PAGE36
   U25  R10  PB19B LCMXO3LF2100C5BG256C-LCMXO3LF-A     I1 @SCM_LIB.SCM(SCH_1):PAGE36
   U25  N10  PB19C LCMXO3LF2100C5BG256C-LCMXO3LF-A     I1 @SCM_LIB.SCM(SCH_1):PAGE36
   U25  M11  PB19D LCMXO3LF2100C5BG256C-LCMXO3LF-A     I1 @SCM_LIB.SCM(SCH_1):PAGE36
   U25  T11  PB21A LCMXO3LF2100C5BG256C-LCMXO3LF-A     I1 @SCM_LIB.SCM(SCH_1):PAGE36
   U25  P11  PB21B LCMXO3LF2100C5BG256C-LCMXO3LF-A     I1 @SCM_LIB.SCM(SCH_1):PAGE36
   U25  N11  PB21D LCMXO3LF2100C5BG256C-LCMXO3LF-A     I1 @SCM_LIB.SCM(SCH_1):PAGE36
   U25  R11  PB22A LCMXO3LF2100C5BG256C-LCMXO3LF-A     I1 @SCM_LIB.SCM(SCH_1):PAGE36
   U25  T12  PB22B LCMXO3LF2100C5BG256C-LCMXO3LF-A     I1 @SCM_LIB.SCM(SCH_1):PAGE36
   U25  R13  PB22C LCMXO3LF2100C5BG256C-LCMXO3LF-A     I1 @SCM_LIB.SCM(SCH_1):PAGE36
   U25  T14  PB22D LCMXO3LF2100C5BG256C-LCMXO3LF-A     I1 @SCM_LIB.SCM(SCH_1):PAGE36
   U25  P12  PB24A LCMXO3LF2100C5BG256C-LCMXO3LF-A     I1 @SCM_LIB.SCM(SCH_1):PAGE36
   U25  T13  PB24B LCMXO3LF2100C5BG256C-LCMXO3LF-A     I1 @SCM_LIB.SCM(SCH_1):PAGE36
   U25  P13 PB25B||SI||SISPI LCMXO3LF2100C5BG256C-LCMXO3LF-A     I1 @SCM_LIB.SCM(SCH_1):PAGE36
   U25   L1  PL11A LCMXO3LF2100C5BG256C-LCMXO3LF-A     I1 @SCM_LIB.SCM(SCH_1):PAGE37
   U25   L3  PL11B LCMXO3LF2100C5BG256C-LCMXO3LF-A     I1 @SCM_LIB.SCM(SCH_1):PAGE37
   U25   K4  PL11C LCMXO3LF2100C5BG256C-LCMXO3LF-A     I1 @SCM_LIB.SCM(SCH_1):PAGE37
   U25   L5  PL11D LCMXO3LF2100C5BG256C-LCMXO3LF-A     I1 @SCM_LIB.SCM(SCH_1):PAGE37
   U25   L2 PL12A||PCLKT3_0 LCMXO3LF2100C5BG256C-LCMXO3LF-A     I1 @SCM_LIB.SCM(SCH_1):PAGE37
   U25   M1 PL12B||PCLKC3_0 LCMXO3LF2100C5BG256C-LCMXO3LF-A     I1 @SCM_LIB.SCM(SCH_1):PAGE37
   U25   K5  PL12C LCMXO3LF2100C5BG256C-LCMXO3LF-A     I1 @SCM_LIB.SCM(SCH_1):PAGE37
   U25   L4  PL12D LCMXO3LF2100C5BG256C-LCMXO3LF-A     I1 @SCM_LIB.SCM(SCH_1):PAGE37
   U25   M3  PL13A LCMXO3LF2100C5BG256C-LCMXO3LF-A     I1 @SCM_LIB.SCM(SCH_1):PAGE37
   U25   N1  PL13B LCMXO3LF2100C5BG256C-LCMXO3LF-A     I1 @SCM_LIB.SCM(SCH_1):PAGE37
   U25   N2  PL13C LCMXO3LF2100C5BG256C-LCMXO3LF-A     I1 @SCM_LIB.SCM(SCH_1):PAGE37
   U25   P1  PL13D LCMXO3LF2100C5BG256C-LCMXO3LF-A     I1 @SCM_LIB.SCM(SCH_1):PAGE37
   U25   M2  PL14A LCMXO3LF2100C5BG256C-LCMXO3LF-A     I1 @SCM_LIB.SCM(SCH_1):PAGE37
   U25   N3  PL14B LCMXO3LF2100C5BG256C-LCMXO3LF-A     I1 @SCM_LIB.SCM(SCH_1):PAGE37
   U25   R1  PL14C LCMXO3LF2100C5BG256C-LCMXO3LF-A     I1 @SCM_LIB.SCM(SCH_1):PAGE37
   U25   P2  PL14D LCMXO3LF2100C5BG256C-LCMXO3LF-A     I1 @SCM_LIB.SCM(SCH_1):PAGE37
   U25   G1   PL6A LCMXO3LF2100C5BG256C-LCMXO3LF-A     I1 @SCM_LIB.SCM(SCH_1):PAGE38
   U25   H2   PL6B LCMXO3LF2100C5BG256C-LCMXO3LF-A     I1 @SCM_LIB.SCM(SCH_1):PAGE38
   U25   H4   PL6C LCMXO3LF2100C5BG256C-LCMXO3LF-A     I1 @SCM_LIB.SCM(SCH_1):PAGE38
   U25   J6   PL6D LCMXO3LF2100C5BG256C-LCMXO3LF-A     I1 @SCM_LIB.SCM(SCH_1):PAGE38
   U25   H3   PL7A LCMXO3LF2100C5BG256C-LCMXO3LF-A     I1 @SCM_LIB.SCM(SCH_1):PAGE38
   U25   H1   PL7B LCMXO3LF2100C5BG256C-LCMXO3LF-A     I1 @SCM_LIB.SCM(SCH_1):PAGE38
   U25   J1 PL7C||PCLKT4_0 LCMXO3LF2100C5BG256C-LCMXO3LF-A     I1 @SCM_LIB.SCM(SCH_1):PAGE38
   U25   J3 PL7D||PCLKC4_0 LCMXO3LF2100C5BG256C-LCMXO3LF-A     I1 @SCM_LIB.SCM(SCH_1):PAGE38
   U25   J2   PL9A LCMXO3LF2100C5BG256C-LCMXO3LF-A     I1 @SCM_LIB.SCM(SCH_1):PAGE38
   U25   K1   PL9B LCMXO3LF2100C5BG256C-LCMXO3LF-A     I1 @SCM_LIB.SCM(SCH_1):PAGE38
   U25   H5   PL9C LCMXO3LF2100C5BG256C-LCMXO3LF-A     I1 @SCM_LIB.SCM(SCH_1):PAGE38
   U25   J4   PL9D LCMXO3LF2100C5BG256C-LCMXO3LF-A     I1 @SCM_LIB.SCM(SCH_1):PAGE38
   U25   K3  PL10A LCMXO3LF2100C5BG256C-LCMXO3LF-A     I1 @SCM_LIB.SCM(SCH_1):PAGE38
   U25   K2  PL10B LCMXO3LF2100C5BG256C-LCMXO3LF-A     I1 @SCM_LIB.SCM(SCH_1):PAGE38
   U25   J5  PL10C LCMXO3LF2100C5BG256C-LCMXO3LF-A     I1 @SCM_LIB.SCM(SCH_1):PAGE38
   U25   K6  PL10D LCMXO3LF2100C5BG256C-LCMXO3LF-A     I1 @SCM_LIB.SCM(SCH_1):PAGE38
   U25   D3 PL1A||L_GPLLT_FB LCMXO3LF2100C5BG256C-LCMXO3LF-A     I1 @SCM_LIB.SCM(SCH_1):PAGE39
   U25   D1 PL1B||L_GPLLC_FB LCMXO3LF2100C5BG256C-LCMXO3LF-A     I1 @SCM_LIB.SCM(SCH_1):PAGE39
   U25   B1   PL1C LCMXO3LF2100C5BG256C-LCMXO3LF-A     I1 @SCM_LIB.SCM(SCH_1):PAGE39
   U25   C2   PL1D LCMXO3LF2100C5BG256C-LCMXO3LF-A     I1 @SCM_LIB.SCM(SCH_1):PAGE39
   U25   E2 PL2A||L_GPLLT_IN LCMXO3LF2100C5BG256C-LCMXO3LF-A     I1 @SCM_LIB.SCM(SCH_1):PAGE39
   U25   E3 PL2B||L_GPLLC_IN LCMXO3LF2100C5BG256C-LCMXO3LF-A     I1 @SCM_LIB.SCM(SCH_1):PAGE39
   U25   C1   PL2C LCMXO3LF2100C5BG256C-LCMXO3LF-A     I1 @SCM_LIB.SCM(SCH_1):PAGE39
   U25   D2   PL2D LCMXO3LF2100C5BG256C-LCMXO3LF-A     I1 @SCM_LIB.SCM(SCH_1):PAGE39
   U25   E1 PL3A||PCLKT5_0 LCMXO3LF2100C5BG256C-LCMXO3LF-A     I1 @SCM_LIB.SCM(SCH_1):PAGE39
   U25   F2 PL3B||PCLKC5_0 LCMXO3LF2100C5BG256C-LCMXO3LF-A     I1 @SCM_LIB.SCM(SCH_1):PAGE39
   U25   F4   PL3C LCMXO3LF2100C5BG256C-LCMXO3LF-A     I1 @SCM_LIB.SCM(SCH_1):PAGE39
   U25   G6   PL3D LCMXO3LF2100C5BG256C-LCMXO3LF-A     I1 @SCM_LIB.SCM(SCH_1):PAGE39
   U25   F3   PL4A LCMXO3LF2100C5BG256C-LCMXO3LF-A     I1 @SCM_LIB.SCM(SCH_1):PAGE39
   U25   F1   PL4B LCMXO3LF2100C5BG256C-LCMXO3LF-A     I1 @SCM_LIB.SCM(SCH_1):PAGE39
   U25   G5   PL4C LCMXO3LF2100C5BG256C-LCMXO3LF-A     I1 @SCM_LIB.SCM(SCH_1):PAGE39
   U25   G4   PL4D LCMXO3LF2100C5BG256C-LCMXO3LF-A     I1 @SCM_LIB.SCM(SCH_1):PAGE39
   U25   G2   PL5A LCMXO3LF2100C5BG256C-LCMXO3LF-A     I1 @SCM_LIB.SCM(SCH_1):PAGE39
   U25   G3   PL5B LCMXO3LF2100C5BG256C-LCMXO3LF-A     I1 @SCM_LIB.SCM(SCH_1):PAGE39
   U25   F5   PL5C LCMXO3LF2100C5BG256C-LCMXO3LF-A     I1 @SCM_LIB.SCM(SCH_1):PAGE39
   U25   H6   PL5D LCMXO3LF2100C5BG256C-LCMXO3LF-A     I1 @SCM_LIB.SCM(SCH_1):PAGE39
   U25   A2    NC1 LCMXO3LF2100C5BG256C-LCMXO3LF-A     I1 @SCM_LIB.SCM(SCH_1):PAGE40
  H2B1    1      1 HOLE_TH-EMPTY,DUMMY50    I14 @SCM_LIB.SCM(SCH_1):PAGE57
  H2B2    1      1 HOLE_TH-EMPTY,DUMMY50    I34 @SCM_LIB.SCM(SCH_1):PAGE57
   DM3    1      1 DUMMY_SYMBOL-BIOS_FLASH,MECH,MA    I35 @SCM_LIB.SCM(SCH_1):PAGE59
   DM1    1      1 DUMMY_SYMBOL-BMC_FLASH,MECH,EMA    I36 @SCM_LIB.SCM(SCH_1):PAGE59
   DM2    1      1 DUMMY_SYMBOL-BMC_FLASH,MECH,EMA    I37 @SCM_LIB.SCM(SCH_1):PAGE59
    J4    6      6 SCONN67_NASA0S6730TS67-SCONN67A    I84 @SCM_LIB.SCM(SCH_1):PAGE21
    J4   17     17 SCONN67_NASA0S6730TS67-SCONN67A    I84 @SCM_LIB.SCM(SCH_1):PAGE21
    J4   20     20 SCONN67_NASA0S6730TS67-SCONN67A    I84 @SCM_LIB.SCM(SCH_1):PAGE21
    J4   22     22 SCONN67_NASA0S6730TS67-SCONN67A    I84 @SCM_LIB.SCM(SCH_1):PAGE21
    J4   32     32 SCONN67_NASA0S6730TS67-SCONN67A    I84 @SCM_LIB.SCM(SCH_1):PAGE21
    J4   34     34 SCONN67_NASA0S6730TS67-SCONN67A    I84 @SCM_LIB.SCM(SCH_1):PAGE21
    J4   38     38 SCONN67_NASA0S6730TS67-SCONN67A    I84 @SCM_LIB.SCM(SCH_1):PAGE21
    J4   41     41 SCONN67_NASA0S6730TS67-SCONN67A    I84 @SCM_LIB.SCM(SCH_1):PAGE21
    J4   43     43 SCONN67_NASA0S6730TS67-SCONN67A    I84 @SCM_LIB.SCM(SCH_1):PAGE21
    J4   44     44 SCONN67_NASA0S6730TS67-SCONN67A    I84 @SCM_LIB.SCM(SCH_1):PAGE21
    J4   47     47 SCONN67_NASA0S6730TS67-SCONN67A    I84 @SCM_LIB.SCM(SCH_1):PAGE21
    J4   48     48 SCONN67_NASA0S6730TS67-SCONN67A    I84 @SCM_LIB.SCM(SCH_1):PAGE21
    J4   49     49 SCONN67_NASA0S6730TS67-SCONN67A    I84 @SCM_LIB.SCM(SCH_1):PAGE21
    J4   50     50 SCONN67_NASA0S6730TS67-SCONN67A    I84 @SCM_LIB.SCM(SCH_1):PAGE21
    J4   53     53 SCONN67_NASA0S6730TS67-SCONN67A    I84 @SCM_LIB.SCM(SCH_1):PAGE21
    J4   60     60 SCONN67_NASA0S6730TS67-SCONN67A    I84 @SCM_LIB.SCM(SCH_1):PAGE21
    J4   62     62 SCONN67_NASA0S6730TS67-SCONN67A    I84 @SCM_LIB.SCM(SCH_1):PAGE21
    J4   64     64 SCONN67_NASA0S6730TS67-SCONN67A    I84 @SCM_LIB.SCM(SCH_1):PAGE21
    J4   68     68 SCONN67_NASA0S6730TS67-SCONN67A    I84 @SCM_LIB.SCM(SCH_1):PAGE21
    J4   70     70 SCONN67_NASA0S6730TS67-SCONN67A    I84 @SCM_LIB.SCM(SCH_1):PAGE21
    J4   73     73 SCONN67_NASA0S6730TS67-SCONN67A    I84 @SCM_LIB.SCM(SCH_1):PAGE21
    H2    1      1 HOLE_TH-EMPTY,HOLE1247    I45 @SCM_LIB.SCM(SCH_1):PAGE57

NC_DP_BMC_AUX_N @SCM_LIB.SCM(SCH_1):NC_DP_BMC_AUX_N
    U5  AB3 DPAUXN AST2600A3GP-AST2600A3-GP,SMLF,A   I436 @SCM_LIB.SCM(SCH_1):PAGE12

NC_DP_BMC_AUX_P @SCM_LIB.SCM(SCH_1):NC_DP_BMC_AUX_P
    U5  AC3 DPAUXP AST2600A3GP-AST2600A3-GP,SMLF,A   I436 @SCM_LIB.SCM(SCH_1):PAGE12

NC_DP_BMC_TX0_N @SCM_LIB.SCM(SCH_1):NC_DP_BMC_TX0_N
    U5  AB1 DPTXN0 AST2600A3GP-AST2600A3-GP,SMLF,A   I436 @SCM_LIB.SCM(SCH_1):PAGE12

NC_DP_BMC_TX0_P @SCM_LIB.SCM(SCH_1):NC_DP_BMC_TX0_P
    U5  AC1 DPTXP0 AST2600A3GP-AST2600A3-GP,SMLF,A   I436 @SCM_LIB.SCM(SCH_1):PAGE12

NC_DP_BMC_TX1_N @SCM_LIB.SCM(SCH_1):NC_DP_BMC_TX1_N
    U5  AA2 DPTXN1 AST2600A3GP-AST2600A3-GP,SMLF,A   I436 @SCM_LIB.SCM(SCH_1):PAGE12

NC_DP_BMC_TX1_P @SCM_LIB.SCM(SCH_1):NC_DP_BMC_TX1_P
    U5  AB2 DPTXP1 AST2600A3GP-AST2600A3-GP,SMLF,A   I436 @SCM_LIB.SCM(SCH_1):PAGE12

NC_FM_PFR_NO_SERVICE_ACT_N @SCM_LIB.SCM(SCH_1):NC_FM_PFR_NO_SERVICE_ACT_N
   U25   L7   PB8D LCMXO3LF2100C5BG256C-LCMXO3LF-A     I1 @SCM_LIB.SCM(SCH_1):PAGE36

NC_FM_PFR_UPDATE_N @SCM_LIB.SCM(SCH_1):NC_FM_PFR_UPDATE_N
   U25   R8 PB11B||PCLKC2_0 LCMXO3LF2100C5BG256C-LCMXO3LF-A     I1 @SCM_LIB.SCM(SCH_1):PAGE36

NC_J1_P3 @SCM_LIB.SCM(SCH_1):NC_J1_P3
    J1    3      3 SCONN3_212H9103GBR1-SCONN3_212A   I169 @SCM_LIB.SCM(SCH_1):PAGE25

NC_U16_P1 @SCM_LIB.SCM(SCH_1):NC_U16_P1
   U16    1     NC 74LVC1G07GW-74LVC1G07GW,SMLF,EA   I227 @SCM_LIB.SCM(SCH_1):PAGE50

NC_U54_P1 @SCM_LIB.SCM(SCH_1):NC_U54_P1
   U54    5      Q 74LVC1G74DP-74LVC1G74DP,SMLF,IA   I138 @SCM_LIB.SCM(SCH_1):PAGE25

NC_U55_P1 @SCM_LIB.SCM(SCH_1):NC_U55_P1
   U55    1     NC SN74LVC1G14DCKR_SMLF-IC,SN74LVA   I150 @SCM_LIB.SCM(SCH_1):PAGE25

NC_U57_P1 @SCM_LIB.SCM(SCH_1):NC_U57_P1
   U57    1     NC 74LVC1G07GW-74LVC1G07GW,SMLF,IA   I278 @SCM_LIB.SCM(SCH_1):PAGE50

P0V6_DDR_VREF_AUX @SCM_LIB.SCM(SCH_1):P0V6_DDR_VREF_AUX
   C21    1      A Q_CAP_C0402-0.01UF,50V,10%,EMPA    I24 @SCM_LIB.SCM(SCH_1):PAGE12
   C23    1      A Q_CAP_0402-0.1UF,25V,10%,X7R,CA    I28 @SCM_LIB.SCM(SCH_1):PAGE12
    U5   T5 MVREF_T5 AST2600A3GP-AST2600A3-GP,SMLF,A   I436 @SCM_LIB.SCM(SCH_1):PAGE12
    U5   U5 MVREF_U5 AST2600A3GP-AST2600A3-GP,SMLF,A   I436 @SCM_LIB.SCM(SCH_1):PAGE12
  R325    1      A Q_RES_0402LF-1K,1%,1/16W,CHIP,A    I27 @SCM_LIB.SCM(SCH_1):PAGE20
  R324    2      B Q_RES_0402LF-1K,1%,1/16W,CHIP,A    I28 @SCM_LIB.SCM(SCH_1):PAGE20
  C168    1      A Q_CAP_0402-0.1UF,25V,10%,X7R,CA    I32 @SCM_LIB.SCM(SCH_1):PAGE20
  C170    1      A Q_CAP_C0402-0.01UF,50V,10%,X7RA    I33 @SCM_LIB.SCM(SCH_1):PAGE20
  C169    2      B Q_CAP_C0402-0.01UF,50V,10%,EMPA    I34 @SCM_LIB.SCM(SCH_1):PAGE20
   C10    1      A Q_CAP_0402-0.1UF,25V,10%,X7R,CA    I85 @SCM_LIB.SCM(SCH_1):PAGE20
    U1   M1 VREFCA K4A8G165WCBCTD-K4A8G165WC-BCTDA   I196 @SCM_LIB.SCM(SCH_1):PAGE20
   C22    1      A Q_CAP_0402-0.1UF,25V,10%,X7R,CA   I448 @SCM_LIB.SCM(SCH_1):PAGE12

P12V_AUX @SCM_LIB.SCM(SCH_1):P12V_AUX
   GF1  OA1 P12V_AUX_OA1 FCONN168_ME1016810202011_SCM-FA   I553 @SCM_LIB.SCM(SCH_1):PAGE10
   GF1  OA2 P12V_AUX_OA2 FCONN168_ME1016810202011_SCM-FA   I553 @SCM_LIB.SCM(SCH_1):PAGE10
   GF1  OB1 P12V_AUX_OB1 FCONN168_ME1016810202011_SCM-FA   I553 @SCM_LIB.SCM(SCH_1):PAGE10
   GF1  OB2 P12V_AUX_OB2 FCONN168_ME1016810202011_SCM-FA   I553 @SCM_LIB.SCM(SCH_1):PAGE10
  R785    1      A Q_RES_0402LF-15.8K,1%,1/16W,CHA   I202 @SCM_LIB.SCM(SCH_1):PAGE15
 PR521    1      A Q_RES_0402LF-681K,1%,1/16W,CHIA     I4 @SCM_LIB.SCM(SCH_1):PAGE51
   PL4    1      1 Q_INDUCTOR_SMLF-BLM18SN220TN1DA    I39 @SCM_LIB.SCM(SCH_1):PAGE51
  C241    1      A Q_CAP_0402-0.1UF,25V,10%,X7R,CA    I52 @SCM_LIB.SCM(SCH_1):PAGE51
  PL19    1      1 Q_INDUCTOR_SMLF-BLM18SN220TN1DA    I32 @SCM_LIB.SCM(SCH_1):PAGE52
  C262    1      A Q_CAP_0402-0.1UF,25V,10%,X7R,CA   I101 @SCM_LIB.SCM(SCH_1):PAGE52
  PL29    1      1 Q_INDUCTOR_SMLF-BLM18SN220TN1DA    I31 @SCM_LIB.SCM(SCH_1):PAGE55
  C278    1      A Q_CAP_0402-0.1UF,25V,10%,X7R,CA    I54 @SCM_LIB.SCM(SCH_1):PAGE55
  PL32    1      1 Q_INDUCTOR_SMLF-BLM18SN220TN1DA    I34 @SCM_LIB.SCM(SCH_1):PAGE56
  C280    1      A Q_CAP_0402-0.1UF,25V,10%,X7R,CA    I58 @SCM_LIB.SCM(SCH_1):PAGE56
  C329    1      A Q_CAP_C0805-22UF,16V,20%,X6S,CA   I573 @SCM_LIB.SCM(SCH_1):PAGE10
  C330    1      A Q_CAP_C0805-22UF,16V,20%,X6S,CA   I574 @SCM_LIB.SCM(SCH_1):PAGE10
   U56    3     EN AP2205W57-AP2205-W5-7,SMLF,IC,A    I56 @SCM_LIB.SCM(SCH_1):PAGE51
   U56    1    VIN AP2205W57-AP2205-W5-7,SMLF,IC,A    I56 @SCM_LIB.SCM(SCH_1):PAGE51
  C226    1      A Q_CAP_C0402-1UF,25V,10%,X6S,CHA    I60 @SCM_LIB.SCM(SCH_1):PAGE51
  R389    2      B Q_RES_0402LF-316,1%,1/16W,CHIPA   I225 @SCM_LIB.SCM(SCH_1):PAGE50

P12V_SENSOR @SCM_LIB.SCM(SCH_1):P12V_SENSOR
  C290    1      A Q_CAP_0402-0.1UF,25V,10%,X7R,CA   I201 @SCM_LIB.SCM(SCH_1):PAGE15
  R785    2      B Q_RES_0402LF-15.8K,1%,1/16W,CHA   I202 @SCM_LIB.SCM(SCH_1):PAGE15
  R786    1      A Q_RES_0402LF-2K,1%,1/16W,CHIP,A   I203 @SCM_LIB.SCM(SCH_1):PAGE15
    U5 AD20 ADC0||GPIT0 AST2600A3GP-AST2600A3-GP,SMLF,A   I350 @SCM_LIB.SCM(SCH_1):PAGE15

P1V0_AUX @SCM_LIB.SCM(SCH_1):P1V0_AUX
  R796    1      A Q_RES_0402LF-1K,1%,1/16W,CHIP,A   I255 @SCM_LIB.SCM(SCH_1):PAGE15
    L8    1      1 Q_INDUCTOR_SMLF-BLM18PG121SN1DA    I29 @SCM_LIB.SCM(SCH_1):PAGE16
   C86    1      A Q_CAP_0402-0.1UF,25V,10%,X7R,CA   I149 @SCM_LIB.SCM(SCH_1):PAGE16
   C92    1      A Q_CAP_0402-0.1UF,25V,10%,X7R,CA   I150 @SCM_LIB.SCM(SCH_1):PAGE16
   C99    1      A Q_CAP_0402-0.1UF,25V,10%,X7R,CA   I154 @SCM_LIB.SCM(SCH_1):PAGE16
  C104    1      A Q_CAP_C0402-1UF,25V,10%,X6S,CHA   I155 @SCM_LIB.SCM(SCH_1):PAGE16
  C108    1      A Q_CAP_C0402-1UF,25V,10%,X6S,CHA   I157 @SCM_LIB.SCM(SCH_1):PAGE16
  C118    1      A Q_CAP_C0603-22UF,6.3V,20%,X6S,A   I162 @SCM_LIB.SCM(SCH_1):PAGE16
  C123    1      A Q_CAP_C0603-22UF,6.3V,20%,X6S,A   I171 @SCM_LIB.SCM(SCH_1):PAGE16
    U5   L9 IV10D_L9 AST2600A3GP-AST2600A3-GP,SMLF,A   I188 @SCM_LIB.SCM(SCH_1):PAGE16
    U5  L10 IV10D_L10 AST2600A3GP-AST2600A3-GP,SMLF,A   I188 @SCM_LIB.SCM(SCH_1):PAGE16
    U5   M8 IV10D_M8 AST2600A3GP-AST2600A3-GP,SMLF,A   I188 @SCM_LIB.SCM(SCH_1):PAGE16
    U5  M11 IV10D_M11 AST2600A3GP-AST2600A3-GP,SMLF,A   I188 @SCM_LIB.SCM(SCH_1):PAGE16
    U5   N8 IV10D_N8 AST2600A3GP-AST2600A3-GP,SMLF,A   I188 @SCM_LIB.SCM(SCH_1):PAGE16
    U5  N11 IV10D_N11 AST2600A3GP-AST2600A3-GP,SMLF,A   I188 @SCM_LIB.SCM(SCH_1):PAGE16
    U5   P8 IV10D_P8 AST2600A3GP-AST2600A3-GP,SMLF,A   I188 @SCM_LIB.SCM(SCH_1):PAGE16
    U5  P11 IV10D_P11 AST2600A3GP-AST2600A3-GP,SMLF,A   I188 @SCM_LIB.SCM(SCH_1):PAGE16
    U5   R9 IV10D_R9 AST2600A3GP-AST2600A3-GP,SMLF,A   I188 @SCM_LIB.SCM(SCH_1):PAGE16
    U5  R10 IV10D_R10 AST2600A3GP-AST2600A3-GP,SMLF,A   I188 @SCM_LIB.SCM(SCH_1):PAGE16
  R281    1      A Q_RES_0402LF-0,5%,1/16W,CHIP,CA    I92 @SCM_LIB.SCM(SCH_1):PAGE17
  R279    1      A Q_RES_0402LF-0,5%,1/16W,CHIP,CA    I95 @SCM_LIB.SCM(SCH_1):PAGE17
    L6    1      1 Q_INDUCTOR_SMLF-BLM18PG121SN1DA   I124 @SCM_LIB.SCM(SCH_1):PAGE17
   L13    1      1 Q_INDUCTOR_SMLF-BLM18PG121SN1DA   I158 @SCM_LIB.SCM(SCH_1):PAGE17
   L15    1      1 Q_INDUCTOR_SMLF-BLM18PG121SN1DA   I170 @SCM_LIB.SCM(SCH_1):PAGE17
  PU42   12   VOUT NB695GDZ-NB695GD-Z,SMLF,IC,AL0A    I15 @SCM_LIB.SCM(SCH_1):PAGE56
 PC266    1      A Q_CAP_0402-0.1UF,25V,10%,X7R,CA    I23 @SCM_LIB.SCM(SCH_1):PAGE56
 PC267    1      A Q_CAP_0805-22UF,4V,20%,X6S,TMPA    I24 @SCM_LIB.SCM(SCH_1):PAGE56
 PC268    1      A Q_CAP_0805-22UF,4V,20%,X6S,TMPA    I25 @SCM_LIB.SCM(SCH_1):PAGE56
 PC269    1      A Q_CAP_0805-22UF,4V,20%,X6S,TMPA    I28 @SCM_LIB.SCM(SCH_1):PAGE56
 PC270    1      A Q_CAP_0805-22UF,4V,20%,X6S,TMPA    I29 @SCM_LIB.SCM(SCH_1):PAGE56
  PL33    2      2 Q_INDUCTOR_SMLF-1UH,IND,CV-10BA    I37 @SCM_LIB.SCM(SCH_1):PAGE56
   U43    5  SENSE TPS3808G18DBVR-TPS3808G01DBVR,A    I90 @SCM_LIB.SCM(SCH_1):PAGE22
  C113    1      A Q_CAP_C0603-22UF,6.3V,20%,X6S,A   I189 @SCM_LIB.SCM(SCH_1):PAGE16

P1V0_AUX_MODE @SCM_LIB.SCM(SCH_1):P1V0_AUX_MODE
  PU42    7   MODE NB695GDZ-NB695GD-Z,SMLF,IC,AL0A    I15 @SCM_LIB.SCM(SCH_1):PAGE56
 PR543    1      A Q_RES_0402LF-100K,1%,1/16W,CHIA    I71 @SCM_LIB.SCM(SCH_1):PAGE56

P1V0_AUX_VCC @SCM_LIB.SCM(SCH_1):P1V0_AUX_VCC
 PC260    1      A Q_CAP_C0402-1UF,25V,10%,X6S,CHA     I7 @SCM_LIB.SCM(SCH_1):PAGE56
 PR541    2      B Q_RES_0402LF-5.1,5%,1/16W,CHIPA     I8 @SCM_LIB.SCM(SCH_1):PAGE56
  PU42   10    3V3 NB695GDZ-NB695GD-Z,SMLF,IC,AL0A    I15 @SCM_LIB.SCM(SCH_1):PAGE56
  PU42    3     C1 NB695GDZ-NB695GD-Z,SMLF,IC,AL0A    I15 @SCM_LIB.SCM(SCH_1):PAGE56
  PU42    6    LP# NB695GDZ-NB695GD-Z,SMLF,IC,AL0A    I15 @SCM_LIB.SCM(SCH_1):PAGE56

P1V0_SENSOR @SCM_LIB.SCM(SCH_1):P1V0_SENSOR
  R796    2      B Q_RES_0402LF-1K,1%,1/16W,CHIP,A   I255 @SCM_LIB.SCM(SCH_1):PAGE15
  C311    1      A Q_CAP_0402-0.1UF,25V,10%,X7R,CA   I256 @SCM_LIB.SCM(SCH_1):PAGE15
    U5 AB17 ADC10||GPIU2||SALT11 AST2600A3GP-AST2600A3-GP,SMLF,A   I350 @SCM_LIB.SCM(SCH_1):PAGE15

P1V0_STBY_DP_VCC10A @SCM_LIB.SCM(SCH_1):P1V0_STBY_DP_VCC10A
    U5   T8 DP_VCC10A AST2600A3GP-AST2600A3-GP,SMLF,A   I188 @SCM_LIB.SCM(SCH_1):PAGE16
   C97    1      A Q_CAP_0402-0.1UF,25V,10%,X7R,CA   I169 @SCM_LIB.SCM(SCH_1):PAGE17
   L15    2      2 Q_INDUCTOR_SMLF-BLM18PG121SN1DA   I170 @SCM_LIB.SCM(SCH_1):PAGE17
   C90    1      A Q_CAP_C0402-1UF,25V,10%,X6S,CHA   I173 @SCM_LIB.SCM(SCH_1):PAGE17

P1V0_STBY_PE_VCC10A @SCM_LIB.SCM(SCH_1):P1V0_STBY_PE_VCC10A
    U5   T9 RC_VCC10A AST2600A3GP-AST2600A3-GP,SMLF,A   I188 @SCM_LIB.SCM(SCH_1):PAGE16
   C79    1      A Q_CAP_0402-0.1UF,25V,10%,X7R,CA   I157 @SCM_LIB.SCM(SCH_1):PAGE17
   L13    2      2 Q_INDUCTOR_SMLF-BLM18PG121SN1DA   I158 @SCM_LIB.SCM(SCH_1):PAGE17
   C78    1      A Q_CAP_C0402-1UF,25V,10%,X6S,CHA   I160 @SCM_LIB.SCM(SCH_1):PAGE17

P1V0_STBY_PLAVDD @SCM_LIB.SCM(SCH_1):P1V0_STBY_PLAVDD
    L8    2      2 Q_INDUCTOR_SMLF-BLM18PG121SN1DA    I29 @SCM_LIB.SCM(SCH_1):PAGE16
   C52    1      A Q_CAP_C0402-1UF,25V,10%,X6S,CHA    I31 @SCM_LIB.SCM(SCH_1):PAGE16
   C54    1      A Q_CAP_0402-0.1UF,25V,10%,X7R,CA    I32 @SCM_LIB.SCM(SCH_1):PAGE16
   C56    1      A Q_CAP_C0402-1UF,25V,10%,X6S,CHA    I33 @SCM_LIB.SCM(SCH_1):PAGE16
   C59    1      A Q_CAP_0402-0.1UF,25V,10%,X7R,CA    I79 @SCM_LIB.SCM(SCH_1):PAGE16
   C64    1      A Q_CAP_C0402-1UF,25V,10%,X6S,CHA    I81 @SCM_LIB.SCM(SCH_1):PAGE16
   C68    1      A Q_CAP_0402-0.1UF,25V,10%,X7R,CA    I82 @SCM_LIB.SCM(SCH_1):PAGE16
    U5   J9 DPLLAVDD AST2600A3GP-AST2600A3-GP,SMLF,A   I188 @SCM_LIB.SCM(SCH_1):PAGE16
    U5   E7 PLLAVDD_E7 AST2600A3GP-AST2600A3-GP,SMLF,A   I188 @SCM_LIB.SCM(SCH_1):PAGE16
    U5   F7 PLLAVDD_F7 AST2600A3GP-AST2600A3-GP,SMLF,A   I188 @SCM_LIB.SCM(SCH_1):PAGE16
    U5   E9 PLLDVDD_E9 AST2600A3GP-AST2600A3-GP,SMLF,A   I188 @SCM_LIB.SCM(SCH_1):PAGE16
    U5   F9 PLLDVDD_F9 AST2600A3GP-AST2600A3-GP,SMLF,A   I188 @SCM_LIB.SCM(SCH_1):PAGE16

P1V0_STBY_RC_VCC10A @SCM_LIB.SCM(SCH_1):P1V0_STBY_RC_VCC10A
    U5  T10 PE_VCC10A AST2600A3GP-AST2600A3-GP,SMLF,A   I188 @SCM_LIB.SCM(SCH_1):PAGE16
    L6    2      2 Q_INDUCTOR_SMLF-BLM18PG121SN1DA   I124 @SCM_LIB.SCM(SCH_1):PAGE17
   C50    1      A Q_CAP_0402-0.1UF,25V,10%,X7R,CA   I126 @SCM_LIB.SCM(SCH_1):PAGE17
   C47    1      A Q_CAP_C0402-1UF,25V,10%,X6S,CHA   I128 @SCM_LIB.SCM(SCH_1):PAGE17

P1V2_AUX @SCM_LIB.SCM(SCH_1):P1V2_AUX
  R795    1      A Q_RES_0402LF-1K,1%,1/16W,CHIP,A   I252 @SCM_LIB.SCM(SCH_1):PAGE15
   C55    1      A Q_CAP_C0603-22UF,6.3V,20%,X6S,A    I23 @SCM_LIB.SCM(SCH_1):PAGE16
   L11    1      1 Q_INDUCTOR_SMLF-BLM18PG121SN1DA    I47 @SCM_LIB.SCM(SCH_1):PAGE16
   C58    1      A Q_CAP_C0402-1UF,25V,10%,X6S,CHA    I52 @SCM_LIB.SCM(SCH_1):PAGE16
   C62    1      A Q_CAP_C0402-1UF,25V,10%,X6S,CHA    I53 @SCM_LIB.SCM(SCH_1):PAGE16
   C66    1      A Q_CAP_0402-0.1UF,25V,10%,X7R,CA    I54 @SCM_LIB.SCM(SCH_1):PAGE16
   C70    1      A Q_CAP_0402-0.1UF,25V,10%,X7R,CA    I57 @SCM_LIB.SCM(SCH_1):PAGE16
   C72    1      A Q_CAP_0402-0.1UF,25V,10%,X7R,CA    I58 @SCM_LIB.SCM(SCH_1):PAGE16
   C74    1      A Q_CAP_0402-0.1UF,25V,10%,X7R,CA    I66 @SCM_LIB.SCM(SCH_1):PAGE16
   C91    1      A Q_CAP_0402-0.1UF,25V,10%,X7R,CA   I151 @SCM_LIB.SCM(SCH_1):PAGE16
   C98    1      A Q_CAP_0402-0.1UF,25V,10%,X7R,CA   I163 @SCM_LIB.SCM(SCH_1):PAGE16
  C103    1      A Q_CAP_0402-0.1UF,25V,10%,X7R,CA   I164 @SCM_LIB.SCM(SCH_1):PAGE16
  C107    1      A Q_CAP_0402-0.1UF,25V,10%,X7R,CA   I165 @SCM_LIB.SCM(SCH_1):PAGE16
  C112    1      A Q_CAP_0402-0.1UF,25V,10%,X7R,CA   I166 @SCM_LIB.SCM(SCH_1):PAGE16
  C117    1      A Q_CAP_C0402-1UF,25V,10%,X6S,CHA   I167 @SCM_LIB.SCM(SCH_1):PAGE16
  C122    1      A Q_CAP_C0402-1UF,25V,10%,X6S,CHA   I168 @SCM_LIB.SCM(SCH_1):PAGE16
  C127    1      A Q_CAP_C0402-1UF,25V,10%,X6S,CHA   I173 @SCM_LIB.SCM(SCH_1):PAGE16
  C129    1      A Q_CAP_C0402-1UF,25V,10%,X6S,CHA   I174 @SCM_LIB.SCM(SCH_1):PAGE16
   C84    1      A Q_CAP_0402-0.1UF,25V,10%,X7R,CA   I179 @SCM_LIB.SCM(SCH_1):PAGE16
   C82    1      A Q_CAP_0402-0.1UF,25V,10%,X7R,CA   I180 @SCM_LIB.SCM(SCH_1):PAGE16
   C76    1      A Q_CAP_0402-0.1UF,25V,10%,X7R,CA   I183 @SCM_LIB.SCM(SCH_1):PAGE16
    U5  K16 IV12D_K16 AST2600A3GP-AST2600A3-GP,SMLF,A   I188 @SCM_LIB.SCM(SCH_1):PAGE16
    U5  K17 IV12D_K17 AST2600A3GP-AST2600A3-GP,SMLF,A   I188 @SCM_LIB.SCM(SCH_1):PAGE16
    U5  K18 IV12D_K18 AST2600A3GP-AST2600A3-GP,SMLF,A   I188 @SCM_LIB.SCM(SCH_1):PAGE16
    U5  K19 IV12D_K19 AST2600A3GP-AST2600A3-GP,SMLF,A   I188 @SCM_LIB.SCM(SCH_1):PAGE16
    U5  L14 IV12D_L14 AST2600A3GP-AST2600A3-GP,SMLF,A   I188 @SCM_LIB.SCM(SCH_1):PAGE16
    U5  L21 IV12D_L21 AST2600A3GP-AST2600A3-GP,SMLF,A   I188 @SCM_LIB.SCM(SCH_1):PAGE16
    U5  M14 IV12D_M14 AST2600A3GP-AST2600A3-GP,SMLF,A   I188 @SCM_LIB.SCM(SCH_1):PAGE16
    U5  M21 IV12D_M21 AST2600A3GP-AST2600A3-GP,SMLF,A   I188 @SCM_LIB.SCM(SCH_1):PAGE16
    U5  N14 IV12D_N14 AST2600A3GP-AST2600A3-GP,SMLF,A   I188 @SCM_LIB.SCM(SCH_1):PAGE16
    U5  N21 IV12D_N21 AST2600A3GP-AST2600A3-GP,SMLF,A   I188 @SCM_LIB.SCM(SCH_1):PAGE16
    U5  P14 IV12D_P14 AST2600A3GP-AST2600A3-GP,SMLF,A   I188 @SCM_LIB.SCM(SCH_1):PAGE16
    U5  P21 IV12D_P21 AST2600A3GP-AST2600A3-GP,SMLF,A   I188 @SCM_LIB.SCM(SCH_1):PAGE16
    U5  R14 IV12D_R14 AST2600A3GP-AST2600A3-GP,SMLF,A   I188 @SCM_LIB.SCM(SCH_1):PAGE16
    U5  R21 IV12D_R21 AST2600A3GP-AST2600A3-GP,SMLF,A   I188 @SCM_LIB.SCM(SCH_1):PAGE16
    U5  T14 IV12D_T14 AST2600A3GP-AST2600A3-GP,SMLF,A   I188 @SCM_LIB.SCM(SCH_1):PAGE16
    U5  T21 IV12D_T21 AST2600A3GP-AST2600A3-GP,SMLF,A   I188 @SCM_LIB.SCM(SCH_1):PAGE16
    U5  U15 IV12D_U15 AST2600A3GP-AST2600A3-GP,SMLF,A   I188 @SCM_LIB.SCM(SCH_1):PAGE16
    U5  U16 IV12D_U16 AST2600A3GP-AST2600A3-GP,SMLF,A   I188 @SCM_LIB.SCM(SCH_1):PAGE16
    U5  U17 IV12D_U17 AST2600A3GP-AST2600A3-GP,SMLF,A   I188 @SCM_LIB.SCM(SCH_1):PAGE16
    U5  U18 IV12D_U18 AST2600A3GP-AST2600A3-GP,SMLF,A   I188 @SCM_LIB.SCM(SCH_1):PAGE16
    U5   G6 MVDD_G6 AST2600A3GP-AST2600A3-GP,SMLF,A   I188 @SCM_LIB.SCM(SCH_1):PAGE16
    U5   H6 MVDD_H6 AST2600A3GP-AST2600A3-GP,SMLF,A   I188 @SCM_LIB.SCM(SCH_1):PAGE16
    U5   J6 MVDD_J6 AST2600A3GP-AST2600A3-GP,SMLF,A   I188 @SCM_LIB.SCM(SCH_1):PAGE16
    U5   K6 MVDD_K6 AST2600A3GP-AST2600A3-GP,SMLF,A   I188 @SCM_LIB.SCM(SCH_1):PAGE16
    U5   L6 MVDD_L6 AST2600A3GP-AST2600A3-GP,SMLF,A   I188 @SCM_LIB.SCM(SCH_1):PAGE16
    U5   P6 MVDD_P6 AST2600A3GP-AST2600A3-GP,SMLF,A   I188 @SCM_LIB.SCM(SCH_1):PAGE16
    U5   R6 MVDD_R6 AST2600A3GP-AST2600A3-GP,SMLF,A   I188 @SCM_LIB.SCM(SCH_1):PAGE16
    U5   T6 MVDD_T6 AST2600A3GP-AST2600A3-GP,SMLF,A   I188 @SCM_LIB.SCM(SCH_1):PAGE16
  R280    1      A Q_RES_0402LF-0,5%,1/16W,EMPTY,A    I94 @SCM_LIB.SCM(SCH_1):PAGE17
  R278    1      A Q_RES_0402LF-0,5%,1/16W,EMPTY,A   I101 @SCM_LIB.SCM(SCH_1):PAGE17
  R782    1      A Q_RES_0402LF-0,5%,1/16W,EMPTY,A   I264 @SCM_LIB.SCM(SCH_1):PAGE17
  R784    1      A Q_RES_0402LF-0,5%,1/16W,EMPTY,A   I267 @SCM_LIB.SCM(SCH_1):PAGE17
    L2    1      1 Q_INDUCTOR_SMLF-BLM18PG121SN1DA   I272 @SCM_LIB.SCM(SCH_1):PAGE17
    C1    1      A Q_CAP_C0603-4.7UF,25V,10%,X6S,A     I4 @SCM_LIB.SCM(SCH_1):PAGE20
    C2    1      A Q_CAP_C0402-1UF,25V,10%,X6S,CHA     I5 @SCM_LIB.SCM(SCH_1):PAGE20
    C3    1      A Q_CAP_C0402-1UF,25V,10%,X6S,CHA     I6 @SCM_LIB.SCM(SCH_1):PAGE20
    C4    1      A Q_CAP_C0402-1UF,25V,10%,X6S,CHA     I7 @SCM_LIB.SCM(SCH_1):PAGE20
    C5    1      A Q_CAP_C0402-1UF,25V,10%,X6S,CHA    I23 @SCM_LIB.SCM(SCH_1):PAGE20
    C7    1      A Q_CAP_0402-0.1UF,25V,10%,X7R,CA    I24 @SCM_LIB.SCM(SCH_1):PAGE20
    C9    1      A Q_CAP_0402-100PF,50V,5%,NPO,CHA    I25 @SCM_LIB.SCM(SCH_1):PAGE20
  R324    1      A Q_RES_0402LF-1K,1%,1/16W,CHIP,A    I28 @SCM_LIB.SCM(SCH_1):PAGE20
  C169    1      A Q_CAP_C0402-0.01UF,50V,10%,EMPA    I34 @SCM_LIB.SCM(SCH_1):PAGE20
  C229    2      B Q_CAP_0402-0.22UF,16V,10%,EMPTA   I107 @SCM_LIB.SCM(SCH_1):PAGE20
    R9    2      B Q_RES_0402LF-4.7K,1%,1/16W,CHIA   I111 @SCM_LIB.SCM(SCH_1):PAGE20
   C16    1      A Q_CAP_C0402-10UF,6.3V,20%,X6S,A   I113 @SCM_LIB.SCM(SCH_1):PAGE20
  R375    2      B Q_RES_0402LF-120,1%,1/16W,EMPTA   I115 @SCM_LIB.SCM(SCH_1):PAGE20
  R374    2      B Q_RES_0402LF-120,1%,1/16W,CHIPA   I127 @SCM_LIB.SCM(SCH_1):PAGE20
  R373    2      B Q_RES_0402LF-120,1%,1/16W,CHIPA   I128 @SCM_LIB.SCM(SCH_1):PAGE20
  R372    2      B Q_RES_0402LF-120,1%,1/16W,CHIPA   I129 @SCM_LIB.SCM(SCH_1):PAGE20
  R371    2      B Q_RES_0402LF-120,1%,1/16W,CHIPA   I130 @SCM_LIB.SCM(SCH_1):PAGE20
  R370    2      B Q_RES_0402LF-120,1%,1/16W,CHIPA   I131 @SCM_LIB.SCM(SCH_1):PAGE20
  R369    2      B Q_RES_0402LF-120,1%,1/16W,CHIPA   I132 @SCM_LIB.SCM(SCH_1):PAGE20
   C15    1      A Q_CAP_C0402-10UF,6.3V,20%,X6S,A   I134 @SCM_LIB.SCM(SCH_1):PAGE20
  R368    2      B Q_RES_0402LF-120,1%,1/16W,CHIPA   I135 @SCM_LIB.SCM(SCH_1):PAGE20
  R367    2      B Q_RES_0402LF-120,1%,1/16W,CHIPA   I136 @SCM_LIB.SCM(SCH_1):PAGE20
  R366    2      B Q_RES_0402LF-120,1%,1/16W,CHIPA   I137 @SCM_LIB.SCM(SCH_1):PAGE20
  R365    2      B Q_RES_0402LF-120,1%,1/16W,CHIPA   I138 @SCM_LIB.SCM(SCH_1):PAGE20
  R364    2      B Q_RES_0402LF-120,1%,1/16W,CHIPA   I165 @SCM_LIB.SCM(SCH_1):PAGE20
  R363    2      B Q_RES_0402LF-120,1%,1/16W,CHIPA   I166 @SCM_LIB.SCM(SCH_1):PAGE20
  R361    2      B Q_RES_0402LF-120,1%,1/16W,CHIPA   I167 @SCM_LIB.SCM(SCH_1):PAGE20
  R362    2      B Q_RES_0402LF-120,1%,1/16W,CHIPA   I168 @SCM_LIB.SCM(SCH_1):PAGE20
  R360    2      B Q_RES_0402LF-120,1%,1/16W,CHIPA   I169 @SCM_LIB.SCM(SCH_1):PAGE20
  R359    2      B Q_RES_0402LF-120,1%,1/16W,CHIPA   I170 @SCM_LIB.SCM(SCH_1):PAGE20
  R358    2      B Q_RES_0402LF-120,1%,1/16W,CHIPA   I178 @SCM_LIB.SCM(SCH_1):PAGE20
  R357    2      B Q_RES_0402LF-120,1%,1/16W,CHIPA   I179 @SCM_LIB.SCM(SCH_1):PAGE20
  R356    2      B Q_RES_0402LF-120,1%,1/16W,CHIPA   I180 @SCM_LIB.SCM(SCH_1):PAGE20
  R354    2      B Q_RES_0402LF-120,1%,1/16W,CHIPA   I181 @SCM_LIB.SCM(SCH_1):PAGE20
  R355    2      B Q_RES_0402LF-120,1%,1/16W,CHIPA   I182 @SCM_LIB.SCM(SCH_1):PAGE20
  R353    2      B Q_RES_0402LF-120,1%,1/16W,CHIPA   I183 @SCM_LIB.SCM(SCH_1):PAGE20
  R352    2      B Q_RES_0402LF-120,1%,1/16W,CHIPA   I184 @SCM_LIB.SCM(SCH_1):PAGE20
   C13    1      A Q_CAP_0402-0.1UF,25V,10%,X7R,CA   I186 @SCM_LIB.SCM(SCH_1):PAGE20
   C14    1      A Q_CAP_0402-0.1UF,25V,10%,X7R,CA   I187 @SCM_LIB.SCM(SCH_1):PAGE20
   C17    1      A Q_CAP_0402-0.1UF,25V,10%,X7R,CA   I190 @SCM_LIB.SCM(SCH_1):PAGE20
   C18    1      A Q_CAP_0402-0.1UF,25V,10%,X7R,CA   I192 @SCM_LIB.SCM(SCH_1):PAGE20
  R351    2      B Q_RES_0402LF-120,1%,1/16W,CHIPA   I194 @SCM_LIB.SCM(SCH_1):PAGE20
    U1   B3   VDD0 K4A8G165WCBCTD-K4A8G165WC-BCTDA   I196 @SCM_LIB.SCM(SCH_1):PAGE20
    U1   B9   VDD1 K4A8G165WCBCTD-K4A8G165WC-BCTDA   I196 @SCM_LIB.SCM(SCH_1):PAGE20
    U1   D1   VDD2 K4A8G165WCBCTD-K4A8G165WC-BCTDA   I196 @SCM_LIB.SCM(SCH_1):PAGE20
    U1   G7   VDD3 K4A8G165WCBCTD-K4A8G165WC-BCTDA   I196 @SCM_LIB.SCM(SCH_1):PAGE20
    U1   J1   VDD4 K4A8G165WCBCTD-K4A8G165WC-BCTDA   I196 @SCM_LIB.SCM(SCH_1):PAGE20
    U1   J9   VDD5 K4A8G165WCBCTD-K4A8G165WC-BCTDA   I196 @SCM_LIB.SCM(SCH_1):PAGE20
    U1   L1   VDD6 K4A8G165WCBCTD-K4A8G165WC-BCTDA   I196 @SCM_LIB.SCM(SCH_1):PAGE20
    U1   L9   VDD7 K4A8G165WCBCTD-K4A8G165WC-BCTDA   I196 @SCM_LIB.SCM(SCH_1):PAGE20
    U1   R1   VDD8 K4A8G165WCBCTD-K4A8G165WC-BCTDA   I196 @SCM_LIB.SCM(SCH_1):PAGE20
    U1   T9   VDD9 K4A8G165WCBCTD-K4A8G165WC-BCTDA   I196 @SCM_LIB.SCM(SCH_1):PAGE20
    U1   A1  VDDQ0 K4A8G165WCBCTD-K4A8G165WC-BCTDA   I196 @SCM_LIB.SCM(SCH_1):PAGE20
    U1   A9  VDDQ1 K4A8G165WCBCTD-K4A8G165WC-BCTDA   I196 @SCM_LIB.SCM(SCH_1):PAGE20
    U1   C1  VDDQ2 K4A8G165WCBCTD-K4A8G165WC-BCTDA   I196 @SCM_LIB.SCM(SCH_1):PAGE20
    U1   D9  VDDQ3 K4A8G165WCBCTD-K4A8G165WC-BCTDA   I196 @SCM_LIB.SCM(SCH_1):PAGE20
    U1   F2  VDDQ4 K4A8G165WCBCTD-K4A8G165WC-BCTDA   I196 @SCM_LIB.SCM(SCH_1):PAGE20
    U1   F8  VDDQ5 K4A8G165WCBCTD-K4A8G165WC-BCTDA   I196 @SCM_LIB.SCM(SCH_1):PAGE20
    U1   G1  VDDQ6 K4A8G165WCBCTD-K4A8G165WC-BCTDA   I196 @SCM_LIB.SCM(SCH_1):PAGE20
    U1   G9  VDDQ7 K4A8G165WCBCTD-K4A8G165WC-BCTDA   I196 @SCM_LIB.SCM(SCH_1):PAGE20
    U1   J2  VDDQ8 K4A8G165WCBCTD-K4A8G165WC-BCTDA   I196 @SCM_LIB.SCM(SCH_1):PAGE20
    U1   J8  VDDQ9 K4A8G165WCBCTD-K4A8G165WC-BCTDA   I196 @SCM_LIB.SCM(SCH_1):PAGE20
  C225    1      A Q_CAP_0402-0.1UF,25V,10%,X7R,CA   I197 @SCM_LIB.SCM(SCH_1):PAGE20
  C222    1      A Q_CAP_0402-0.1UF,25V,10%,X7R,CA   I198 @SCM_LIB.SCM(SCH_1):PAGE20
  C221    1      A Q_CAP_0402-0.1UF,25V,10%,X7R,CA   I199 @SCM_LIB.SCM(SCH_1):PAGE20
  PU41   12   VOUT NB695GDZ-NB695GD-Z,SMLF,IC,AL0A    I15 @SCM_LIB.SCM(SCH_1):PAGE55
  PL31    2      2 Q_INDUCTOR_SMLF-1UH,IND,CV-10BA    I21 @SCM_LIB.SCM(SCH_1):PAGE55
 PC255    1      A Q_CAP_0402-0.1UF,25V,10%,X7R,CA    I23 @SCM_LIB.SCM(SCH_1):PAGE55
 PC256    1      A Q_CAP_0805-22UF,4V,20%,X6S,TMPA    I24 @SCM_LIB.SCM(SCH_1):PAGE55
 PC257    1      A Q_CAP_0805-22UF,4V,20%,X6S,TMPA    I25 @SCM_LIB.SCM(SCH_1):PAGE55
 PC258    1      A Q_CAP_0805-22UF,4V,20%,X6S,TMPA    I28 @SCM_LIB.SCM(SCH_1):PAGE55
 PC259    1      A Q_CAP_0805-22UF,4V,20%,X6S,TMPA    I29 @SCM_LIB.SCM(SCH_1):PAGE55
  C131    1      A Q_CAP_C0603-22UF,6.3V,20%,X6S,A   I192 @SCM_LIB.SCM(SCH_1):PAGE16
  C132    1      A Q_CAP_C0603-22UF,6.3V,20%,X6S,A   I193 @SCM_LIB.SCM(SCH_1):PAGE16

P1V2_AUX_MODE @SCM_LIB.SCM(SCH_1):P1V2_AUX_MODE
 PR496    1      A Q_RES_0402LF-150K,1%,1/16W,CHIA     I6 @SCM_LIB.SCM(SCH_1):PAGE55
  PU41    7   MODE NB695GDZ-NB695GD-Z,SMLF,IC,AL0A    I15 @SCM_LIB.SCM(SCH_1):PAGE55

P1V2_AUX_VCC @SCM_LIB.SCM(SCH_1):P1V2_AUX_VCC
 PC250    1      A Q_CAP_C0402-1UF,25V,10%,X6S,CHA     I7 @SCM_LIB.SCM(SCH_1):PAGE55
 PR539    2      B Q_RES_0402LF-5.1,5%,1/16W,CHIPA     I8 @SCM_LIB.SCM(SCH_1):PAGE55
  PU41   10    3V3 NB695GDZ-NB695GD-Z,SMLF,IC,AL0A    I15 @SCM_LIB.SCM(SCH_1):PAGE55
  PU41    6    LP# NB695GDZ-NB695GD-Z,SMLF,IC,AL0A    I15 @SCM_LIB.SCM(SCH_1):PAGE55

P1V2_P1V0_I3C_VDDL1 @SCM_LIB.SCM(SCH_1):P1V2_P1V0_I3C_VDDL1
  R194    1      A Q_RES_0402LF-1K,1%,1/16W,CHIP,A   I171 @SCM_LIB.SCM(SCH_1):PAGE14
  R195    1      A Q_RES_0402LF-1K,1%,1/16W,CHIP,A   I172 @SCM_LIB.SCM(SCH_1):PAGE14
  R190    1      A Q_RES_0402LF-1K,1%,1/16W,CHIP,A   I173 @SCM_LIB.SCM(SCH_1):PAGE14
  R191    1      A Q_RES_0402LF-1K,1%,1/16W,CHIP,A   I174 @SCM_LIB.SCM(SCH_1):PAGE14
    U5  V22 I3CVDDL1 AST2600A3GP-AST2600A3-GP,SMLF,A   I188 @SCM_LIB.SCM(SCH_1):PAGE16
  R279    2      B Q_RES_0402LF-0,5%,1/16W,CHIP,CA    I95 @SCM_LIB.SCM(SCH_1):PAGE17
  C139    1      A Q_CAP_0402-0.1UF,25V,10%,X7R,CA    I98 @SCM_LIB.SCM(SCH_1):PAGE17
  R278    2      B Q_RES_0402LF-0,5%,1/16W,EMPTY,A   I101 @SCM_LIB.SCM(SCH_1):PAGE17
  R188    1      A Q_RES_0402LF-1K,1%,1/16W,CHIP,A   I183 @SCM_LIB.SCM(SCH_1):PAGE14
  R189    1      A Q_RES_0402LF-1K,1%,1/16W,CHIP,A   I188 @SCM_LIB.SCM(SCH_1):PAGE14
  R196    1      A Q_RES_0402LF-1K,1%,1/16W,CHIP,A   I189 @SCM_LIB.SCM(SCH_1):PAGE14
  R197    1      A Q_RES_0402LF-1K,1%,1/16W,CHIP,A   I190 @SCM_LIB.SCM(SCH_1):PAGE14

P1V2_P1V0_I3C_VDDL2 @SCM_LIB.SCM(SCH_1):P1V2_P1V0_I3C_VDDL2
    U5  U21 I3CVDDL2 AST2600A3GP-AST2600A3-GP,SMLF,A   I188 @SCM_LIB.SCM(SCH_1):PAGE16
  R281    2      B Q_RES_0402LF-0,5%,1/16W,CHIP,CA    I92 @SCM_LIB.SCM(SCH_1):PAGE17
  R280    2      B Q_RES_0402LF-0,5%,1/16W,EMPTY,A    I94 @SCM_LIB.SCM(SCH_1):PAGE17
  C140    1      A Q_CAP_0402-0.1UF,25V,10%,X7R,CA    I97 @SCM_LIB.SCM(SCH_1):PAGE17

P1V2_SENSOR @SCM_LIB.SCM(SCH_1):P1V2_SENSOR
  C309    1      A Q_CAP_0402-0.1UF,25V,10%,X7R,CA   I247 @SCM_LIB.SCM(SCH_1):PAGE15
  R795    2      B Q_RES_0402LF-1K,1%,1/16W,CHIP,A   I252 @SCM_LIB.SCM(SCH_1):PAGE15
    U5 AB18 ADC6||GPIT6 AST2600A3GP-AST2600A3-GP,SMLF,A   I350 @SCM_LIB.SCM(SCH_1):PAGE15

P1V2_STBY_MVDD_CK @SCM_LIB.SCM(SCH_1):P1V2_STBY_MVDD_CK
   C63    1      A Q_CAP_0402-2200PF,50V,10%,X7R,A    I46 @SCM_LIB.SCM(SCH_1):PAGE16
   L11    2      2 Q_INDUCTOR_SMLF-BLM18PG121SN1DA    I47 @SCM_LIB.SCM(SCH_1):PAGE16
   C67    1      A Q_CAP_C0402-1UF,25V,10%,X6S,CHA    I48 @SCM_LIB.SCM(SCH_1):PAGE16
   C71    1      A Q_CAP_0402-0.1UF,25V,10%,X7R,CA    I49 @SCM_LIB.SCM(SCH_1):PAGE16
   C73    1      A Q_CAP_0402-0.1UF,25V,10%,X7R,CA    I51 @SCM_LIB.SCM(SCH_1):PAGE16
    U5   M6 MVDD_CK AST2600A3GP-AST2600A3-GP,SMLF,A   I188 @SCM_LIB.SCM(SCH_1):PAGE16

P1V8_AUX @SCM_LIB.SCM(SCH_1):P1V8_AUX
  R154    1      A Q_RES_0402LF-0,5%,1/16W,EMPTY,A     I3 @SCM_LIB.SCM(SCH_1):PAGE13
  R208    1      A Q_RES_0402LF-0,5%,1/16W,EMPTY,A     I2 @SCM_LIB.SCM(SCH_1):PAGE15
  R214    1      A Q_RES_0402LF-0,5%,1/16W,EMPTY,A    I32 @SCM_LIB.SCM(SCH_1):PAGE15
    L3    1      1 Q_INDUCTOR_SMLF-BLM18PG121SN1DA    I65 @SCM_LIB.SCM(SCH_1):PAGE15
  R793    1      A Q_RES_0402LF-665,1%,1/16W,CHIPA   I244 @SCM_LIB.SCM(SCH_1):PAGE15
   L10    1      1 Q_INDUCTOR_SMLF-BLM18PG121SN1DA    I24 @SCM_LIB.SCM(SCH_1):PAGE16
   C89    1      A Q_CAP_0402-0.1UF,25V,10%,X7R,CA   I118 @SCM_LIB.SCM(SCH_1):PAGE16
   C95    1      A Q_CAP_0402-0.1UF,25V,10%,X7R,CA   I119 @SCM_LIB.SCM(SCH_1):PAGE16
  C102    1      A Q_CAP_0402-0.1UF,25V,10%,X7R,CA   I126 @SCM_LIB.SCM(SCH_1):PAGE16
  C106    1      A Q_CAP_C0402-1UF,25V,10%,X6S,CHA   I127 @SCM_LIB.SCM(SCH_1):PAGE16
  C111    1      A Q_CAP_C0402-1UF,25V,10%,X6S,CHA   I128 @SCM_LIB.SCM(SCH_1):PAGE16
  C116    1      A Q_CAP_C0402-1UF,25V,10%,X6S,CHA   I129 @SCM_LIB.SCM(SCH_1):PAGE16
  C121    1      A Q_CAP_C0603-22UF,6.3V,20%,X6S,A   I131 @SCM_LIB.SCM(SCH_1):PAGE16
  C126    1      A Q_CAP_C0603-22UF,6.3V,20%,X6S,A   I143 @SCM_LIB.SCM(SCH_1):PAGE16
   C87    1      A Q_CAP_0402-0.1UF,25V,10%,X7R,CA   I147 @SCM_LIB.SCM(SCH_1):PAGE16
   C93    1      A Q_CAP_0402-0.1UF,25V,10%,X7R,CA   I148 @SCM_LIB.SCM(SCH_1):PAGE16
  C100    1      A Q_CAP_0402-0.1UF,25V,10%,X7R,CA   I152 @SCM_LIB.SCM(SCH_1):PAGE16
  C105    1      A Q_CAP_0402-0.1UF,25V,10%,X7R,CA   I153 @SCM_LIB.SCM(SCH_1):PAGE16
  C109    1      A Q_CAP_0402-0.1UF,25V,10%,X7R,CA   I156 @SCM_LIB.SCM(SCH_1):PAGE16
  C114    1      A Q_CAP_C0402-1UF,25V,10%,X6S,CHA   I158 @SCM_LIB.SCM(SCH_1):PAGE16
  C119    1      A Q_CAP_C0402-1UF,25V,10%,X6S,CHA   I159 @SCM_LIB.SCM(SCH_1):PAGE16
  C124    1      A Q_CAP_C0603-22UF,6.3V,20%,X6S,A   I169 @SCM_LIB.SCM(SCH_1):PAGE16
    U5   H8 PV18D_H8 AST2600A3GP-AST2600A3-GP,SMLF,A   I188 @SCM_LIB.SCM(SCH_1):PAGE16
    U5   J8 PV18D_J8 AST2600A3GP-AST2600A3-GP,SMLF,A   I188 @SCM_LIB.SCM(SCH_1):PAGE16
    U5  N12 PV18D_N12 AST2600A3GP-AST2600A3-GP,SMLF,A   I188 @SCM_LIB.SCM(SCH_1):PAGE16
    U5  P12 PV18D_P12 AST2600A3GP-AST2600A3-GP,SMLF,A   I188 @SCM_LIB.SCM(SCH_1):PAGE16
    U5  R12 PV18D_R12 AST2600A3GP-AST2600A3-GP,SMLF,A   I188 @SCM_LIB.SCM(SCH_1):PAGE16
    U5  H12 PV18D_RGM_H12 AST2600A3GP-AST2600A3-GP,SMLF,A   I188 @SCM_LIB.SCM(SCH_1):PAGE16
    U5  J12 PV18D_RGM_J12 AST2600A3GP-AST2600A3-GP,SMLF,A   I188 @SCM_LIB.SCM(SCH_1):PAGE16
    U5  L13 PV18D_SLI_L13 AST2600A3GP-AST2600A3-GP,SMLF,A   I188 @SCM_LIB.SCM(SCH_1):PAGE16
    U5  M13 PV18D_SLI_M13 AST2600A3GP-AST2600A3-GP,SMLF,A   I188 @SCM_LIB.SCM(SCH_1):PAGE16
    U5  N13 PV18D_SLI_N13 AST2600A3GP-AST2600A3-GP,SMLF,A   I188 @SCM_LIB.SCM(SCH_1):PAGE16
    U5  P13 PV18D_SLI_P13 AST2600A3GP-AST2600A3-GP,SMLF,A   I188 @SCM_LIB.SCM(SCH_1):PAGE16
    U5  R13 PV18D_SLI_R13 AST2600A3GP-AST2600A3-GP,SMLF,A   I188 @SCM_LIB.SCM(SCH_1):PAGE16
    U5  T13 PV18D_SLI_T13 AST2600A3GP-AST2600A3-GP,SMLF,A   I188 @SCM_LIB.SCM(SCH_1):PAGE16
    U5  U13 PV18D_SLI_U13 AST2600A3GP-AST2600A3-GP,SMLF,A   I188 @SCM_LIB.SCM(SCH_1):PAGE16
    U5  V13 PV18D_SLI_V13 AST2600A3GP-AST2600A3-GP,SMLF,A   I188 @SCM_LIB.SCM(SCH_1):PAGE16
    U5  W13 PV18D_SLI_W13 AST2600A3GP-AST2600A3-GP,SMLF,A   I188 @SCM_LIB.SCM(SCH_1):PAGE16
    U5  W14 PV18D_SLI_W14 AST2600A3GP-AST2600A3-GP,SMLF,A   I188 @SCM_LIB.SCM(SCH_1):PAGE16
    U5   U6 PV18D_U6 AST2600A3GP-AST2600A3-GP,SMLF,A   I188 @SCM_LIB.SCM(SCH_1):PAGE16
    U5   V6 PV18D_V6 AST2600A3GP-AST2600A3-GP,SMLF,A   I188 @SCM_LIB.SCM(SCH_1):PAGE16
    L5    1      1 Q_INDUCTOR_SMLF-BLM18PG121SN1DA   I120 @SCM_LIB.SCM(SCH_1):PAGE17
  R232    1      A Q_RES_0402LF-0,5%,1/16W,EMPTY,A   I136 @SCM_LIB.SCM(SCH_1):PAGE17
   L14    1      1 Q_INDUCTOR_SMLF-BLM18PG121SN1DA   I154 @SCM_LIB.SCM(SCH_1):PAGE17
   L16    1      1 Q_INDUCTOR_SMLF-BLM18PG121SN1DA   I166 @SCM_LIB.SCM(SCH_1):PAGE17
  R783    1      A Q_RES_0402LF-0,5%,1/16W,CHIP,CA   I260 @SCM_LIB.SCM(SCH_1):PAGE17
  R781    1      A Q_RES_0402LF-0,5%,1/16W,EMPTY,A   I263 @SCM_LIB.SCM(SCH_1):PAGE17
    Q5    4      4 MOSFET_NCH_4D1S-NTGS4141NT1G,SA   I274 @SCM_LIB.SCM(SCH_1):PAGE17
  R645    1      A Q_RES_0603LF-0,5%,1/10W,EMPTY,A   I278 @SCM_LIB.SCM(SCH_1):PAGE17
   U41    1  VOUT1 RT9059GQW-RT9059GQW,SMLF,IC,ALA    I96 @SCM_LIB.SCM(SCH_1):PAGE54
   U41    2  VOUT2 RT9059GQW-RT9059GQW,SMLF,IC,ALA    I96 @SCM_LIB.SCM(SCH_1):PAGE54
   U41    3  VOUT3 RT9059GQW-RT9059GQW,SMLF,IC,ALA    I96 @SCM_LIB.SCM(SCH_1):PAGE54
  R831    1      A Q_RES_0402LF-15K,1%,1/16W,CHIPA    I98 @SCM_LIB.SCM(SCH_1):PAGE54
  C142    1      A Q_CAP_C0805-10UF,25V,10%,X6S,CA   I104 @SCM_LIB.SCM(SCH_1):PAGE54
  C294    1      A Q_CAP_0402-0.1UF,25V,10%,X7R,CA   I105 @SCM_LIB.SCM(SCH_1):PAGE54
  R856    1      A Q_RES_0402LF-4.7K,1%,1/16W,CHIA   I220 @SCM_LIB.SCM(SCH_1):PAGE14
  R854    1      A Q_RES_0402LF-4.7K,1%,1/16W,EMPA   I221 @SCM_LIB.SCM(SCH_1):PAGE14
  R858    1      A Q_RES_0402LF-4.7K,1%,1/16W,CHIA   I222 @SCM_LIB.SCM(SCH_1):PAGE14
  R885    1      A Q_RES_0402LF-4.7K,1%,1/16W,CHIA   I231 @SCM_LIB.SCM(SCH_1):PAGE14

P1V8_BMC_USB2AV18 @SCM_LIB.SCM(SCH_1):P1V8_BMC_USB2AV18
    L3    2      2 Q_INDUCTOR_SMLF-BLM18PG121SN1DA    I65 @SCM_LIB.SCM(SCH_1):PAGE15
   C41    1      A Q_CAP_0402-0.1UF,25V,10%,X7R,CA    I68 @SCM_LIB.SCM(SCH_1):PAGE15
    U5  K10 USB2AV18 AST2600A3GP-AST2600A3-GP,SMLF,A   I350 @SCM_LIB.SCM(SCH_1):PAGE15
   C40    1      A Q_CAP_C0603-4.7UF,25V,10%,X6S,A   I368 @SCM_LIB.SCM(SCH_1):PAGE15

P1V8_SENSOR @SCM_LIB.SCM(SCH_1):P1V8_SENSOR
  C307    1      A Q_CAP_0402-0.1UF,25V,10%,X7R,CA   I240 @SCM_LIB.SCM(SCH_1):PAGE15
  R794    1      A Q_RES_0402LF-2K,1%,1/16W,CHIP,A   I242 @SCM_LIB.SCM(SCH_1):PAGE15
  R793    2      B Q_RES_0402LF-665,1%,1/16W,CHIPA   I244 @SCM_LIB.SCM(SCH_1):PAGE15
    U5 AC19 ADC4||GPIT4 AST2600A3GP-AST2600A3-GP,SMLF,A   I350 @SCM_LIB.SCM(SCH_1):PAGE15

P1V8_STBY_AVDDPLL @SCM_LIB.SCM(SCH_1):P1V8_STBY_AVDDPLL
    U5   N5 AVDDPLL AST2600A3GP-AST2600A3-GP,SMLF,A   I188 @SCM_LIB.SCM(SCH_1):PAGE16
   C49    1      A Q_CAP_0402-0.1UF,25V,10%,X7R,CA   I118 @SCM_LIB.SCM(SCH_1):PAGE17
    L5    2      2 Q_INDUCTOR_SMLF-BLM18PG121SN1DA   I120 @SCM_LIB.SCM(SCH_1):PAGE17
   C46    1      A Q_CAP_C0402-1UF,25V,10%,X6S,CHA   I122 @SCM_LIB.SCM(SCH_1):PAGE17

P1V8_STBY_DP_VCC18A @SCM_LIB.SCM(SCH_1):P1V8_STBY_DP_VCC18A
    U5   V8 DP_VCC18A AST2600A3GP-AST2600A3-GP,SMLF,A   I188 @SCM_LIB.SCM(SCH_1):PAGE16
  C130    1      A Q_CAP_0402-0.1UF,25V,10%,X7R,CA   I163 @SCM_LIB.SCM(SCH_1):PAGE17
  C128    1      A Q_CAP_C0402-1UF,25V,10%,X6S,CHA   I165 @SCM_LIB.SCM(SCH_1):PAGE17
   L16    2      2 Q_INDUCTOR_SMLF-BLM18PG121SN1DA   I166 @SCM_LIB.SCM(SCH_1):PAGE17

P1V8_STBY_PE_VCC18A @SCM_LIB.SCM(SCH_1):P1V8_STBY_PE_VCC18A
   L10    2      2 Q_INDUCTOR_SMLF-BLM18PG121SN1DA    I24 @SCM_LIB.SCM(SCH_1):PAGE16
   C61    1      A Q_CAP_C0402-1UF,25V,10%,X6S,CHA    I55 @SCM_LIB.SCM(SCH_1):PAGE16
   C69    1      A Q_CAP_0402-0.1UF,25V,10%,X7R,CA    I59 @SCM_LIB.SCM(SCH_1):PAGE16
    U5   V9 RC_VCC18A AST2600A3GP-AST2600A3-GP,SMLF,A   I188 @SCM_LIB.SCM(SCH_1):PAGE16

P1V8_STBY_RC_VCC18A @SCM_LIB.SCM(SCH_1):P1V8_STBY_RC_VCC18A
    U5  V10 PE_VCC18A AST2600A3GP-AST2600A3-GP,SMLF,A   I188 @SCM_LIB.SCM(SCH_1):PAGE16
   C81    1      A Q_CAP_0402-0.1UF,25V,10%,X7R,CA   I151 @SCM_LIB.SCM(SCH_1):PAGE17
   C80    1      A Q_CAP_C0402-1UF,25V,10%,X6S,CHA   I153 @SCM_LIB.SCM(SCH_1):PAGE17
   L14    2      2 Q_INDUCTOR_SMLF-BLM18PG121SN1DA   I154 @SCM_LIB.SCM(SCH_1):PAGE17

P2E_GPU_RX_DN @SCM_LIB.SCM(SCH_1):P2E_GPU_RX_DN
   GF1  A66 PCIE_HPM_RXN_2 FCONN168_ME1016810202011_SCM-FA   I553 @SCM_LIB.SCM(SCH_1):PAGE10
    U5  AD3  RCRXN AST2600A3GP-AST2600A3-GP,SMLF,A   I436 @SCM_LIB.SCM(SCH_1):PAGE12

P2E_GPU_RX_DP @SCM_LIB.SCM(SCH_1):P2E_GPU_RX_DP
   GF1  A65 PCIE_HPM_RXP_2 FCONN168_ME1016810202011_SCM-FA   I553 @SCM_LIB.SCM(SCH_1):PAGE10
    U5  AD2  RCRXP AST2600A3GP-AST2600A3-GP,SMLF,A   I436 @SCM_LIB.SCM(SCH_1):PAGE12

P2E_GPU_TX_C_DN @SCM_LIB.SCM(SCH_1):P2E_GPU_TX_C_DN
   GF1  B66 PCIE_HPM_TXN_2 FCONN168_ME1016810202011_SCM-FA   I553 @SCM_LIB.SCM(SCH_1):PAGE10
  C271    2      B Q_CAP_0402-0.1UF,25V,10%,X7R,CA   I429 @SCM_LIB.SCM(SCH_1):PAGE12

P2E_GPU_TX_C_DP @SCM_LIB.SCM(SCH_1):P2E_GPU_TX_C_DP
   GF1  B65 PCIE_HPM_TXP_2 FCONN168_ME1016810202011_SCM-FA   I553 @SCM_LIB.SCM(SCH_1):PAGE10
  C272    2      B Q_CAP_0402-0.1UF,25V,10%,X7R,CA   I428 @SCM_LIB.SCM(SCH_1):PAGE12

P2E_GPU_TX_DN @SCM_LIB.SCM(SCH_1):P2E_GPU_TX_DN
  C271    1      A Q_CAP_0402-0.1UF,25V,10%,X7R,CA   I429 @SCM_LIB.SCM(SCH_1):PAGE12
    U5  AF2  RCTXP AST2600A3GP-AST2600A3-GP,SMLF,A   I436 @SCM_LIB.SCM(SCH_1):PAGE12

P2E_GPU_TX_DP @SCM_LIB.SCM(SCH_1):P2E_GPU_TX_DP
  C272    1      A Q_CAP_0402-0.1UF,25V,10%,X7R,CA   I428 @SCM_LIB.SCM(SCH_1):PAGE12
    U5  AF3  RCTXN AST2600A3GP-AST2600A3-GP,SMLF,A   I436 @SCM_LIB.SCM(SCH_1):PAGE12

P2E_PCH_RX_DN @SCM_LIB.SCM(SCH_1):P2E_PCH_RX_DN
   GF1  A18 PCIE_BMC_TX_DN FCONN168_ME1016810202011_SCM-FA   I553 @SCM_LIB.SCM(SCH_1):PAGE10
    U5  AF6  PERXN AST2600A3GP-AST2600A3-GP,SMLF,A   I436 @SCM_LIB.SCM(SCH_1):PAGE12

P2E_PCH_RX_DP @SCM_LIB.SCM(SCH_1):P2E_PCH_RX_DP
   GF1  A17 PCIE_BMC_TX_DP FCONN168_ME1016810202011_SCM-FA   I553 @SCM_LIB.SCM(SCH_1):PAGE10
    U5  AF5  PERXP AST2600A3GP-AST2600A3-GP,SMLF,A   I436 @SCM_LIB.SCM(SCH_1):PAGE12

P2E_PCH_TX_C_DN @SCM_LIB.SCM(SCH_1):P2E_PCH_TX_C_DN
   GF1  A21 PCIE_BMC_RX_DN FCONN168_ME1016810202011_SCM-FA   I553 @SCM_LIB.SCM(SCH_1):PAGE10
   C25    2      B Q_CAP_0402-0.1UF,25V,10%,X7R,CA   I153 @SCM_LIB.SCM(SCH_1):PAGE12

P2E_PCH_TX_C_DP @SCM_LIB.SCM(SCH_1):P2E_PCH_TX_C_DP
   GF1  A20 PCIE_BMC_RX_DP FCONN168_ME1016810202011_SCM-FA   I553 @SCM_LIB.SCM(SCH_1):PAGE10
   C24    2      B Q_CAP_0402-0.1UF,25V,10%,X7R,CA   I152 @SCM_LIB.SCM(SCH_1):PAGE12

P2E_PCH_TX_DN @SCM_LIB.SCM(SCH_1):P2E_PCH_TX_DN
   C25    1      A Q_CAP_0402-0.1UF,25V,10%,X7R,CA   I153 @SCM_LIB.SCM(SCH_1):PAGE12
    U5  AE5  PETXN AST2600A3GP-AST2600A3-GP,SMLF,A   I436 @SCM_LIB.SCM(SCH_1):PAGE12

P2E_PCH_TX_DP @SCM_LIB.SCM(SCH_1):P2E_PCH_TX_DP
   C24    1      A Q_CAP_0402-0.1UF,25V,10%,X7R,CA   I152 @SCM_LIB.SCM(SCH_1):PAGE12
    U5  AE4  PETXP AST2600A3GP-AST2600A3-GP,SMLF,A   I436 @SCM_LIB.SCM(SCH_1):PAGE12

P2V5_AUX @SCM_LIB.SCM(SCH_1):P2V5_AUX
  R156    1      A Q_RES_0402LF-0,5%,1/16W,EMPTY,A     I4 @SCM_LIB.SCM(SCH_1):PAGE13
  R791    1      A Q_RES_0402LF-1.69K,1%,1/16W,CHA   I245 @SCM_LIB.SCM(SCH_1):PAGE15
  R780    1      A Q_RES_0402LF-0,5%,1/16W,EMPTY,A   I256 @SCM_LIB.SCM(SCH_1):PAGE17
  R779    1      A Q_RES_0402LF-0,5%,1/16W,CHIP,CA   I259 @SCM_LIB.SCM(SCH_1):PAGE17
    C6    1      A Q_CAP_0402-0.1UF,25V,10%,X7R,CA    I19 @SCM_LIB.SCM(SCH_1):PAGE20
    C8    1      A Q_CAP_0402-0.1UF,25V,10%,X7R,CA    I21 @SCM_LIB.SCM(SCH_1):PAGE20
    U1   B1   VPP0 K4A8G165WCBCTD-K4A8G165WC-BCTDA   I196 @SCM_LIB.SCM(SCH_1):PAGE20
    U1   R9   VPP1 K4A8G165WCBCTD-K4A8G165WC-BCTDA   I196 @SCM_LIB.SCM(SCH_1):PAGE20
   U39    1  VOUT1 RT9059GQW-RT9059GQW,SMLF,IC,ALA    I60 @SCM_LIB.SCM(SCH_1):PAGE53
   U39    2  VOUT2 RT9059GQW-RT9059GQW,SMLF,IC,ALA    I60 @SCM_LIB.SCM(SCH_1):PAGE53
   U39    3  VOUT3 RT9059GQW-RT9059GQW,SMLF,IC,ALA    I60 @SCM_LIB.SCM(SCH_1):PAGE53
  R829    1      A Q_RES_0402LF-25.5K,1%,1/16W,CHA    I62 @SCM_LIB.SCM(SCH_1):PAGE53
  C289    1      A Q_CAP_C0805-10UF,25V,10%,X6S,CA    I69 @SCM_LIB.SCM(SCH_1):PAGE53
  C291    1      A Q_CAP_0402-0.1UF,25V,10%,X7R,CA    I70 @SCM_LIB.SCM(SCH_1):PAGE53

P2V5_SENSOR @SCM_LIB.SCM(SCH_1):P2V5_SENSOR
  C303    1      A Q_CAP_0402-0.1UF,25V,10%,X7R,CA   I235 @SCM_LIB.SCM(SCH_1):PAGE15
  R792    1      A Q_RES_0402LF-2K,1%,1/16W,CHIP,A   I236 @SCM_LIB.SCM(SCH_1):PAGE15
  R791    2      B Q_RES_0402LF-1.69K,1%,1/16W,CHA   I245 @SCM_LIB.SCM(SCH_1):PAGE15
    U5 AD19 ADC3||GPIT3 AST2600A3GP-AST2600A3-GP,SMLF,A   I350 @SCM_LIB.SCM(SCH_1):PAGE15

P3V3_AUX @SCM_LIB.SCM(SCH_1):P3V3_AUX
   R75    1      A Q_RES_0402LF-2K,1%,1/16W,CHIP,A   I110 @SCM_LIB.SCM(SCH_1):PAGE11
   R74    1      A Q_RES_0402LF-2K,1%,1/16W,CHIP,A   I117 @SCM_LIB.SCM(SCH_1):PAGE11
   R73    1      A Q_RES_0402LF-1K,1%,1/16W,EMPTYA   I118 @SCM_LIB.SCM(SCH_1):PAGE11
   R77    1      A Q_RES_0402LF-1K,1%,1/16W,EMPTYA   I128 @SCM_LIB.SCM(SCH_1):PAGE11
   R78    1      A Q_RES_0402LF-2K,1%,1/16W,CHIP,A   I129 @SCM_LIB.SCM(SCH_1):PAGE11
   R79    1      A Q_RES_0402LF-2K,1%,1/16W,CHIP,A   I130 @SCM_LIB.SCM(SCH_1):PAGE11
   R44    1      A Q_RES_0402LF-4.7K,1%,1/16W,EMPA   I175 @SCM_LIB.SCM(SCH_1):PAGE11
   R45    1      A Q_RES_0402LF-4.7K,1%,1/16W,CHIA   I176 @SCM_LIB.SCM(SCH_1):PAGE11
   R68    1      A Q_RES_0402LF-4.7K,1%,1/16W,CHIA   I179 @SCM_LIB.SCM(SCH_1):PAGE11
  R163    1      A Q_RES_0402LF-4.7K,1%,1/16W,CHIA   I212 @SCM_LIB.SCM(SCH_1):PAGE11
  R101    1      A Q_RES_0402LF-4.7K,1%,1/16W,CHIA   I214 @SCM_LIB.SCM(SCH_1):PAGE11
  R161    1      A Q_RES_0402LF-4.7K,1%,1/16W,CHIA   I218 @SCM_LIB.SCM(SCH_1):PAGE11
  R103    1      A Q_RES_0402LF-4.7K,1%,1/16W,CHIA   I219 @SCM_LIB.SCM(SCH_1):PAGE11
   R41    1      A Q_RES_0402LF-10K,1%,1/16W,EMPTA   I225 @SCM_LIB.SCM(SCH_1):PAGE11
   R69    1      A Q_RES_0402LF-4.7K,1%,1/16W,CHIA   I227 @SCM_LIB.SCM(SCH_1):PAGE11
   R76    1      A Q_RES_0402LF-2K,1%,1/16W,CHIP,A   I230 @SCM_LIB.SCM(SCH_1):PAGE11
   R82    1      A Q_RES_0402LF-2K,1%,1/16W,CHIP,A   I232 @SCM_LIB.SCM(SCH_1):PAGE11
  R828    1      A Q_RES_0402LF-4.7K,1%,1/16W,EMPA   I241 @SCM_LIB.SCM(SCH_1):PAGE11
   R81    1      A Q_RES_0402LF-4.7K,1%,1/16W,CHIA   I245 @SCM_LIB.SCM(SCH_1):PAGE11
   R62    1      A Q_RES_0402LF-4.7K,1%,1/16W,CHIA   I350 @SCM_LIB.SCM(SCH_1):PAGE12
  R706    1      A Q_RES_0402LF-4.7K,1%,1/16W,CHIA   I354 @SCM_LIB.SCM(SCH_1):PAGE12
  R155    1      A Q_RES_0402LF-0,5%,1/16W,CHIP,CA     I5 @SCM_LIB.SCM(SCH_1):PAGE13
  R167    1      A Q_RES_0402LF-330,1%,1/16W,CHIPA    I33 @SCM_LIB.SCM(SCH_1):PAGE13
  R238    1      A Q_RES_0402LF-4.7K,1%,1/16W,CHIA   I184 @SCM_LIB.SCM(SCH_1):PAGE13
  R239    1      A Q_RES_0402LF-4.7K,1%,1/16W,CHIA   I185 @SCM_LIB.SCM(SCH_1):PAGE13
  R241    1      A Q_RES_0402LF-4.7K,1%,1/16W,CHIA   I186 @SCM_LIB.SCM(SCH_1):PAGE13
  R240    1      A Q_RES_0402LF-4.7K,1%,1/16W,CHIA   I187 @SCM_LIB.SCM(SCH_1):PAGE13
  R683    1      A Q_RES_0402LF-4.7K,1%,1/16W,CHIA   I188 @SCM_LIB.SCM(SCH_1):PAGE13
   R38    1      A Q_RES_0402LF-4.7K,1%,1/16W,CHIA   I200 @SCM_LIB.SCM(SCH_1):PAGE13
   R61    1      A Q_RES_0402LF-4.7K,1%,1/16W,CHIA   I204 @SCM_LIB.SCM(SCH_1):PAGE13
  R774    1      A Q_RES_0402LF-4.7K,1%,1/16W,CHIA   I213 @SCM_LIB.SCM(SCH_1):PAGE13
  R821    1      A Q_RES_0402LF-4.7K,1%,1/16W,EMPA   I220 @SCM_LIB.SCM(SCH_1):PAGE13
   R55    1      A Q_RES_0402LF-4.7K,1%,1/16W,CHIA   I278 @SCM_LIB.SCM(SCH_1):PAGE13
   R56    1      A Q_RES_0402LF-4.7K,1%,1/16W,CHIA   I279 @SCM_LIB.SCM(SCH_1):PAGE13
  R446    1      A Q_RES_0402LF-4.7K,1%,1/16W,CHIA   I299 @SCM_LIB.SCM(SCH_1):PAGE13
  R452    1      A Q_RES_0402LF-4.7K,1%,1/16W,CHIA   I339 @SCM_LIB.SCM(SCH_1):PAGE13
  R816    1      A Q_RES_0402LF-4.7K,1%,1/16W,CHIA   I353 @SCM_LIB.SCM(SCH_1):PAGE13
  R805    1      A Q_RES_0402LF-4.7K,1%,1/16W,CHIA   I356 @SCM_LIB.SCM(SCH_1):PAGE13
  R686    1      A Q_RES_0402LF-4.7K,1%,1/16W,EMPB   I164 @SCM_LIB.SCM(SCH_1):PAGE14
  R687    1      A Q_RES_0402LF-4.7K,1%,1/16W,EMPB   I166 @SCM_LIB.SCM(SCH_1):PAGE14
  R207    1      A Q_RES_0402LF-0,5%,1/16W,CHIP,CA     I4 @SCM_LIB.SCM(SCH_1):PAGE15
  R213    1      A Q_RES_0402LF-0,5%,1/16W,CHIP,CA    I34 @SCM_LIB.SCM(SCH_1):PAGE15
    L4    1      1 Q_INDUCTOR_SMLF-BLM18PG121SN1DA    I82 @SCM_LIB.SCM(SCH_1):PAGE15
  R717    1      A Q_RES_0402LF-4.7K,1%,1/16W,CHIA   I174 @SCM_LIB.SCM(SCH_1):PAGE15
  R789    1      A Q_RES_0402LF-2.87K,1%,1/16W,CHA   I219 @SCM_LIB.SCM(SCH_1):PAGE15
   L12    1      1 Q_INDUCTOR_SMLF-BLM18PG121SN1DA    I99 @SCM_LIB.SCM(SCH_1):PAGE16
   C88    1      A Q_CAP_0402-0.1UF,25V,10%,X7R,CA   I123 @SCM_LIB.SCM(SCH_1):PAGE16
   C94    1      A Q_CAP_0402-0.1UF,25V,10%,X7R,CA   I124 @SCM_LIB.SCM(SCH_1):PAGE16
  C101    1      A Q_CAP_0402-0.1UF,25V,10%,X7R,CA   I132 @SCM_LIB.SCM(SCH_1):PAGE16
  C110    1      A Q_CAP_C0402-1UF,25V,10%,X6S,CHA   I133 @SCM_LIB.SCM(SCH_1):PAGE16
  C115    1      A Q_CAP_C0402-1UF,25V,10%,X6S,CHA   I135 @SCM_LIB.SCM(SCH_1):PAGE16
    U5  H15 PV33D_H15 AST2600A3GP-AST2600A3-GP,SMLF,A   I188 @SCM_LIB.SCM(SCH_1):PAGE16
    U5  H16 PV33D_H16 AST2600A3GP-AST2600A3-GP,SMLF,A   I188 @SCM_LIB.SCM(SCH_1):PAGE16
    U5  H17 PV33D_H17 AST2600A3GP-AST2600A3-GP,SMLF,A   I188 @SCM_LIB.SCM(SCH_1):PAGE16
    U5  N22 PV33D_N22 AST2600A3GP-AST2600A3-GP,SMLF,A   I188 @SCM_LIB.SCM(SCH_1):PAGE16
    U5  P22 PV33D_P22 AST2600A3GP-AST2600A3-GP,SMLF,A   I188 @SCM_LIB.SCM(SCH_1):PAGE16
    U5  R22 PV33D_R22 AST2600A3GP-AST2600A3-GP,SMLF,A   I188 @SCM_LIB.SCM(SCH_1):PAGE16
    U5  T22 PV33D_T22 AST2600A3GP-AST2600A3-GP,SMLF,A   I188 @SCM_LIB.SCM(SCH_1):PAGE16
    U5  W16 PV33D_W16 AST2600A3GP-AST2600A3-GP,SMLF,A   I188 @SCM_LIB.SCM(SCH_1):PAGE16
    U5  W17 PV33D_W17 AST2600A3GP-AST2600A3-GP,SMLF,A   I188 @SCM_LIB.SCM(SCH_1):PAGE16
    U5  W18 PV33D_W18 AST2600A3GP-AST2600A3-GP,SMLF,A   I188 @SCM_LIB.SCM(SCH_1):PAGE16
    U5  W19 PV33D_W19 AST2600A3GP-AST2600A3-GP,SMLF,A   I188 @SCM_LIB.SCM(SCH_1):PAGE16
  R231    1      A Q_RES_0402LF-0,5%,1/16W,CHIP,CA   I131 @SCM_LIB.SCM(SCH_1):PAGE17
    L9    1      1 Q_INDUCTOR_SMLF-BLM18PG121SN1DB   I142 @SCM_LIB.SCM(SCH_1):PAGE17
    L7    1      1 Q_INDUCTOR_SMLF-BLM18PG121SN1DA   I146 @SCM_LIB.SCM(SCH_1):PAGE17
  R646    2      B Q_RES_0603LF-0,5%,1/10W,EMPTY,A   I279 @SCM_LIB.SCM(SCH_1):PAGE17
  C228    1      A Q_CAP_0402-0.1UF,25V,10%,EMPTYA    I21 @SCM_LIB.SCM(SCH_1):PAGE21
  R662    1      A Q_RES_0402LF-10K,1%,1/16W,EMPTB    I58 @SCM_LIB.SCM(SCH_1):PAGE21
  R663    1      A Q_RES_0402LF-10K,1%,1/16W,EMPTB    I59 @SCM_LIB.SCM(SCH_1):PAGE21
  R661    1      A Q_RES_0402LF-10K,1%,1/16W,EMPTB    I60 @SCM_LIB.SCM(SCH_1):PAGE21
  R660    1      A Q_RES_0402LF-10K,1%,1/16W,EMPTB    I61 @SCM_LIB.SCM(SCH_1):PAGE21
  R658    1      A Q_RES_0402LF-10K,1%,1/16W,EMPTB    I62 @SCM_LIB.SCM(SCH_1):PAGE21
  R657    1      A Q_RES_0402LF-10K,1%,1/16W,EMPTB    I63 @SCM_LIB.SCM(SCH_1):PAGE21
  R659    1      A Q_RES_0402LF-10K,1%,1/16W,EMPTB    I64 @SCM_LIB.SCM(SCH_1):PAGE21
  R656    1      A Q_RES_0402LF-10K,1%,1/16W,EMPTB    I66 @SCM_LIB.SCM(SCH_1):PAGE21
  R655    1      A Q_RES_0402LF-10K,1%,1/16W,EMPTB    I67 @SCM_LIB.SCM(SCH_1):PAGE21
  C235    1      A Q_CAP_0402-0.1UF,25V,10%,EMPTYA    I80 @SCM_LIB.SCM(SCH_1):PAGE21
  C234    1      A Q_CAP_C0603-22UF,10V,20%,EMPTYA    I81 @SCM_LIB.SCM(SCH_1):PAGE21
  C147    1      A Q_CAP_0402-0.1UF,25V,10%,EMPTYA    I17 @SCM_LIB.SCM(SCH_1):PAGE22
   C34    1      A Q_CAP_0402-0.1UF,25V,10%,X7R,CA    I42 @SCM_LIB.SCM(SCH_1):PAGE22
  R710    1      A Q_RES_0402LF-100K,1%,1/16W,CHIA    I55 @SCM_LIB.SCM(SCH_1):PAGE22
  C253    1      A Q_CAP_0402-0.1UF,25V,10%,X7R,CA    I57 @SCM_LIB.SCM(SCH_1):PAGE22
  R124    1      A Q_RES_0402LF-2K,1%,1/16W,CHIP,A    I67 @SCM_LIB.SCM(SCH_1):PAGE22
  R633    1      A Q_RES_0402LF-1K,1%,1/16W,EMPTYA    I81 @SCM_LIB.SCM(SCH_1):PAGE22
  R751    1      A Q_RES_0402LF-2K,1%,1/16W,CHIP,A    I83 @SCM_LIB.SCM(SCH_1):PAGE22
    U6    5    VCC 74LVC2G07DW7-74LVC2G07DW-7,SMLA    I87 @SCM_LIB.SCM(SCH_1):PAGE22
   U13    5    VCC MC74VHC1G07DFT2G-MC74VHC1G07DFA    I89 @SCM_LIB.SCM(SCH_1):PAGE22
  R563    1      A Q_RES_0402LF-4.7K,1%,1/16W,CHIA     I3 @SCM_LIB.SCM(SCH_1):PAGE25
   U44    5    VCC SN74LVC1G07DCKR-SN74LVC1G07DCKA    I61 @SCM_LIB.SCM(SCH_1):PAGE25
  C304    1      A Q_CAP_0402-0.1UF,25V,10%,X7R,CA    I65 @SCM_LIB.SCM(SCH_1):PAGE25
   R12    1      A Q_RES_0402LF-4.7K,1%,1/16W,EMPA     I9 @SCM_LIB.SCM(SCH_1):PAGE26
   R13    1      A Q_RES_0402LF-4.7K,1%,1/16W,EMPA    I11 @SCM_LIB.SCM(SCH_1):PAGE26
   R14    1      A Q_RES_0402LF-4.7K,1%,1/16W,EMPA    I14 @SCM_LIB.SCM(SCH_1):PAGE26
   U19    8    VCC M24128BWDW6TP-M24128-BWDW6TP,SA    I15 @SCM_LIB.SCM(SCH_1):PAGE26
  C192    1      A Q_CAP_0402-0.1UF,25V,10%,X7R,CA    I17 @SCM_LIB.SCM(SCH_1):PAGE26
  R418    1      A Q_RES_0402LF-4.7K,1%,1/16W,EMPA    I40 @SCM_LIB.SCM(SCH_1):PAGE26
  R416    1      A Q_RES_0402LF-4.7K,1%,1/16W,CHIA    I41 @SCM_LIB.SCM(SCH_1):PAGE26
  C191    1      A Q_CAP_0402-0.1UF,25V,10%,X7R,CA    I54 @SCM_LIB.SCM(SCH_1):PAGE26
  R269    1      A Q_RES_0402LF-4.7K,1%,1/16W,CHIA    I84 @SCM_LIB.SCM(SCH_1):PAGE27
  R267    1      A Q_RES_0402LF-4.7K,1%,1/16W,EMPA    I85 @SCM_LIB.SCM(SCH_1):PAGE27
  R268    1      A Q_RES_0402LF-4.7K,1%,1/16W,CHIA    I86 @SCM_LIB.SCM(SCH_1):PAGE27
  R265    1      A Q_RES_0402LF-2.2K,5%,1/16W,CHIA    I88 @SCM_LIB.SCM(SCH_1):PAGE27
  R264    1      A Q_RES_0402LF-2.2K,5%,1/16W,CHIA    I89 @SCM_LIB.SCM(SCH_1):PAGE27
  R262    1      A Q_RES_0402LF-10K,1%,1/16W,CHIPA    I93 @SCM_LIB.SCM(SCH_1):PAGE27
  R261    1      A Q_RES_0402LF-10K,1%,1/16W,CHIPA    I94 @SCM_LIB.SCM(SCH_1):PAGE27
  R266    1      A Q_RES_0402LF-4.7K,1%,1/16W,EMPA    I95 @SCM_LIB.SCM(SCH_1):PAGE27
  R259    1      A Q_RES_0402LF-2.2K,5%,1/16W,CHIA    I96 @SCM_LIB.SCM(SCH_1):PAGE27
  R260    1      A Q_RES_0402LF-10K,1%,1/16W,CHIPA    I97 @SCM_LIB.SCM(SCH_1):PAGE27
  R258    1      A Q_RES_0402LF-2.2K,5%,1/16W,CHIA    I98 @SCM_LIB.SCM(SCH_1):PAGE27
  R257    1      A Q_RES_0402LF-2.2K,5%,1/16W,CHIA    I99 @SCM_LIB.SCM(SCH_1):PAGE27
  R256    1      A Q_RES_0402LF-2.2K,5%,1/16W,CHIA   I100 @SCM_LIB.SCM(SCH_1):PAGE27
  R254    1      A Q_RES_0402LF-10K,1%,1/16W,CHIPA   I101 @SCM_LIB.SCM(SCH_1):PAGE27
  R255    1      A Q_RES_0402LF-10K,1%,1/16W,CHIPA   I102 @SCM_LIB.SCM(SCH_1):PAGE27
  R253    1      A Q_RES_0402LF-2.2K,5%,1/16W,CHIA   I103 @SCM_LIB.SCM(SCH_1):PAGE27
  R252    1      A Q_RES_0402LF-2.2K,5%,1/16W,CHIA   I105 @SCM_LIB.SCM(SCH_1):PAGE27
  R250    1      A Q_RES_0402LF-402,1%,1/16W,CHIPA   I106 @SCM_LIB.SCM(SCH_1):PAGE27
  R248    1      A Q_RES_0402LF-2.2K,5%,1/16W,CHIA   I107 @SCM_LIB.SCM(SCH_1):PAGE27
  R249    1      A Q_RES_0402LF-2.2K,5%,1/16W,CHIA   I108 @SCM_LIB.SCM(SCH_1):PAGE27
  R247    1      A Q_RES_0402LF-2.2K,5%,1/16W,CHIA   I109 @SCM_LIB.SCM(SCH_1):PAGE27
  R246    1      A Q_RES_0402LF-2.2K,5%,1/16W,CHIA   I145 @SCM_LIB.SCM(SCH_1):PAGE27
  R245    1      A Q_RES_0402LF-1.8K,1%,1/16W,CHIA   I146 @SCM_LIB.SCM(SCH_1):PAGE27
  R244    1      A Q_RES_0402LF-1.8K,1%,1/16W,CHIA   I147 @SCM_LIB.SCM(SCH_1):PAGE27
  R699    1      A Q_RES_0402LF-4.7K,1%,1/16W,EMPA   I163 @SCM_LIB.SCM(SCH_1):PAGE27
  R842    1      A Q_RES_0402LF-4.7K,1%,1/16W,CHIA   I168 @SCM_LIB.SCM(SCH_1):PAGE27
  R843    1      A Q_RES_0402LF-4.7K,1%,1/16W,CHIA   I177 @SCM_LIB.SCM(SCH_1):PAGE27
  R844    1      A Q_RES_0402LF-4.7K,1%,1/16W,CHIA   I179 @SCM_LIB.SCM(SCH_1):PAGE27
  R846    1      A Q_RES_0402LF-4.7K,1%,1/16W,EMPA   I181 @SCM_LIB.SCM(SCH_1):PAGE27
  R848    1      A Q_RES_0402LF-4.7K,1%,1/16W,CHIA   I182 @SCM_LIB.SCM(SCH_1):PAGE27
  R851    1      A Q_RES_0402LF-4.7K,1%,1/16W,CHIA   I184 @SCM_LIB.SCM(SCH_1):PAGE27
  R430    1      A Q_RES_0402LF-4.7K,1%,1/16W,CHIA   I188 @SCM_LIB.SCM(SCH_1):PAGE27
   R42    1      A Q_RES_0402LF-4.7K,1%,1/16W,CHIA   I222 @SCM_LIB.SCM(SCH_1):PAGE27
  R383    1      A Q_RES_0402LF-10K,1%,1/16W,CHIPA    I42 @SCM_LIB.SCM(SCH_1):PAGE28
  R299    1      A Q_RES_0402LF-4.7K,1%,1/16W,CHIA    I91 @SCM_LIB.SCM(SCH_1):PAGE28
  R298    1      A Q_RES_0402LF-4.7K,1%,1/16W,CHIA    I96 @SCM_LIB.SCM(SCH_1):PAGE28
  C159    1      A Q_CAP_0402-0.1UF,25V,10%,X7R,CA    I98 @SCM_LIB.SCM(SCH_1):PAGE28
   U37    1   VCCA PCA9517ADP_SMLF-PCA9517ADP,IC,A    I99 @SCM_LIB.SCM(SCH_1):PAGE28
   U37    8   VCCB PCA9517ADP_SMLF-PCA9517ADP,IC,A    I99 @SCM_LIB.SCM(SCH_1):PAGE28
  C158    1      A Q_CAP_0402-0.1UF,25V,10%,X7R,CA   I101 @SCM_LIB.SCM(SCH_1):PAGE28
  R295    1      A Q_RES_0402LF-10K,1%,1/16W,CHIPA   I113 @SCM_LIB.SCM(SCH_1):PAGE28
   U40   24    VDD PCA9555PW_SMLF-PCA9555PW,IC,TMA   I141 @SCM_LIB.SCM(SCH_1):PAGE28
  C300    1      A Q_CAP_0402-0.1UF,25V,10%,X7R,CA   I146 @SCM_LIB.SCM(SCH_1):PAGE28
  R667    1      A Q_RES_0402LF-4.7K,1%,1/16W,CHIA   I147 @SCM_LIB.SCM(SCH_1):PAGE28
  R736    1      A Q_RES_0402LF-1K,1%,1/16W,CHIP,A   I162 @SCM_LIB.SCM(SCH_1):PAGE28
  R735    1      A Q_RES_0402LF-1K,1%,1/16W,CHIP,A   I166 @SCM_LIB.SCM(SCH_1):PAGE28
  R740    1      A Q_RES_0402LF-4.7K,1%,1/16W,CHIA   I168 @SCM_LIB.SCM(SCH_1):PAGE28
  R739    1      A Q_RES_0402LF-4.7K,1%,1/16W,CHIA   I169 @SCM_LIB.SCM(SCH_1):PAGE28
  R738    1      A Q_RES_0402LF-4.7K,1%,1/16W,CHIA   I171 @SCM_LIB.SCM(SCH_1):PAGE28
   U23    5    VCC 74LVC1G07W57-74LVC1G07W5-7,SMLA   I180 @SCM_LIB.SCM(SCH_1):PAGE28
  C157    1      A Q_CAP_0402-0.1UF,25V,10%,X7R,CA   I181 @SCM_LIB.SCM(SCH_1):PAGE28
  C237    1      A Q_CAP_0402-0.1UF,25V,10%,X7R,CA   I146 @SCM_LIB.SCM(SCH_1):PAGE29
  C236    1      A Q_CAP_0402-0.1UF,25V,10%,X7R,CA   I148 @SCM_LIB.SCM(SCH_1):PAGE29
  C219    1      A Q_CAP_0402-0.1UF,25V,10%,X7R,CA   I150 @SCM_LIB.SCM(SCH_1):PAGE29
  R712    1      A Q_RES_0402LF-10K,1%,1/16W,EMPTA   I153 @SCM_LIB.SCM(SCH_1):PAGE29
  R274    1      A Q_RES_0402LF-100K,1%,1/16W,EMPA   I157 @SCM_LIB.SCM(SCH_1):PAGE29
  C149    1      A Q_CAP_0402-0.1UF,25V,10%,X7R,CA   I161 @SCM_LIB.SCM(SCH_1):PAGE29
   U36    5      5 74HC1G126GW-74HC1G126GW,SMLF,IA   I164 @SCM_LIB.SCM(SCH_1):PAGE29
  R193    1      A Q_RES_0402LF-100K,1%,1/16W,CHIA   I166 @SCM_LIB.SCM(SCH_1):PAGE29
  C148    1      A Q_CAP_0402-0.1UF,25V,10%,X7R,CA   I172 @SCM_LIB.SCM(SCH_1):PAGE29
   U29    5      5 74HC1G126GW-74HC1G126GW,SMLF,IA   I174 @SCM_LIB.SCM(SCH_1):PAGE29
  R730    1      A Q_RES_0402LF-4.7K,1%,1/16W,CHIA   I204 @SCM_LIB.SCM(SCH_1):PAGE29
   U22    1   VDD0 PI3PCIE3212ZBEX-PI3PCIE3212ZBEA   I206 @SCM_LIB.SCM(SCH_1):PAGE29
   U22    6   VDD1 PI3PCIE3212ZBEX-PI3PCIE3212ZBEA   I206 @SCM_LIB.SCM(SCH_1):PAGE29
   U22   10   VDD2 PI3PCIE3212ZBEX-PI3PCIE3212ZBEA   I206 @SCM_LIB.SCM(SCH_1):PAGE29
   R67    1      A Q_RES_0402LF-4.7K,1%,1/16W,CHIA   I146 @SCM_LIB.SCM(SCH_1):PAGE30
  C175    1      A Q_CAP_0402-0.1UF,25V,10%,X7R,CA   I151 @SCM_LIB.SCM(SCH_1):PAGE30
  R737    1      A Q_RES_0402LF-4.7K,1%,1/16W,EMPA   I192 @SCM_LIB.SCM(SCH_1):PAGE30
  R742    1      A Q_RES_0402LF-4.7K,1%,1/16W,EMPA   I195 @SCM_LIB.SCM(SCH_1):PAGE30
  R741    1      A Q_RES_0402LF-4.7K,1%,1/16W,CHIA   I197 @SCM_LIB.SCM(SCH_1):PAGE30
  C268    1      A Q_CAP_0402-0.1UF,25V,10%,X7R,CA   I229 @SCM_LIB.SCM(SCH_1):PAGE30
   R72    1      A Q_RES_0402LF-4.7K,1%,1/16W,CHIA   I231 @SCM_LIB.SCM(SCH_1):PAGE30
  R765    1      A Q_RES_0402LF-4.7K,1%,1/16W,CHIA   I239 @SCM_LIB.SCM(SCH_1):PAGE30
   U24    5    VCC 74LVC2G07DW7-74LVC2G07DW-7,SMLA   I246 @SCM_LIB.SCM(SCH_1):PAGE30
   U47    5    VCC 74LVC2G07DW7-74LVC2G07DW-7,SMLA   I247 @SCM_LIB.SCM(SCH_1):PAGE30
    U2    8    VCC FSA3357K8X-FSA3357K8X,SMLF,IC,A   I250 @SCM_LIB.SCM(SCH_1):PAGE30
    U3    8    VCC FSA3357K8X-FSA3357K8X,SMLF,IC,A   I251 @SCM_LIB.SCM(SCH_1):PAGE30
   C20    1      A Q_CAP_0402-0.1UF,25V,10%,X7R,CA   I254 @SCM_LIB.SCM(SCH_1):PAGE30
   C19    1      A Q_CAP_0402-0.1UF,25V,10%,X7R,CA   I261 @SCM_LIB.SCM(SCH_1):PAGE30
  C501    1      A Q_CAP_0402-0.1UF,25V,10%,X7R,CA    I11 @SCM_LIB.SCM(SCH_1):PAGE31
  C500    1      A Q_CAP_0402-0.1UF,25V,10%,X7R,CA    I17 @SCM_LIB.SCM(SCH_1):PAGE31
   U50    5    VCC NC7SB3157_SMLF-NC7SB3157P6X,NCA    I23 @SCM_LIB.SCM(SCH_1):PAGE31
   U51    5    VCC NC7SB3157_SMLF-NC7SB3157P6X,NCA    I24 @SCM_LIB.SCM(SCH_1):PAGE31
  R226    1      A Q_RES_0402LF-10K,1%,1/16W,CHIPA   I103 @SCM_LIB.SCM(SCH_1):PAGE32
  R227    1      A Q_RES_0402LF-10K,1%,1/16W,CHIPA   I104 @SCM_LIB.SCM(SCH_1):PAGE32
  R230    1      A Q_RES_0402LF-10K,1%,1/16W,CHIPA   I105 @SCM_LIB.SCM(SCH_1):PAGE32
  R625    1      A Q_RES_0402LF-4.7K,1%,1/16W,CHIA    I17 @SCM_LIB.SCM(SCH_1):PAGE34
  R806    1      A Q_RES_0402LF-4.7K,1%,1/16W,CHIA   I119 @SCM_LIB.SCM(SCH_1):PAGE34
  C318    1      A Q_CAP_0402-0.1UF,25V,10%,X7R,CA   I122 @SCM_LIB.SCM(SCH_1):PAGE34
  OSC2    4    VDD OSC4_7X25000018-25MHZ,SMLF,MISA   I127 @SCM_LIB.SCM(SCH_1):PAGE34
  R305    1      A Q_RES_0402LF-0,5%,1/16W,CHIP,CA    I71 @SCM_LIB.SCM(SCH_1):PAGE41
  R525    1      A Q_RES_0402LF-0,5%,1/16W,CHIP,CA    I72 @SCM_LIB.SCM(SCH_1):PAGE41
  R304    1      A Q_RES_0402LF-0,5%,1/16W,CHIP,CA    I73 @SCM_LIB.SCM(SCH_1):PAGE41
  R308    1      A Q_RES_0402LF-0,5%,1/16W,CHIP,CA    I74 @SCM_LIB.SCM(SCH_1):PAGE41
  R301    1      A Q_RES_0402LF-0,5%,1/16W,CHIP,CA    I75 @SCM_LIB.SCM(SCH_1):PAGE41
  R307    1      A Q_RES_0402LF-0,5%,1/16W,CHIP,CA    I76 @SCM_LIB.SCM(SCH_1):PAGE41
  C145    1      A Q_CAP_C0402-1UF,25V,10%,X6S,CHA    I99 @SCM_LIB.SCM(SCH_1):PAGE41
  C194    1      A Q_CAP_C0603-10UF,16V,20%,X6S,CA   I101 @SCM_LIB.SCM(SCH_1):PAGE41
   L19    1      1 Q_INDUCTOR_SMLF-BLM18EG121SN1DA   I107 @SCM_LIB.SCM(SCH_1):PAGE41
  R627    1      A Q_RES_0402LF-4.7K,1%,1/16W,CHIA     I7 @SCM_LIB.SCM(SCH_1):PAGE42
  R621    1      A Q_RES_0402LF-4.7K,1%,1/16W,CHIA    I13 @SCM_LIB.SCM(SCH_1):PAGE42
  R608    1      A Q_RES_0402LF-4.7K,1%,1/16W,CHIA    I27 @SCM_LIB.SCM(SCH_1):PAGE42
  R607    1      A Q_RES_0402LF-4.7K,1%,1/16W,CHIA    I29 @SCM_LIB.SCM(SCH_1):PAGE42
  R595    1      A Q_RES_0402LF-4.7K,1%,1/16W,EMPA    I37 @SCM_LIB.SCM(SCH_1):PAGE42
  R593    1      A Q_RES_0402LF-4.7K,1%,1/16W,EMPA    I39 @SCM_LIB.SCM(SCH_1):PAGE42
  R641    1      A Q_RES_0402LF-4.7K,1%,1/16W,EMPA    I53 @SCM_LIB.SCM(SCH_1):PAGE42
  R640    1      A Q_RES_0402LF-4.7K,1%,1/16W,EMPA    I56 @SCM_LIB.SCM(SCH_1):PAGE42
  R749    1      A Q_RES_0402LF-4.7K,1%,1/16W,CHIA    I61 @SCM_LIB.SCM(SCH_1):PAGE42
  R835    1      A Q_RES_0402LF-4.7K,1%,1/16W,CHIA    I63 @SCM_LIB.SCM(SCH_1):PAGE42
  R319    1      A Q_RES_0402LF-4.7K,1%,1/16W,CHIA    I65 @SCM_LIB.SCM(SCH_1):PAGE42
   U30   16    VCC IDTQS3VH257PAG_SMLF-IDTQS3VH25A   I271 @SCM_LIB.SCM(SCH_1):PAGE44
  C255    1      A Q_CAP_0402-0.1UF,25V,10%,X7R,CA   I278 @SCM_LIB.SCM(SCH_1):PAGE44
  C146    1      A Q_CAP_0402-0.1UF,25V,10%,X7R,CA   I292 @SCM_LIB.SCM(SCH_1):PAGE44
   U21   16    VCC IDTQS3VH257PAG_SMLF-IDTQS3VH25A   I296 @SCM_LIB.SCM(SCH_1):PAGE44
  R870    1      A Q_RES_0402LF-4.7K,1%,1/16W,EMPA   I315 @SCM_LIB.SCM(SCH_1):PAGE44
  R488    1      A Q_RES_0402LF-4.7K,1%,1/16W,CHIA    I33 @SCM_LIB.SCM(SCH_1):PAGE45
  R490    1      A Q_RES_0402LF-4.7K,1%,1/16W,CHIA    I34 @SCM_LIB.SCM(SCH_1):PAGE45
  R492    1      A Q_RES_0402LF-4.7K,1%,1/16W,CHIA    I35 @SCM_LIB.SCM(SCH_1):PAGE45
  C244    1      A Q_CAP_C0402-1UF,25V,10%,X6S,CHA    I42 @SCM_LIB.SCM(SCH_1):PAGE45
  C246    1      A Q_CAP_C0402-0.01UF,50V,10%,X7RA    I45 @SCM_LIB.SCM(SCH_1):PAGE45
  R496    1      A Q_RES_0402LF-4.7K,1%,1/16W,EMPA    I48 @SCM_LIB.SCM(SCH_1):PAGE45
   J40    2    VCC SCONN16_ACASPI006P06-SCONN16_AA    I53 @SCM_LIB.SCM(SCH_1):PAGE45
    J5    7      7 SCONN11_9192031111LF-SCONN11_9A    I56 @SCM_LIB.SCM(SCH_1):PAGE46
  C249    1      A Q_CAP_0402-0.1UF,25V,10%,X7R,CA    I67 @SCM_LIB.SCM(SCH_1):PAGE46
  C248    1      A Q_CAP_C0402-10UF,6.3V,20%,X6S,A    I69 @SCM_LIB.SCM(SCH_1):PAGE46
  R464    1      A Q_RES_0402LF-10K,1%,1/16W,CHIPA    I75 @SCM_LIB.SCM(SCH_1):PAGE46
  R497    1      A Q_RES_0402LF-10K,1%,1/16W,CHIPA    I78 @SCM_LIB.SCM(SCH_1):PAGE46
   R59    1      A Q_RES_0402LF-10K,1%,1/16W,CHIPA    I98 @SCM_LIB.SCM(SCH_1):PAGE46
  C144    1      A Q_CAP_0402-0.1UF,25V,10%,X7R,CA   I102 @SCM_LIB.SCM(SCH_1):PAGE46
   R50    1      A Q_RES_0402LF-10K,1%,1/16W,CHIPA   I104 @SCM_LIB.SCM(SCH_1):PAGE46
  C143    1      A Q_CAP_C0402-10UF,6.3V,20%,X6S,A   I108 @SCM_LIB.SCM(SCH_1):PAGE46
   J10    7      7 SCONN11_9192031111LF-SCONN11_9A   I113 @SCM_LIB.SCM(SCH_1):PAGE46
  R136    1      A Q_RES_0402LF-10K,1%,1/16W,CHIPA   I132 @SCM_LIB.SCM(SCH_1):PAGE46
  R126    2      B Q_RES_0402LF-10K,1%,1/16W,CHIPA   I134 @SCM_LIB.SCM(SCH_1):PAGE46
    U9    5    VCC MC74VHC1G32DTT1G-MC74VHC1G32DTA     I5 @SCM_LIB.SCM(SCH_1):PAGE49
    U8    5    VCC 74LVC1G126SE7-74LVC1G126SE-7,SA    I11 @SCM_LIB.SCM(SCH_1):PAGE49
  C274    1      A Q_CAP_0402-0.1UF,25V,10%,X7R,CA    I13 @SCM_LIB.SCM(SCH_1):PAGE49
   D19    A      A Q_LED_SMLF-LED_BLUE,LTST-C281TA    I50 @SCM_LIB.SCM(SCH_1):PAGE49
   D18    A      A Q_LED_SMLF-LED_BLUE,LTST-C281TA    I51 @SCM_LIB.SCM(SCH_1):PAGE49
  C276    1      A Q_CAP_0402-0.1UF,25V,10%,X7R,CA    I75 @SCM_LIB.SCM(SCH_1):PAGE49
   R43    2      B Q_RES_0402LF-220,1%,1/16W,CHIPA    I79 @SCM_LIB.SCM(SCH_1):PAGE49
  C200    1      A Q_CAP_0402-0.1UF,25V,10%,X7R,CA    I43 @SCM_LIB.SCM(SCH_1):PAGE50
   U32    5    VCC 74LVC1G17GW-74LVC1G17GW,SMLF,IA    I49 @SCM_LIB.SCM(SCH_1):PAGE50
  C201    1      A Q_CAP_0402-0.1UF,25V,10%,X7R,CA    I51 @SCM_LIB.SCM(SCH_1):PAGE50
  R504    1      A Q_RES_0402LF-8.2K,5%,1/16W,CHIA    I82 @SCM_LIB.SCM(SCH_1):PAGE50
  R768    1      A Q_RES_0402LF-8.2K,5%,1/16W,CHIA    I89 @SCM_LIB.SCM(SCH_1):PAGE50
   U31    5    VCC 74LVC1G07GW-74LVC1G07GW,SMLF,IA   I151 @SCM_LIB.SCM(SCH_1):PAGE50
   U48    2      A BAS70057F-BAS70-05-7-F,SMLF,ICA   I161 @SCM_LIB.SCM(SCH_1):PAGE50
 PR242    1      A Q_RES_0402LF-10K,1%,1/16W,CHIPA    I13 @SCM_LIB.SCM(SCH_1):PAGE52
 PC225    1      A Q_CAP_0402-0.1UF,25V,10%,X7R,CA    I23 @SCM_LIB.SCM(SCH_1):PAGE52
 PR534    2      B Q_RES_0402LF-56K,1%,1/16W,CHIPA    I25 @SCM_LIB.SCM(SCH_1):PAGE52
 PC226    1      A Q_CAP_C0805-22UF,10V,20%,X6S,CA    I35 @SCM_LIB.SCM(SCH_1):PAGE52
 PC227    1      A Q_CAP_C0805-22UF,10V,20%,X6S,CA    I36 @SCM_LIB.SCM(SCH_1):PAGE52
 PC228    1      A Q_CAP_C0805-22UF,10V,20%,X6S,CA    I37 @SCM_LIB.SCM(SCH_1):PAGE52
 PC229    1      A Q_CAP_C0805-22UF,10V,20%,X6S,CA    I38 @SCM_LIB.SCM(SCH_1):PAGE52
  C240    1      A Q_CAP_0402-0.1UF,25V,10%,X7R,CA    I63 @SCM_LIB.SCM(SCH_1):PAGE52
   U14    5     IN AP22811AW57-AP22811AW5-7,SMLF,A    I79 @SCM_LIB.SCM(SCH_1):PAGE52
 PC239    2      B Q_CAP_0402-100PF,50V,5%,NPO,CHA    I91 @SCM_LIB.SCM(SCH_1):PAGE52
  PL35    2      2 Q_INDUCTOR_SMLF-3.3UH/6A,IND,CA    I92 @SCM_LIB.SCM(SCH_1):PAGE52
   U39    7   VIN1 RT9059GQW-RT9059GQW,SMLF,IC,ALA    I60 @SCM_LIB.SCM(SCH_1):PAGE53
   U39    8   VIN2 RT9059GQW-RT9059GQW,SMLF,IC,ALA    I60 @SCM_LIB.SCM(SCH_1):PAGE53
   U39    9   VIN3 RT9059GQW-RT9059GQW,SMLF,IC,ALA    I60 @SCM_LIB.SCM(SCH_1):PAGE53
   U41    7   VIN1 RT9059GQW-RT9059GQW,SMLF,IC,ALA    I96 @SCM_LIB.SCM(SCH_1):PAGE54
   U41    8   VIN2 RT9059GQW-RT9059GQW,SMLF,IC,ALA    I96 @SCM_LIB.SCM(SCH_1):PAGE54
   U41    9   VIN3 RT9059GQW-RT9059GQW,SMLF,IC,ALA    I96 @SCM_LIB.SCM(SCH_1):PAGE54
 PR498    1      A Q_RES_0402LF-10K,1%,1/16W,CHIPA    I18 @SCM_LIB.SCM(SCH_1):PAGE55
 PR274    1      A Q_RES_0402LF-0,5%,1/16W,CHIP,CA    I45 @SCM_LIB.SCM(SCH_1):PAGE55
 PR500    1      A Q_RES_0402LF-10K,1%,1/16W,CHIPA    I18 @SCM_LIB.SCM(SCH_1):PAGE56
 PR193    1      A Q_RES_0402LF-0,5%,1/16W,CHIP,CA    I47 @SCM_LIB.SCM(SCH_1):PAGE56
   R52    1      A Q_RES_0402LF-4.7K,1%,1/16W,CHIA    I67 @SCM_LIB.SCM(SCH_1):PAGE26
  R400    1      A Q_RES_0402LF-4.7K,1%,1/16W,EMPA   I454 @SCM_LIB.SCM(SCH_1):PAGE12
  C293    1      A Q_CAP_C0805-10UF,25V,10%,X6S,CA   I106 @SCM_LIB.SCM(SCH_1):PAGE54
  R406    1      A Q_RES_0402LF-10K,1%,1/16W,CHIPA   I108 @SCM_LIB.SCM(SCH_1):PAGE54
  R403    1      A Q_RES_0402LF-10K,1%,1/16W,CHIPA    I68 @SCM_LIB.SCM(SCH_1):PAGE53
  C288    1      A Q_CAP_C0805-10UF,25V,10%,X6S,CA    I71 @SCM_LIB.SCM(SCH_1):PAGE53
  R408    1      A Q_RES_0402LF-4.7K,1%,1/16W,EMPB   I139 @SCM_LIB.SCM(SCH_1):PAGE46
  R414    1      A Q_RES_0402LF-4.7K,1%,1/16W,EMPB   I140 @SCM_LIB.SCM(SCH_1):PAGE46
  R140    1      A Q_RES_0402LF-4.7K,1%,1/16W,EMPA   I228 @SCM_LIB.SCM(SCH_1):PAGE27
  R753    1      A Q_RES_0402LF-4.7K,1%,1/16W,EMPA   I233 @SCM_LIB.SCM(SCH_1):PAGE27
   D20    1      A SCHOTTKY_12-1N5819HW,SMLF,IC,BA   I144 @SCM_LIB.SCM(SCH_1):PAGE32
   U17    2    VCC MX25L51245GMI10G-MX25L51245GMIA    I54 @SCM_LIB.SCM(SCH_1):PAGE45
  R538    1      A Q_RES_0402LF-100K,1%,1/16W,CHIA    I25 @SCM_LIB.SCM(SCH_1):PAGE31
   U54    8    VCC 74LVC1G74DP-74LVC1G74DP,SMLF,IA   I138 @SCM_LIB.SCM(SCH_1):PAGE25
  C312    1      A Q_CAP_0402-0.1UF,25V,10%,X7R,CA   I146 @SCM_LIB.SCM(SCH_1):PAGE25
   U55    5    VCC SN74LVC1G14DCKR_SMLF-IC,SN74LVA   I150 @SCM_LIB.SCM(SCH_1):PAGE25
  C313    1      A Q_CAP_0402-0.1UF,25V,10%,X7R,CA   I154 @SCM_LIB.SCM(SCH_1):PAGE25
  R554    1      A Q_RES_0402LF-4.7K,1%,1/16W,EMPB   I156 @SCM_LIB.SCM(SCH_1):PAGE25
  R521    1      A Q_RES_0402LF-10K,1%,1/16W,CHIPA   I234 @SCM_LIB.SCM(SCH_1):PAGE27
  R145    1      A Q_RES_0402LF-10K,1%,1/16W,CHIPA   I235 @SCM_LIB.SCM(SCH_1):PAGE27
  R149    1      A Q_RES_0402LF-10K,1%,1/16W,CHIPA   I236 @SCM_LIB.SCM(SCH_1):PAGE27
  R610    1      A Q_RES_0402LF-2.2K,5%,1/16W,CHIA   I237 @SCM_LIB.SCM(SCH_1):PAGE27
  R692    1      A Q_RES_0402LF-2.2K,5%,1/16W,CHIA   I238 @SCM_LIB.SCM(SCH_1):PAGE27
  R422    1      A Q_RES_0402LF-2.2K,5%,1/16W,CHIA   I239 @SCM_LIB.SCM(SCH_1):PAGE27
  R428    1      A Q_RES_0402LF-2.2K,5%,1/16W,CHIA   I240 @SCM_LIB.SCM(SCH_1):PAGE27
  R429    1      A Q_RES_0402LF-2.2K,5%,1/16W,CHIA   I241 @SCM_LIB.SCM(SCH_1):PAGE27
  R438    1      A Q_RES_0402LF-2.2K,5%,1/16W,CHIA   I242 @SCM_LIB.SCM(SCH_1):PAGE27
   U43    6    VDD TPS3808G18DBVR-TPS3808G01DBVR,A    I90 @SCM_LIB.SCM(SCH_1):PAGE22
    J4    2      2 SCONN67_NASA0S6730TS67-SCONN67A    I84 @SCM_LIB.SCM(SCH_1):PAGE21
    J4    4      4 SCONN67_NASA0S6730TS67-SCONN67A    I84 @SCM_LIB.SCM(SCH_1):PAGE21
    J4   72     72 SCONN67_NASA0S6730TS67-SCONN67A    I84 @SCM_LIB.SCM(SCH_1):PAGE21
    J4   74     74 SCONN67_NASA0S6730TS67-SCONN67A    I84 @SCM_LIB.SCM(SCH_1):PAGE21
  R543    1      A Q_RES_0402LF-4.7K,1%,1/16W,EMPB   I147 @SCM_LIB.SCM(SCH_1):PAGE21
    U7    5    VCC NC7SB3157_SMLF-NC7SB3157P6X,NCA    I27 @SCM_LIB.SCM(SCH_1):PAGE31
   C11    1      A Q_CAP_0402-0.1UF,25V,10%,X7R,CA    I31 @SCM_LIB.SCM(SCH_1):PAGE31
   U20    5    VCC NC7SB3157_SMLF-NC7SB3157P6X,NCA    I38 @SCM_LIB.SCM(SCH_1):PAGE31
  C231    1      A Q_CAP_0402-0.1UF,25V,10%,X7R,CA    I45 @SCM_LIB.SCM(SCH_1):PAGE31
  R183    1      A Q_RES_0402LF-0,5%,1/16W,CHIP,CA   I139 @SCM_LIB.SCM(SCH_1):PAGE34
  C120    1      A Q_CAP_C0603-22UF,6.3V,20%,X6S,A   I190 @SCM_LIB.SCM(SCH_1):PAGE16
  C125    1      A Q_CAP_C0603-22UF,6.3V,20%,X6S,A   I191 @SCM_LIB.SCM(SCH_1):PAGE16
  R867    1      A Q_RES_0402LF-1K,1%,1/16W,EMPTYA   I161 @SCM_LIB.SCM(SCH_1):PAGE21
  R615    1      A Q_RES_0402LF-4.7K,1%,1/16W,EMPB    I33 @SCM_LIB.SCM(SCH_1):PAGE48
  R881    1      A Q_RES_0402LF-4.7K,1%,1/16W,EMPB    I42 @SCM_LIB.SCM(SCH_1):PAGE48
  R624    1      A Q_RES_0402LF-4.7K,1%,1/16W,CHIA    I48 @SCM_LIB.SCM(SCH_1):PAGE48
  R508    1      A Q_RES_0402LF-10K,1%,1/16W,CHIPA    I51 @SCM_LIB.SCM(SCH_1):PAGE48
  R404    1      A Q_RES_0402LF-10K,1%,1/16W,CHIPA   I166 @SCM_LIB.SCM(SCH_1):PAGE21
   R58    1      A Q_RES_0402LF-4.7K,1%,1/16W,EMPB   I168 @SCM_LIB.SCM(SCH_1):PAGE21
  R169    1      A Q_RES_0402LF-4.7K,1%,1/16W,CHIA   I256 @SCM_LIB.SCM(SCH_1):PAGE11
  R586    1      A Q_RES_0402LF-4.7K,1%,1/16W,CHIA    I67 @SCM_LIB.SCM(SCH_1):PAGE42
  R462    1      A Q_RES_0402LF-4.7K,1%,1/16W,CHIA   I391 @SCM_LIB.SCM(SCH_1):PAGE15
   U15    5    VCC 74LVC1G08GW_SM-74LVC1G08GW,IC,A   I393 @SCM_LIB.SCM(SCH_1):PAGE15
   C26    1      A Q_CAP_0402-0.1UF,25V,10%,X7R,CA   I398 @SCM_LIB.SCM(SCH_1):PAGE15
   U16    5    VCC 74LVC1G07GW-74LVC1G07GW,SMLF,EA   I227 @SCM_LIB.SCM(SCH_1):PAGE50
   C29    1      A Q_CAP_0402-0.1UF,25V,10%,EMPTYA   I232 @SCM_LIB.SCM(SCH_1):PAGE50
  R391    1      A Q_RES_0402LF-8.2K,5%,1/16W,EMPA   I235 @SCM_LIB.SCM(SCH_1):PAGE50
    Q4    S      S MOSFET_PCH_GDS-NTR1P02LT1G,SMLA   I289 @SCM_LIB.SCM(SCH_1):PAGE17
   R11    1      A Q_RES_0402LF-4.7K,1%,1/16W,CHIA   I172 @SCM_LIB.SCM(SCH_1):PAGE21
  R557    1      A Q_RES_0402LF-4.7K,1%,1/16W,CHIA   I173 @SCM_LIB.SCM(SCH_1):PAGE21
  R558    1      A Q_RES_0402LF-4.7K,1%,1/16W,CHIA   I174 @SCM_LIB.SCM(SCH_1):PAGE21
  R181    1      A Q_RES_0402LF-4.7K,1%,1/16W,CHIA   I170 @SCM_LIB.SCM(SCH_1):PAGE25
  R592    1      A Q_RES_0402LF-4.7K,1%,1/16W,CHIA   I171 @SCM_LIB.SCM(SCH_1):PAGE25
   R90    1      A Q_RES_0402LF-4.7K,1%,1/16W,EMPA   I182 @SCM_LIB.SCM(SCH_1):PAGE21
  R630    1      A Q_RES_0402LF-4.7K,1%,1/16W,CHIA    I79 @SCM_LIB.SCM(SCH_1):PAGE31
  R396    1      A Q_RES_0402LF-100K,1%,1/16W,CHIA    I80 @SCM_LIB.SCM(SCH_1):PAGE31
  R472    1      A Q_RES_0402LF-4.7K,1%,1/16W,EMPA   I136 @SCM_LIB.SCM(SCH_1):PAGE35
   J14    1      1 CONN8_TSW10407FD-CONN8_TSW-104A    I71 @SCM_LIB.SCM(SCH_1):PAGE26
   U57    5    VCC 74LVC1G07GW-74LVC1G07GW,SMLF,IA   I278 @SCM_LIB.SCM(SCH_1):PAGE50
  C336    1      A Q_CAP_0402-0.1UF,25V,10%,X7R,CA   I281 @SCM_LIB.SCM(SCH_1):PAGE50
  R883    1      A Q_RES_0402LF-8.2K,5%,1/16W,EMPA   I284 @SCM_LIB.SCM(SCH_1):PAGE50
  R886    1      A Q_RES_0402LF-4.7K,1%,1/16W,CHIA   I151 @SCM_LIB.SCM(SCH_1):PAGE35
  R251    1      A Q_RES_0402LF-499,1%,1/16W,CHIPA   I247 @SCM_LIB.SCM(SCH_1):PAGE27
   U58    5    VCC MC74VHC1G32DTT1G-MC74VHC1G32DTA    I94 @SCM_LIB.SCM(SCH_1):PAGE22
  C337    1      A Q_CAP_0402-0.1UF,25V,10%,X7R,CA    I97 @SCM_LIB.SCM(SCH_1):PAGE22
  R888    1      A Q_RES_0402LF-1K,1%,1/16W,EMPTYA   I102 @SCM_LIB.SCM(SCH_1):PAGE22
  R887    1      A Q_RES_0402LF-4.7K,1%,1/16W,EMPA   I106 @SCM_LIB.SCM(SCH_1):PAGE22

P3V3_AUX_CS @SCM_LIB.SCM(SCH_1):P3V3_AUX_CS
   PU1    4     CS MPQ8626GDZ-MPQ8626GD-Z,SMLF,ICA    I82 @SCM_LIB.SCM(SCH_1):PAGE52
 PR276    2      B Q_RES_0402LF-5.49K,1%,1/16W,CHA    I87 @SCM_LIB.SCM(SCH_1):PAGE52

P3V3_AUX_FB_RC @SCM_LIB.SCM(SCH_1):P3V3_AUX_FB_RC
 PR530    2      B Q_RES_0402LF-12.4K,1%,1/16W,CHA    I17 @SCM_LIB.SCM(SCH_1):PAGE52
 PR534    1      A Q_RES_0402LF-56K,1%,1/16W,CHIPA    I25 @SCM_LIB.SCM(SCH_1):PAGE52
   PU1    6     FB MPQ8626GDZ-MPQ8626GD-Z,SMLF,ICA    I82 @SCM_LIB.SCM(SCH_1):PAGE52
 PC239    1      A Q_CAP_0402-100PF,50V,5%,NPO,CHA    I91 @SCM_LIB.SCM(SCH_1):PAGE52

P3V3_AUX_MODE @SCM_LIB.SCM(SCH_1):P3V3_AUX_MODE
   PU1   12   MODE MPQ8626GDZ-MPQ8626GD-Z,SMLF,ICA    I82 @SCM_LIB.SCM(SCH_1):PAGE52
 PR532    2      B Q_RES_0402LF-60.4K,1%,1/16W,CHA    I88 @SCM_LIB.SCM(SCH_1):PAGE52

P3V3_AUX_REF @SCM_LIB.SCM(SCH_1):P3V3_AUX_REF
   PU1    8 TRK_REF MPQ8626GDZ-MPQ8626GD-Z,SMLF,ICA    I82 @SCM_LIB.SCM(SCH_1):PAGE52
 PC273    1      A Q_CAP_0402-3300PF,50V,10%,X7R,A    I86 @SCM_LIB.SCM(SCH_1):PAGE52

P3V3_AUX_VCC @SCM_LIB.SCM(SCH_1):P3V3_AUX_VCC
 PC221    1      A Q_CAP_C0402-1UF,25V,10%,X6S,CHA     I9 @SCM_LIB.SCM(SCH_1):PAGE52
   PU1   13    VCC MPQ8626GDZ-MPQ8626GD-Z,SMLF,ICA    I82 @SCM_LIB.SCM(SCH_1):PAGE52

P3V3_BMC_USB2AV33 @SCM_LIB.SCM(SCH_1):P3V3_BMC_USB2AV33
    L4    2      2 Q_INDUCTOR_SMLF-BLM18PG121SN1DA    I82 @SCM_LIB.SCM(SCH_1):PAGE15
   C45    1      A Q_CAP_0402-0.1UF,25V,10%,X7R,CA    I89 @SCM_LIB.SCM(SCH_1):PAGE15
    U5  J10 USB2AV33 AST2600A3GP-AST2600A3-GP,SMLF,A   I350 @SCM_LIB.SCM(SCH_1):PAGE15
   C44    1      A Q_CAP_C0603-4.7UF,25V,10%,X6S,A   I369 @SCM_LIB.SCM(SCH_1):PAGE15

P3V3_LDO @SCM_LIB.SCM(SCH_1):P3V3_LDO
  C298    1      A Q_CAP_0402-0.1UF,25V,10%,X7R,CA   I112 @SCM_LIB.SCM(SCH_1):PAGE54
   U49    5    VCC MC74VHC1G32DTT1G-MC74VHC1G32DTA   I116 @SCM_LIB.SCM(SCH_1):PAGE54
  C302    1      A Q_CAP_0402-0.1UF,25V,10%,X7R,CA    I64 @SCM_LIB.SCM(SCH_1):PAGE56
   U53    5    VCC 74LVC1G08GW_SM-74LVC1G08GW,IC,A    I66 @SCM_LIB.SCM(SCH_1):PAGE56
  C301    1      A Q_CAP_0402-0.1UF,25V,10%,X7R,CA    I61 @SCM_LIB.SCM(SCH_1):PAGE55
   U52    5    VCC 74LVC1G08GW_SM-74LVC1G08GW,IC,A    I63 @SCM_LIB.SCM(SCH_1):PAGE55
   U42    5    VCC MC74VHC1G32DTT1G-MC74VHC1G32DTA   I104 @SCM_LIB.SCM(SCH_1):PAGE52
  C297    1      A Q_CAP_0402-0.1UF,25V,10%,X7R,CA   I107 @SCM_LIB.SCM(SCH_1):PAGE52
   U18    5    VCC 74LVC1G08GW_SM-74LVC1G08GW,IC,A   I114 @SCM_LIB.SCM(SCH_1):PAGE52
  C296    1      A Q_CAP_0402-0.1UF,25V,10%,X7R,CA   I119 @SCM_LIB.SCM(SCH_1):PAGE52
   U56    5   VOUT AP2205W57-AP2205-W5-7,SMLF,IC,A    I56 @SCM_LIB.SCM(SCH_1):PAGE51
  R631    1      A Q_RES_0402LF-16.9K,1%,1/16W,CHA    I62 @SCM_LIB.SCM(SCH_1):PAGE51
   U28    5    VCC 74LVC1G66GV-74LVC1G66GV,SMLF,IA   I435 @SCM_LIB.SCM(SCH_1):PAGE13
  C180    1      A Q_CAP_0402-0.1UF,25V,10%,X7R,CA   I440 @SCM_LIB.SCM(SCH_1):PAGE13
  C227    1      A Q_CAP_C0402-2.2UF,10V,10%,X6S,A    I68 @SCM_LIB.SCM(SCH_1):PAGE51

P3V3_P1V8_I2C_I3C @SCM_LIB.SCM(SCH_1):P3V3_P1V8_I2C_I3C
    U5  F19 I3CVDDH_F19 AST2600A3GP-AST2600A3-GP,SMLF,A   I188 @SCM_LIB.SCM(SCH_1):PAGE16
    U5  F20 I3CVDDH_F20 AST2600A3GP-AST2600A3-GP,SMLF,A   I188 @SCM_LIB.SCM(SCH_1):PAGE16
  R231    2      B Q_RES_0402LF-0,5%,1/16W,CHIP,CA   I131 @SCM_LIB.SCM(SCH_1):PAGE17
   C57    1      A Q_CAP_0402-0.1UF,25V,10%,X7R,CA   I133 @SCM_LIB.SCM(SCH_1):PAGE17
   C53    1      A Q_CAP_C0402-1UF,25V,10%,X6S,CHA   I135 @SCM_LIB.SCM(SCH_1):PAGE17
  R232    2      B Q_RES_0402LF-0,5%,1/16W,EMPTY,A   I136 @SCM_LIB.SCM(SCH_1):PAGE17

P3V3_P1V8_SD1VDD @SCM_LIB.SCM(SCH_1):P3V3_P1V8_SD1VDD
  R208    2      B Q_RES_0402LF-0,5%,1/16W,EMPTY,A     I2 @SCM_LIB.SCM(SCH_1):PAGE15
  R207    2      B Q_RES_0402LF-0,5%,1/16W,CHIP,CA     I4 @SCM_LIB.SCM(SCH_1):PAGE15
   C35    1      A Q_CAP_C0402-1UF,25V,10%,X6S,CHA    I14 @SCM_LIB.SCM(SCH_1):PAGE15
   C36    1      A Q_CAP_0402-0.1UF,25V,10%,X7R,CA    I16 @SCM_LIB.SCM(SCH_1):PAGE15
    U5  G21 SD1VDD_G21 AST2600A3GP-AST2600A3-GP,SMLF,A   I188 @SCM_LIB.SCM(SCH_1):PAGE16
    U5  H21 SD1VDD_H21 AST2600A3GP-AST2600A3-GP,SMLF,A   I188 @SCM_LIB.SCM(SCH_1):PAGE16

P3V3_P1V8_SD2VDD @SCM_LIB.SCM(SCH_1):P3V3_P1V8_SD2VDD
  R214    2      B Q_RES_0402LF-0,5%,1/16W,EMPTY,A    I32 @SCM_LIB.SCM(SCH_1):PAGE15
  R213    2      B Q_RES_0402LF-0,5%,1/16W,CHIP,CA    I34 @SCM_LIB.SCM(SCH_1):PAGE15
   C38    1      A Q_CAP_C0402-1UF,25V,10%,X6S,CHA    I36 @SCM_LIB.SCM(SCH_1):PAGE15
   C39    1      A Q_CAP_0402-0.1UF,25V,10%,X7R,CA    I37 @SCM_LIB.SCM(SCH_1):PAGE15
    U5  H18 SD2VDD_H18 AST2600A3GP-AST2600A3-GP,SMLF,A   I188 @SCM_LIB.SCM(SCH_1):PAGE16
    U5  H19 SD2VDD_H19 AST2600A3GP-AST2600A3-GP,SMLF,A   I188 @SCM_LIB.SCM(SCH_1):PAGE16

P3V3_P2V5_P1V8_RVDD @SCM_LIB.SCM(SCH_1):P3V3_P2V5_P1V8_RVDD
  R154    2      B Q_RES_0402LF-0,5%,1/16W,EMPTY,A     I3 @SCM_LIB.SCM(SCH_1):PAGE13
  R156    2      B Q_RES_0402LF-0,5%,1/16W,EMPTY,A     I4 @SCM_LIB.SCM(SCH_1):PAGE13
  R155    2      B Q_RES_0402LF-0,5%,1/16W,CHIP,CA     I5 @SCM_LIB.SCM(SCH_1):PAGE13
   C30    1      A Q_CAP_C0402-1UF,25V,10%,X6S,CHA    I29 @SCM_LIB.SCM(SCH_1):PAGE13
   C31    1      A Q_CAP_0402-0.1UF,25V,10%,X7R,CA    I30 @SCM_LIB.SCM(SCH_1):PAGE13
   C32    1      A Q_CAP_C0402-1UF,25V,10%,X6S,CHA    I31 @SCM_LIB.SCM(SCH_1):PAGE13
   C33    1      A Q_CAP_0402-0.1UF,25V,10%,X7R,CA    I32 @SCM_LIB.SCM(SCH_1):PAGE13
    U5  J21 RVDD_J21 AST2600A3GP-AST2600A3-GP,SMLF,A   I188 @SCM_LIB.SCM(SCH_1):PAGE16
    U5  K21 RVDD_K21 AST2600A3GP-AST2600A3-GP,SMLF,A   I188 @SCM_LIB.SCM(SCH_1):PAGE16
    U5  L22 RVDD_L22 AST2600A3GP-AST2600A3-GP,SMLF,A   I188 @SCM_LIB.SCM(SCH_1):PAGE16
    U5  M22 RVDD_M22 AST2600A3GP-AST2600A3-GP,SMLF,A   I188 @SCM_LIB.SCM(SCH_1):PAGE16

P3V3_RGM @SCM_LIB.SCM(SCH_1):P3V3_RGM
   R34    1      A Q_RES_0402LF-4.7K,1%,1/16W,EMPA   I194 @SCM_LIB.SCM(SCH_1):PAGE11
  R212    1      A Q_RES_0402LF-4.7K,1%,1/16W,CHIA    I21 @SCM_LIB.SCM(SCH_1):PAGE15
   C37    1      A Q_CAP_0402-0.1UF,25V,10%,X7R,CA    I24 @SCM_LIB.SCM(SCH_1):PAGE15
  OSC1    4    VDD OSC4_7X25000018-25MHZ,SMLF,MISA    I39 @SCM_LIB.SCM(SCH_1):PAGE15
  R211    1      A Q_RES_0402LF-10K,1%,1/16W,CHIPA    I51 @SCM_LIB.SCM(SCH_1):PAGE15
  R623    1      A Q_RES_0402LF-4.7K,1%,1/16W,EMPA   I152 @SCM_LIB.SCM(SCH_1):PAGE15
  R491    1      A Q_RES_0402LF-4.7K,1%,1/16W,EMPA   I346 @SCM_LIB.SCM(SCH_1):PAGE15
   C85    1      A Q_CAP_0402-0.1UF,25V,10%,X7R,CA   I120 @SCM_LIB.SCM(SCH_1):PAGE16
    U5  K11 PV33D_RGM_K11 AST2600A3GP-AST2600A3-GP,SMLF,A   I188 @SCM_LIB.SCM(SCH_1):PAGE16
    U5  K12 PV33D_RGM_K12 AST2600A3GP-AST2600A3-GP,SMLF,A   I188 @SCM_LIB.SCM(SCH_1):PAGE16
  R287    1      A Q_RES_0402LF-499,1%,1/16W,CHIPA     I5 @SCM_LIB.SCM(SCH_1):PAGE22
  R289    1      A Q_RES_0402LF-10K,1%,1/16W,CHIPA     I7 @SCM_LIB.SCM(SCH_1):PAGE22
  R291    1      A Q_RES_0402LF-4.7K,1%,1/16W,CHIA     I9 @SCM_LIB.SCM(SCH_1):PAGE22
   R31    1      A Q_RES_0402LF-4.7K,1%,1/16W,CHIA    I27 @SCM_LIB.SCM(SCH_1):PAGE23
   R32    1      A Q_RES_0402LF-4.7K,1%,1/16W,CHIA    I50 @SCM_LIB.SCM(SCH_1):PAGE23
   R86    1      A Q_RES_0402LF-0,5%,1/16W,CHIP,CA    I51 @SCM_LIB.SCM(SCH_1):PAGE23
  R754    1      A Q_RES_0402LF-4.7K,1%,1/16W,EMPA   I213 @SCM_LIB.SCM(SCH_1):PAGE27
  R758    1      A Q_RES_0402LF-4.7K,1%,1/16W,CHIA   I221 @SCM_LIB.SCM(SCH_1):PAGE30
  R203    1      A Q_RES_0402LF-10K,1%,1/16W,CHIPA   I117 @SCM_LIB.SCM(SCH_1):PAGE32
  R523    1      A Q_RES_0402LF-10K,1%,1/16W,CHIPA   I119 @SCM_LIB.SCM(SCH_1):PAGE32
  R204    1      A Q_RES_0402LF-10K,1%,1/16W,CHIPA   I120 @SCM_LIB.SCM(SCH_1):PAGE32
  R834    1      A Q_RES_0402LF-10K,1%,1/16W,EMPTA   I131 @SCM_LIB.SCM(SCH_1):PAGE32
  C251    1      A Q_CAP_0402-0.1UF,25V,10%,X7R,CA    I66 @SCM_LIB.SCM(SCH_1):PAGE52
   U14    1    OUT AP22811AW57-AP22811AW5-7,SMLF,A    I79 @SCM_LIB.SCM(SCH_1):PAGE52
  R709    1      A Q_RES_0402LF-2.2K,5%,1/16W,CHIA   I145 @SCM_LIB.SCM(SCH_1):PAGE52

P3V3_RTC_AUX @SCM_LIB.SCM(SCH_1):P3V3_RTC_AUX
   C83    1      A Q_CAP_0402-0.1UF,25V,10%,X7R,CA   I106 @SCM_LIB.SCM(SCH_1):PAGE16
    U5  V23 BATVDD AST2600A3GP-AST2600A3-GP,SMLF,A   I188 @SCM_LIB.SCM(SCH_1):PAGE16
   U48    3      C BAS70057F-BAS70-05-7-F,SMLF,ICA   I161 @SCM_LIB.SCM(SCH_1):PAGE50
  C196    1      A Q_CAP_C0402-1UF,25V,10%,X6S,CHA   I165 @SCM_LIB.SCM(SCH_1):PAGE50

P3V3_SENSOR @SCM_LIB.SCM(SCH_1):P3V3_SENSOR
  C299    1      A Q_CAP_0402-0.1UF,25V,10%,X7R,CA   I215 @SCM_LIB.SCM(SCH_1):PAGE15
  R789    2      B Q_RES_0402LF-2.87K,1%,1/16W,CHA   I219 @SCM_LIB.SCM(SCH_1):PAGE15
  R790    1      A Q_RES_0402LF-2K,1%,1/16W,CHIP,A   I220 @SCM_LIB.SCM(SCH_1):PAGE15
    U5 AE19 ADC2||GPIT2 AST2600A3GP-AST2600A3-GP,SMLF,A   I350 @SCM_LIB.SCM(SCH_1):PAGE15

P3V3_STBY_DACAV33 @SCM_LIB.SCM(SCH_1):P3V3_STBY_DACAV33
    U5  V21 DACAV33_V21 AST2600A3GP-AST2600A3-GP,SMLF,A   I188 @SCM_LIB.SCM(SCH_1):PAGE16
    U5  W21 DACAV33_W21 AST2600A3GP-AST2600A3-GP,SMLF,A   I188 @SCM_LIB.SCM(SCH_1):PAGE16
   C51    1      A Q_CAP_0402-0.1UF,25V,10%,X7R,CA   I145 @SCM_LIB.SCM(SCH_1):PAGE17
    L7    2      2 Q_INDUCTOR_SMLF-BLM18PG121SN1DA   I146 @SCM_LIB.SCM(SCH_1):PAGE17
   C48    1      A Q_CAP_C0402-1UF,25V,10%,X6S,CHA   I148 @SCM_LIB.SCM(SCH_1):PAGE17

P3V3_STBY_PLLAHVDD @SCM_LIB.SCM(SCH_1):P3V3_STBY_PLLAHVDD
    U5  H14 PLLAHVDD AST2600A3GP-AST2600A3-GP,SMLF,A   I188 @SCM_LIB.SCM(SCH_1):PAGE16
   C65    1      A Q_CAP_0402-0.1UF,25V,10%,X7R,CA   I139 @SCM_LIB.SCM(SCH_1):PAGE17
   C60    1      A Q_CAP_C0402-1UF,25V,10%,X6S,CHA   I141 @SCM_LIB.SCM(SCH_1):PAGE17
    L9    2      2 Q_INDUCTOR_SMLF-BLM18PG121SN1DB   I142 @SCM_LIB.SCM(SCH_1):PAGE17
    L2    2      2 Q_INDUCTOR_SMLF-BLM18PG121SN1DA   I272 @SCM_LIB.SCM(SCH_1):PAGE17

P3V_BAT_R @SCM_LIB.SCM(SCH_1):P3V_BAT_R
  C174    1      A Q_CAP_0402-0.1UF,25V,10%,EMPTYA   I503 @SCM_LIB.SCM(SCH_1):PAGE10
   GF1  B41 P3V0_BAT FCONN168_ME1016810202011_SCM-FA   I553 @SCM_LIB.SCM(SCH_1):PAGE10
  R777    1      A Q_RES_0402LF-200K,1%,1/16W,CHIA   I289 @SCM_LIB.SCM(SCH_1):PAGE15
   U48    1      B BAS70057F-BAS70-05-7-F,SMLF,ICA   I161 @SCM_LIB.SCM(SCH_1):PAGE50

P3V_BAT_R1 @SCM_LIB.SCM(SCH_1):P3V_BAT_R1
   Q11    D  DRAIN MOSFET_N_GSD-NX7002AK,SMLF,IC,A   I179 @SCM_LIB.SCM(SCH_1):PAGE15
  R777    2      B Q_RES_0402LF-200K,1%,1/16W,CHIA   I289 @SCM_LIB.SCM(SCH_1):PAGE15

P3V_BAT_SENSOR @SCM_LIB.SCM(SCH_1):P3V_BAT_SENSOR
   Q11    S SOURCE MOSFET_N_GSD-NX7002AK,SMLF,IC,A   I179 @SCM_LIB.SCM(SCH_1):PAGE15
  C275    1      A Q_CAP_0402-100PF,50V,5%,NPO,CHA   I180 @SCM_LIB.SCM(SCH_1):PAGE15
  R778    1      A Q_RES_0402LF-100K,1%,1/16W,CHIA   I181 @SCM_LIB.SCM(SCH_1):PAGE15
    U5 AE18 ADC7||GPIT7 AST2600A3GP-AST2600A3-GP,SMLF,A   I350 @SCM_LIB.SCM(SCH_1):PAGE15

P5V_AUX @SCM_LIB.SCM(SCH_1):P5V_AUX
  R787    1      A Q_RES_0402LF-5.36K,1%,1/16W,CHA   I223 @SCM_LIB.SCM(SCH_1):PAGE15
  R716    1      A Q_RES_0402LF-10K,1%,1/16W,CHIPA   I230 @SCM_LIB.SCM(SCH_1):PAGE17
  C202    1      A Q_CAP_0402-0.1UF,25V,10%,X7R,CA    I11 @SCM_LIB.SCM(SCH_1):PAGE23
  C203    1      A Q_CAP_0402-0.1UF,25V,10%,X7R,CA    I12 @SCM_LIB.SCM(SCH_1):PAGE23
   R18    1      A Q_RES_0402LF-0,5%,1/16W,CHIP,CA    I19 @SCM_LIB.SCM(SCH_1):PAGE23
   R27    1      A Q_RES_0603LF-0,5%,1/10W,EMPTY,A    I40 @SCM_LIB.SCM(SCH_1):PAGE23
   D11    A      A SCHOTTKY_AC-SS0530,SMLF,IC,BCSA    I41 @SCM_LIB.SCM(SCH_1):PAGE23
    D9    A      A SCHOTTKY_AC-SS0530,SMLF,EMPTY,A    I42 @SCM_LIB.SCM(SCH_1):PAGE23
   D16    1      A SCHOTTKY_12-SBA130Q,SMLF,EMPTYA   I161 @SCM_LIB.SCM(SCH_1):PAGE23
  C172    1      A Q_CAP_0402-470PF,50V,10%,X7R,TA    I35 @SCM_LIB.SCM(SCH_1):PAGE28
  C171    1      A Q_CAP_C0805-22UF,10V,20%,X6S,CA    I38 @SCM_LIB.SCM(SCH_1):PAGE28
  R376    1      A Q_RES_0402LF-4.7K,1%,1/16W,CHIA    I62 @SCM_LIB.SCM(SCH_1):PAGE28
   U10    1     IN NCP380HSNAJAAT1G-NCP380HSNAJAAA   I179 @SCM_LIB.SCM(SCH_1):PAGE28
  R814    1      A Q_RES_0402LF-10K,1%,1/16W,CHIPA    I36 @SCM_LIB.SCM(SCH_1):PAGE49
  R815    1      A Q_RES_0402LF-10K,1%,1/16W,CHIPA    I40 @SCM_LIB.SCM(SCH_1):PAGE49
  R568    2      B Q_RES_0402LF-220,1%,1/16W,CHIPA    I59 @SCM_LIB.SCM(SCH_1):PAGE49
  R569    2      B Q_RES_0402LF-220,1%,1/16W,CHIPA    I60 @SCM_LIB.SCM(SCH_1):PAGE49
 PC272    2      B Q_CAP_C0402-68PF,50V,5%,COG,CHA    I27 @SCM_LIB.SCM(SCH_1):PAGE51
  PL34    2      2 Q_INDUCTOR_SMLF-4.7UH,IND,CV-4A    I28 @SCM_LIB.SCM(SCH_1):PAGE51
 PR527    2      B Q_RES_0402LF-91K,1%,1/16W,CHIPA    I30 @SCM_LIB.SCM(SCH_1):PAGE51
 PC212    1      A Q_CAP_0402-0.1UF,25V,10%,X7R,CA    I31 @SCM_LIB.SCM(SCH_1):PAGE51
 PC213    1      A Q_CAP_C0805-22UF,10V,20%,X6S,CA    I32 @SCM_LIB.SCM(SCH_1):PAGE51
 PC214    1      A Q_CAP_C0805-22UF,10V,20%,X6S,CA    I33 @SCM_LIB.SCM(SCH_1):PAGE51
 PC215    1      A Q_CAP_C0805-22UF,10V,20%,X6S,CA    I36 @SCM_LIB.SCM(SCH_1):PAGE51
 PC217    1      A Q_CAP_C0805-22UF,10V,20%,X6S,CA    I37 @SCM_LIB.SCM(SCH_1):PAGE51
   U39   10    VDD RT9059GQW-RT9059GQW,SMLF,IC,ALA    I60 @SCM_LIB.SCM(SCH_1):PAGE53
   U41   10    VDD RT9059GQW-RT9059GQW,SMLF,IC,ALA    I96 @SCM_LIB.SCM(SCH_1):PAGE54
 PR275    1      A Q_RES_0402LF-0,5%,1/16W,EMPTY,A    I48 @SCM_LIB.SCM(SCH_1):PAGE55
 PR205    1      A Q_RES_0402LF-0,5%,1/16W,EMPTY,A    I48 @SCM_LIB.SCM(SCH_1):PAGE56
  C292    1      A Q_CAP_C0402-1UF,25V,10%,X6S,CHA   I107 @SCM_LIB.SCM(SCH_1):PAGE54
  C287    1      A Q_CAP_C0402-1UF,25V,10%,X6S,CHA    I67 @SCM_LIB.SCM(SCH_1):PAGE53
   R80    2      B Q_RES_0402LF-220,1%,1/16W,CHIPA   I210 @SCM_LIB.SCM(SCH_1):PAGE50

P5V_AUX_CS @SCM_LIB.SCM(SCH_1):P5V_AUX_CS
 PR525    1      A Q_RES_0402LF-20.5K,1%,1/16W,CHA     I9 @SCM_LIB.SCM(SCH_1):PAGE51
  PU38    3     CS MPQ8633AGLEC807Z-MPQ8633AGLE-CA    I42 @SCM_LIB.SCM(SCH_1):PAGE51

P5V_AUX_FB @SCM_LIB.SCM(SCH_1):P5V_AUX_FB
 PR526    1      A Q_RES_0402LF-12.4K,1%,1/16W,CHA    I26 @SCM_LIB.SCM(SCH_1):PAGE51
 PC272    1      A Q_CAP_C0402-68PF,50V,5%,COG,CHA    I27 @SCM_LIB.SCM(SCH_1):PAGE51
 PR527    1      A Q_RES_0402LF-91K,1%,1/16W,CHIPA    I30 @SCM_LIB.SCM(SCH_1):PAGE51
  PU38    7     FB MPQ8633AGLEC807Z-MPQ8633AGLE-CA    I42 @SCM_LIB.SCM(SCH_1):PAGE51

P5V_AUX_REF @SCM_LIB.SCM(SCH_1):P5V_AUX_REF
 PC271    1      A Q_CAP_0402-0.1UF,25V,10%,X7R,CA    I22 @SCM_LIB.SCM(SCH_1):PAGE51
  PU38    5 TRK_REF MPQ8633AGLEC807Z-MPQ8633AGLE-CA    I42 @SCM_LIB.SCM(SCH_1):PAGE51

P5V_AUX_VCC @SCM_LIB.SCM(SCH_1):P5V_AUX_VCC
 PC208    1      A Q_CAP_C0402-1UF,25V,10%,X6S,CHA    I13 @SCM_LIB.SCM(SCH_1):PAGE51
 PR241    1      A Q_RES_0402LF-10K,1%,1/16W,CHIPA    I21 @SCM_LIB.SCM(SCH_1):PAGE51
  PU38   19    VCC MPQ8633AGLEC807Z-MPQ8633AGLE-CA    I42 @SCM_LIB.SCM(SCH_1):PAGE51

P5V_SENSOR @SCM_LIB.SCM(SCH_1):P5V_SENSOR
  C295    1      A Q_CAP_0402-0.1UF,25V,10%,X7R,CA   I207 @SCM_LIB.SCM(SCH_1):PAGE15
  R788    1      A Q_RES_0402LF-2K,1%,1/16W,CHIP,A   I211 @SCM_LIB.SCM(SCH_1):PAGE15
  R787    2      B Q_RES_0402LF-5.36K,1%,1/16W,CHA   I223 @SCM_LIB.SCM(SCH_1):PAGE15
    U5 AC18 ADC1||GPIT1 AST2600A3GP-AST2600A3-GP,SMLF,A   I350 @SCM_LIB.SCM(SCH_1):PAGE15

P5V_USB_REAR @SCM_LIB.SCM(SCH_1):P5V_USB_REAR
   U10    6    OUT NCP380HSNAJAAT1G-NCP380HSNAJAAA   I179 @SCM_LIB.SCM(SCH_1):PAGE28
   U38    4    VCC PRTR5V0U2X-PRTR5V0U2X,SMLF,IC,A    I99 @SCM_LIB.SCM(SCH_1):PAGE29
  C179    1      A Q_CAP_0402-470PF,50V,10%,X7R,TA   I193 @SCM_LIB.SCM(SCH_1):PAGE29
  C178    1      A Q_CAP_0402-470PF,50V,10%,X7R,TA   I194 @SCM_LIB.SCM(SCH_1):PAGE29
  C177    1      A Q_CAP_C1206-47UF,6.3V,20%,X6S,A   I219 @SCM_LIB.SCM(SCH_1):PAGE29
  C327    1      A Q_CAP_C1206-47UF,6.3V,20%,X6S,A   I220 @SCM_LIB.SCM(SCH_1):PAGE29
    J2    1   VBUS CONN9_GSB3111315HR-CONN9_GSB31A   I221 @SCM_LIB.SCM(SCH_1):PAGE29

PCH_BEEP_LED @SCM_LIB.SCM(SCH_1):PCH_BEEP_LED
    U8    2      A 74LVC1G126SE7-74LVC1G126SE-7,SA    I11 @SCM_LIB.SCM(SCH_1):PAGE49
  R811    1      A Q_RES_0402LF-0,5%,1/16W,EMPTY,A   I565 @SCM_LIB.SCM(SCH_1):PAGE10
  R847    1      A Q_RES_0402LF-0,5%,1/16W,CHIP,CA   I569 @SCM_LIB.SCM(SCH_1):PAGE10

PCH_BEEP_R_LED @SCM_LIB.SCM(SCH_1):PCH_BEEP_R_LED
   GF1  B69 PCIE_HPM_TXN_3 FCONN168_ME1016810202011_SCM-FA   I553 @SCM_LIB.SCM(SCH_1):PAGE10
  R811    2      B Q_RES_0402LF-0,5%,1/16W,EMPTY,A   I565 @SCM_LIB.SCM(SCH_1):PAGE10

PD_BIOS_MUX_EN_N @SCM_LIB.SCM(SCH_1):PD_BIOS_MUX_EN_N
   U30   15     E* IDTQS3VH257PAG_SMLF-IDTQS3VH25A   I271 @SCM_LIB.SCM(SCH_1):PAGE44
   U21   15     E* IDTQS3VH257PAG_SMLF-IDTQS3VH25A   I296 @SCM_LIB.SCM(SCH_1):PAGE44
  R467    1      A Q_RES_0402LF-2K,1%,1/16W,CHIP,A   I313 @SCM_LIB.SCM(SCH_1):PAGE44
  R870    2      B Q_RES_0402LF-4.7K,1%,1/16W,EMPA   I315 @SCM_LIB.SCM(SCH_1):PAGE44
  R405    2      B Q_RES_0402LF-33.2,1%,1/16W,CHIA   I430 @SCM_LIB.SCM(SCH_1):PAGE13

PD_BIOS_MUX_EN_R_N @SCM_LIB.SCM(SCH_1):PD_BIOS_MUX_EN_R_N
    U5  D26 RGMII4TXD2||NDTR3||GPIOE0 AST2600A3GP-AST2600A3-GP,SMLF,A   I363 @SCM_LIB.SCM(SCH_1):PAGE13
  R405    1      A Q_RES_0402LF-33.2,1%,1/16W,CHIA   I430 @SCM_LIB.SCM(SCH_1):PAGE13

PD_CLK_125M_PHY_BMC_RGMII @SCM_LIB.SCM(SCH_1):PD_CLK_125M_PHY_BMC_RGMII
  R273    1      A Q_RES_0402LF-100K,1%,1/16W,CHIA   I340 @SCM_LIB.SCM(SCH_1):PAGE13
    U5  A10 RGMIICK AST2600A3GP-AST2600A3-GP,SMLF,A   I363 @SCM_LIB.SCM(SCH_1):PAGE13

PD_FRU_WC_N @SCM_LIB.SCM(SCH_1):PD_FRU_WC_N
   U19    7    WC# M24128BWDW6TP-M24128-BWDW6TP,SA    I15 @SCM_LIB.SCM(SCH_1):PAGE26
   R15    1      A Q_RES_0402LF-1K,1%,1/16W,CHIP,A    I32 @SCM_LIB.SCM(SCH_1):PAGE26

PD_M_BMC_DDR4_PAR @SCM_LIB.SCM(SCH_1):PD_M_BMC_DDR4_PAR
    R4    1      A Q_RES_0402LF-1K,1%,1/16W,CHIP,A   I141 @SCM_LIB.SCM(SCH_1):PAGE20
    U1   T3    PAR K4A8G165WCBCTD-K4A8G165WC-BCTDA   I196 @SCM_LIB.SCM(SCH_1):PAGE20

PD_M_BMC_DDR4_TEN @SCM_LIB.SCM(SCH_1):PD_M_BMC_DDR4_TEN
    R5    1      A Q_RES_0402LF-1K,1%,1/16W,CHIP,A   I142 @SCM_LIB.SCM(SCH_1):PAGE20
    U1   N9    TEN K4A8G165WCBCTD-K4A8G165WC-BCTDA   I196 @SCM_LIB.SCM(SCH_1):PAGE20

PD_M_BMC_DDR4_ZQ @SCM_LIB.SCM(SCH_1):PD_M_BMC_DDR4_ZQ
    R6    1      A Q_RES_0402LF-240,1%,1/16W,CHIPA   I143 @SCM_LIB.SCM(SCH_1):PAGE20
    U1   F9     ZQ K4A8G165WCBCTD-K4A8G165WC-BCTDA   I196 @SCM_LIB.SCM(SCH_1):PAGE20

PD_SP_ENTEST @SCM_LIB.SCM(SCH_1):PD_SP_ENTEST
  R210    2      B Q_RES_0402LF-1K,1%,1/16W,CHIP,A    I47 @SCM_LIB.SCM(SCH_1):PAGE15
    U5  C10 ENTEST AST2600A3GP-AST2600A3-GP,SMLF,A   I350 @SCM_LIB.SCM(SCH_1):PAGE15

PECI_BMC @SCM_LIB.SCM(SCH_1):PECI_BMC
   GF1  B27 PECI_BMC FCONN168_ME1016810202011_SCM-FA   I553 @SCM_LIB.SCM(SCH_1):PAGE10
  R209    1      A Q_RES_0402LF-10K,1%,1/16W,EMPTA    I19 @SCM_LIB.SCM(SCH_1):PAGE15
  R216    2      B Q_RES_0402LF-49.9,1%,1/16W,CHIA   I389 @SCM_LIB.SCM(SCH_1):PAGE15

PECI_BMC_R @SCM_LIB.SCM(SCH_1):PECI_BMC_R
    U5 AF16   PECI AST2600A3GP-AST2600A3-GP,SMLF,A   I350 @SCM_LIB.SCM(SCH_1):PAGE15
  R216    1      A Q_RES_0402LF-49.9,1%,1/16W,CHIA   I389 @SCM_LIB.SCM(SCH_1):PAGE15

PGPPA_BMC_AUX @SCM_LIB.SCM(SCH_1):PGPPA_BMC_AUX
  R117    1      A Q_RES_0402LF-4.7K,1%,1/16W,EMPA     I2 @SCM_LIB.SCM(SCH_1):PAGE12
  R116    1      A Q_RES_0402LF-4.7K,1%,1/16W,CHIA     I3 @SCM_LIB.SCM(SCH_1):PAGE12
  R115    1      A Q_RES_0402LF-4.7K,1%,1/16W,EMPA     I4 @SCM_LIB.SCM(SCH_1):PAGE12
  R797    1      A Q_RES_0402LF-2.87K,1%,1/16W,CHA   I261 @SCM_LIB.SCM(SCH_1):PAGE15
    U5  W15  LPVDD AST2600A3GP-AST2600A3-GP,SMLF,A   I188 @SCM_LIB.SCM(SCH_1):PAGE16
   L17    2      2 Q_INDUCTOR_SMLF-BLM18EG121SN1DA   I176 @SCM_LIB.SCM(SCH_1):PAGE17
   C96    1      A Q_CAP_0402-0.1UF,25V,10%,X7R,CA   I178 @SCM_LIB.SCM(SCH_1):PAGE17
  C224    1      A Q_CAP_C0402-10UF,6.3V,20%,X6S,A   I180 @SCM_LIB.SCM(SCH_1):PAGE17

PGPPA_BMC_AUX_L @SCM_LIB.SCM(SCH_1):PGPPA_BMC_AUX_L
   L17    1      1 Q_INDUCTOR_SMLF-BLM18EG121SN1DA   I176 @SCM_LIB.SCM(SCH_1):PAGE17
    Q5    1      1 MOSFET_NCH_4D1S-NTGS4141NT1G,SA   I274 @SCM_LIB.SCM(SCH_1):PAGE17
    Q5    2      2 MOSFET_NCH_4D1S-NTGS4141NT1G,SA   I274 @SCM_LIB.SCM(SCH_1):PAGE17
    Q5    5      5 MOSFET_NCH_4D1S-NTGS4141NT1G,SA   I274 @SCM_LIB.SCM(SCH_1):PAGE17
    Q5    6      6 MOSFET_NCH_4D1S-NTGS4141NT1G,SA   I274 @SCM_LIB.SCM(SCH_1):PAGE17
  R645    2      B Q_RES_0603LF-0,5%,1/10W,EMPTY,A   I278 @SCM_LIB.SCM(SCH_1):PAGE17
  R646    1      A Q_RES_0603LF-0,5%,1/10W,EMPTY,A   I279 @SCM_LIB.SCM(SCH_1):PAGE17
    Q4    D      D MOSFET_PCH_GDS-NTR1P02LT1G,SMLA   I289 @SCM_LIB.SCM(SCH_1):PAGE17

PGPPA_BMC_AUX_SENSOR @SCM_LIB.SCM(SCH_1):PGPPA_BMC_AUX_SENSOR
  C314    1      A Q_CAP_0402-0.1UF,25V,10%,X7R,CA   I259 @SCM_LIB.SCM(SCH_1):PAGE15
  R797    2      B Q_RES_0402LF-2.87K,1%,1/16W,CHA   I261 @SCM_LIB.SCM(SCH_1):PAGE15
  R798    1      A Q_RES_0402LF-2K,1%,1/16W,CHIP,A   I262 @SCM_LIB.SCM(SCH_1):PAGE15
    U5 AB19 ADC5||GPIT5 AST2600A3GP-AST2600A3-GP,SMLF,A   I350 @SCM_LIB.SCM(SCH_1):PAGE15

PU_25M_BMC_CLK_EN @SCM_LIB.SCM(SCH_1):PU_25M_BMC_CLK_EN
  R212    2      B Q_RES_0402LF-4.7K,1%,1/16W,CHIA    I21 @SCM_LIB.SCM(SCH_1):PAGE15
  OSC1    1     OE OSC4_7X25000018-25MHZ,SMLF,MISA    I39 @SCM_LIB.SCM(SCH_1):PAGE15

PU_25M_FPGA_CLK_EN @SCM_LIB.SCM(SCH_1):PU_25M_FPGA_CLK_EN
  R806    2      B Q_RES_0402LF-4.7K,1%,1/16W,CHIA   I119 @SCM_LIB.SCM(SCH_1):PAGE34
  OSC2    1     OE OSC4_7X25000018-25MHZ,SMLF,MISA   I127 @SCM_LIB.SCM(SCH_1):PAGE34

PU_BMC_FWSPIABR_N @SCM_LIB.SCM(SCH_1):PU_BMC_FWSPIABR_N
  R239    2      B Q_RES_0402LF-4.7K,1%,1/16W,CHIA   I185 @SCM_LIB.SCM(SCH_1):PAGE13
  R401    1      A Q_RES_0402LF-33.2,1%,1/16W,CHIA   I374 @SCM_LIB.SCM(SCH_1):PAGE13

PU_BMC_FWSPIABR_N_R @SCM_LIB.SCM(SCH_1):PU_BMC_FWSPIABR_N_R
    U5 AC12 GPIOY6||FWSPIABR AST2600A3GP-AST2600A3-GP,SMLF,A   I363 @SCM_LIB.SCM(SCH_1):PAGE13
  R401    2      B Q_RES_0402LF-33.2,1%,1/16W,CHIA   I374 @SCM_LIB.SCM(SCH_1):PAGE13

PU_FPGA_CONFIG_DONE @SCM_LIB.SCM(SCH_1):PU_FPGA_CONFIG_DONE
   U25  C13 PT24D||DONE LCMXO3LF2100C5BG256C-LCMXO3LF-A     I1 @SCM_LIB.SCM(SCH_1):PAGE34
  R808    1      A Q_RES_0402LF-10K,1%,1/16W,CHIPA   I117 @SCM_LIB.SCM(SCH_1):PAGE34

PU_FPGA_NCONFIG @SCM_LIB.SCM(SCH_1):PU_FPGA_NCONFIG
  R809    1      A Q_RES_0402LF-10K,1%,1/16W,CHIPA   I115 @SCM_LIB.SCM(SCH_1):PAGE34
   U25  M10  PB21C LCMXO3LF2100C5BG256C-LCMXO3LF-A     I1 @SCM_LIB.SCM(SCH_1):PAGE36
  R748    1      A Q_RES_0402LF-0,5%,1/16W,CHIP,CA    I78 @SCM_LIB.SCM(SCH_1):PAGE36

PU_FPGA_NSTATUS @SCM_LIB.SCM(SCH_1):PU_FPGA_NSTATUS
   U25  A13 PT24C||INITN LCMXO3LF2100C5BG256C-LCMXO3LF-A     I1 @SCM_LIB.SCM(SCH_1):PAGE34
  R810    1      A Q_RES_0402LF-10K,1%,1/16W,CHIPA   I116 @SCM_LIB.SCM(SCH_1):PAGE34

PU_FWSPIWP_N @SCM_LIB.SCM(SCH_1):PU_FWSPIWP_N
  R240    2      B Q_RES_0402LF-4.7K,1%,1/16W,CHIA   I187 @SCM_LIB.SCM(SCH_1):PAGE13
  R402    1      A Q_RES_0402LF-33.2,1%,1/16W,CHIA   I373 @SCM_LIB.SCM(SCH_1):PAGE13

PU_FWSPIWP_N_R @SCM_LIB.SCM(SCH_1):PU_FWSPIWP_N_R
    U5 AB12 GPIOY7||FWSPIWP# AST2600A3GP-AST2600A3-GP,SMLF,A   I363 @SCM_LIB.SCM(SCH_1):PAGE13
  R402    2      B Q_RES_0402LF-33.2,1%,1/16W,CHIA   I373 @SCM_LIB.SCM(SCH_1):PAGE13

PU_J13_P1 @SCM_LIB.SCM(SCH_1):PU_J13_P1
   J13    1      1 SCONN3_212H9103GBR1-SCONN3_212B    I61 @SCM_LIB.SCM(SCH_1):PAGE31
  R630    2      B Q_RES_0402LF-4.7K,1%,1/16W,CHIA    I79 @SCM_LIB.SCM(SCH_1):PAGE31

PU_J1_P1 @SCM_LIB.SCM(SCH_1):PU_J1_P1
    J1    1      1 SCONN3_212H9103GBR1-SCONN3_212A   I169 @SCM_LIB.SCM(SCH_1):PAGE25
  R592    2      B Q_RES_0402LF-4.7K,1%,1/16W,CHIA   I171 @SCM_LIB.SCM(SCH_1):PAGE25

PU_PB25A @SCM_LIB.SCM(SCH_1):PU_PB25A
   U25  R12 PB25A||SN LCMXO3LF2100C5BG256C-LCMXO3LF-A     I1 @SCM_LIB.SCM(SCH_1):PAGE36
  R288    2      B Q_RES_0402LF-10K,1%,1/16W,CHIPA    I50 @SCM_LIB.SCM(SCH_1):PAGE36

PU_PT20D @SCM_LIB.SCM(SCH_1):PU_PT20D
   U25  B10 PT20D||PROGRAMN LCMXO3LF2100C5BG256C-LCMXO3LF-A     I1 @SCM_LIB.SCM(SCH_1):PAGE34
  R297    1      A Q_RES_0402LF-10K,1%,1/16W,CHIPA   I137 @SCM_LIB.SCM(SCH_1):PAGE34

PU_SPI1ABR @SCM_LIB.SCM(SCH_1):PU_SPI1ABR
  R241    2      B Q_RES_0402LF-4.7K,1%,1/16W,CHIA   I186 @SCM_LIB.SCM(SCH_1):PAGE13
    U5 AD10 GPIOZ1||SPI1ABR AST2600A3GP-AST2600A3-GP,SMLF,A   I363 @SCM_LIB.SCM(SCH_1):PAGE13

PU_SPI1WP_N @SCM_LIB.SCM(SCH_1):PU_SPI1WP_N
  R683    2      B Q_RES_0402LF-4.7K,1%,1/16W,CHIA   I188 @SCM_LIB.SCM(SCH_1):PAGE13
    U5 AE10 GPIOZ2||SPI1WP# AST2600A3GP-AST2600A3-GP,SMLF,A   I363 @SCM_LIB.SCM(SCH_1):PAGE13

PVCC1_AUX @SCM_LIB.SCM(SCH_1):PVCC1_AUX
 PR539    1      A Q_RES_0402LF-5.1,5%,1/16W,CHIPA     I8 @SCM_LIB.SCM(SCH_1):PAGE55
 PR274    2      B Q_RES_0402LF-0,5%,1/16W,CHIP,CA    I45 @SCM_LIB.SCM(SCH_1):PAGE55
 PR275    2      B Q_RES_0402LF-0,5%,1/16W,EMPTY,A    I48 @SCM_LIB.SCM(SCH_1):PAGE55

PVCC2_AUX @SCM_LIB.SCM(SCH_1):PVCC2_AUX
 PR541    1      A Q_RES_0402LF-5.1,5%,1/16W,CHIPA     I8 @SCM_LIB.SCM(SCH_1):PAGE56
 PR193    2      B Q_RES_0402LF-0,5%,1/16W,CHIP,CA    I47 @SCM_LIB.SCM(SCH_1):PAGE56
 PR205    2      B Q_RES_0402LF-0,5%,1/16W,EMPTY,A    I48 @SCM_LIB.SCM(SCH_1):PAGE56

PVCCA_AUX_PLD @SCM_LIB.SCM(SCH_1):PVCCA_AUX_PLD
   U25   A1 VCC_A1 LCMXO3LF2100C5BG256C-LCMXO3LF-A     I1 @SCM_LIB.SCM(SCH_1):PAGE40
   U25  A16 VCC_A16 LCMXO3LF2100C5BG256C-LCMXO3LF-A     I1 @SCM_LIB.SCM(SCH_1):PAGE40
   U25   G7 VCC_G7 LCMXO3LF2100C5BG256C-LCMXO3LF-A     I1 @SCM_LIB.SCM(SCH_1):PAGE40
   U25  G10 VCC_G10 LCMXO3LF2100C5BG256C-LCMXO3LF-A     I1 @SCM_LIB.SCM(SCH_1):PAGE40
   U25   K7 VCC_K7 LCMXO3LF2100C5BG256C-LCMXO3LF-A     I1 @SCM_LIB.SCM(SCH_1):PAGE40
   U25  K10 VCC_K10 LCMXO3LF2100C5BG256C-LCMXO3LF-A     I1 @SCM_LIB.SCM(SCH_1):PAGE40
   U25   T1 VCC_T1 LCMXO3LF2100C5BG256C-LCMXO3LF-A     I1 @SCM_LIB.SCM(SCH_1):PAGE40
   U25  T16 VCC_T16 LCMXO3LF2100C5BG256C-LCMXO3LF-A     I1 @SCM_LIB.SCM(SCH_1):PAGE40
   L19    2      2 Q_INDUCTOR_SMLF-BLM18EG121SN1DA   I107 @SCM_LIB.SCM(SCH_1):PAGE41
  C176    1      A Q_CAP_C0402-1UF,25V,10%,X6S,CHA   I108 @SCM_LIB.SCM(SCH_1):PAGE41
  C193    1      A Q_CAP_0402-0.1UF,25V,10%,X7R,CA   I109 @SCM_LIB.SCM(SCH_1):PAGE41
  C250    1      A Q_CAP_0402-0.1UF,25V,10%,X7R,CA   I115 @SCM_LIB.SCM(SCH_1):PAGE41
  C190    1      A Q_CAP_0402-0.1UF,25V,10%,X7R,CA   I116 @SCM_LIB.SCM(SCH_1):PAGE41
  C263    1      A Q_CAP_0402-0.1UF,25V,10%,X7R,CA   I117 @SCM_LIB.SCM(SCH_1):PAGE41
  C269    1      A Q_CAP_0402-0.1UF,25V,10%,X7R,CA   I118 @SCM_LIB.SCM(SCH_1):PAGE41
  C266    1      A Q_CAP_0402-0.1UF,25V,10%,X7R,CA   I119 @SCM_LIB.SCM(SCH_1):PAGE41
  C163    1      A Q_CAP_C0603-10UF,16V,20%,X6S,CA   I122 @SCM_LIB.SCM(SCH_1):PAGE41
  C286    1      A Q_CAP_C0402-0.01UF,50V,10%,EMPA   I123 @SCM_LIB.SCM(SCH_1):PAGE41

PVCCIO_AUX_PLD @SCM_LIB.SCM(SCH_1):PVCCIO_AUX_PLD
  R809    2      B Q_RES_0402LF-10K,1%,1/16W,CHIPA   I115 @SCM_LIB.SCM(SCH_1):PAGE34
  R810    2      B Q_RES_0402LF-10K,1%,1/16W,CHIPA   I116 @SCM_LIB.SCM(SCH_1):PAGE34
  R808    2      B Q_RES_0402LF-10K,1%,1/16W,CHIPA   I117 @SCM_LIB.SCM(SCH_1):PAGE34
  R183    2      B Q_RES_0402LF-0,5%,1/16W,CHIP,CA   I139 @SCM_LIB.SCM(SCH_1):PAGE34
  C256    1      A Q_CAP_C0402-1UF,25V,10%,X6S,CHA   I140 @SCM_LIB.SCM(SCH_1):PAGE34
  C257    1      A Q_CAP_0402-0.1UF,25V,10%,X7R,CA   I144 @SCM_LIB.SCM(SCH_1):PAGE34

PVCCIO_PECI_BMC @SCM_LIB.SCM(SCH_1):PVCCIO_PECI_BMC
   GF1  B28 PVCCIO_PECI FCONN168_ME1016810202011_SCM-FA   I553 @SCM_LIB.SCM(SCH_1):PAGE10
   C42    1      A Q_CAP_C0603-22UF,6.3V,20%,X6S,A   I117 @SCM_LIB.SCM(SCH_1):PAGE15
   C43    1      A Q_CAP_C0402-1UF,25V,10%,X6S,CHA   I119 @SCM_LIB.SCM(SCH_1):PAGE15
    U5 AA18 PECIVDD AST2600A3GP-AST2600A3-GP,SMLF,A   I350 @SCM_LIB.SCM(SCH_1):PAGE15

PWRGD_CPUPWRGD_LVC1 @SCM_LIB.SCM(SCH_1):PWRGD_CPUPWRGD_LVC1
    U5  W26 GPIOR6||TACH14 AST2600A3GP-AST2600A3-GP,SMLF,A   I350 @SCM_LIB.SCM(SCH_1):PAGE15
   U25  C11  PT21B LCMXO3LF2100C5BG256C-LCMXO3LF-A     I1 @SCM_LIB.SCM(SCH_1):PAGE34

PWRGD_DSW_PWROK @SCM_LIB.SCM(SCH_1):PWRGD_DSW_PWROK
  R643    1      A Q_RES_0402LF-33.2,1%,1/16W,CHIA   I344 @SCM_LIB.SCM(SCH_1):PAGE13
  R703    1      A Q_RES_0402LF-0,5%,1/16W,CHIP,CA   I127 @SCM_LIB.SCM(SCH_1):PAGE28
  R578    1      A Q_RES_0402LF-0,5%,1/16W,CHIP,CA     I8 @SCM_LIB.SCM(SCH_1):PAGE36
  R627    2      B Q_RES_0402LF-4.7K,1%,1/16W,CHIA     I7 @SCM_LIB.SCM(SCH_1):PAGE42

PWRGD_DSW_PWROK_R1 @SCM_LIB.SCM(SCH_1):PWRGD_DSW_PWROK_R1
  R643    2      B Q_RES_0402LF-33.2,1%,1/16W,CHIA   I344 @SCM_LIB.SCM(SCH_1):PAGE13
    U5  AA9 GPIOX1||SPI2CS1# AST2600A3GP-AST2600A3-GP,SMLF,A   I363 @SCM_LIB.SCM(SCH_1):PAGE13

PWRGD_DSW_PWROK_R2 @SCM_LIB.SCM(SCH_1):PWRGD_DSW_PWROK_R2
   U25   R3   PB3D LCMXO3LF2100C5BG256C-LCMXO3LF-A     I1 @SCM_LIB.SCM(SCH_1):PAGE36
  R578    2      B Q_RES_0402LF-0,5%,1/16W,CHIP,CA     I8 @SCM_LIB.SCM(SCH_1):PAGE36

PWRGD_DSW_PWROK_R3 @SCM_LIB.SCM(SCH_1):PWRGD_DSW_PWROK_R3
  R703    2      B Q_RES_0402LF-0,5%,1/16W,CHIP,CA   I127 @SCM_LIB.SCM(SCH_1):PAGE28
  R719    2      B Q_RES_0402LF-0,5%,1/16W,EMPTY,A   I128 @SCM_LIB.SCM(SCH_1):PAGE28
   U40   17    P14 PCA9555PW_SMLF-PCA9555PW,IC,TMA   I141 @SCM_LIB.SCM(SCH_1):PAGE28

PWRGD_EN_P3V3_R @SCM_LIB.SCM(SCH_1):PWRGD_EN_P3V3_R
   PU1    5     EN MPQ8626GDZ-MPQ8626GD-Z,SMLF,ICA    I82 @SCM_LIB.SCM(SCH_1):PAGE52
  R381    2      B Q_RES_0402LF-0,5%,1/16W,CHIP,CA    I97 @SCM_LIB.SCM(SCH_1):PAGE52
  R871    2      B Q_RES_0402LF-0,5%,1/16W,EMPTY,A   I137 @SCM_LIB.SCM(SCH_1):PAGE52

PWRGD_P1V0_AUX @SCM_LIB.SCM(SCH_1):PWRGD_P1V0_AUX
   R49    1      A Q_RES_0402LF-0,5%,1/16W,CHIP,CA    I72 @SCM_LIB.SCM(SCH_1):PAGE22
  R379    2      B Q_RES_0402LF-0,5%,1/16W,CHIP,CA    I36 @SCM_LIB.SCM(SCH_1):PAGE36
  R277    2      B Q_RES_0402LF-0,5%,1/16W,CHIP,CA    I54 @SCM_LIB.SCM(SCH_1):PAGE56

PWRGD_P1V0_AUX_DELAY @SCM_LIB.SCM(SCH_1):PWRGD_P1V0_AUX_DELAY
  R711    2      B Q_RES_0402LF-0,5%,1/16W,EMPTY,A    I49 @SCM_LIB.SCM(SCH_1):PAGE22
  R451    1      A Q_RES_0402LF-0,5%,1/16W,CHIP,CA    I74 @SCM_LIB.SCM(SCH_1):PAGE22
    U6    1     1A 74LVC2G07DW7-74LVC2G07DW-7,SMLA    I87 @SCM_LIB.SCM(SCH_1):PAGE22
   Q13    2     G1 MOSFET_NCH_DUAL-PJT138K,SMLF,IA   I218 @SCM_LIB.SCM(SCH_1):PAGE50
  R395    2      B Q_RES_0402LF-0,5%,1/16W,CHIP,CA   I448 @SCM_LIB.SCM(SCH_1):PAGE13

PWRGD_P1V0_AUX_DELAY_BUF @SCM_LIB.SCM(SCH_1):PWRGD_P1V0_AUX_DELAY_BUF
  R192    1      A Q_RES_0402LF-49.9,1%,1/16W,CHIA    I41 @SCM_LIB.SCM(SCH_1):PAGE22
    U6    6     1Y 74LVC2G07DW7-74LVC2G07DW-7,SMLA    I87 @SCM_LIB.SCM(SCH_1):PAGE22

PWRGD_P1V0_AUX_DELAY_R @SCM_LIB.SCM(SCH_1):PWRGD_P1V0_AUX_DELAY_R
   U28    4      E 74LVC1G66GV-74LVC1G66GV,SMLF,IA   I435 @SCM_LIB.SCM(SCH_1):PAGE13
  R395    1      A Q_RES_0402LF-0,5%,1/16W,CHIP,CA   I448 @SCM_LIB.SCM(SCH_1):PAGE13

PWRGD_P1V0_AUX_DELAY_R1 @SCM_LIB.SCM(SCH_1):PWRGD_P1V0_AUX_DELAY_R1
  R451    2      B Q_RES_0402LF-0,5%,1/16W,CHIP,CA    I74 @SCM_LIB.SCM(SCH_1):PAGE22
  R751    2      B Q_RES_0402LF-2K,1%,1/16W,CHIP,A    I83 @SCM_LIB.SCM(SCH_1):PAGE22
   U43    1 #RESET TPS3808G18DBVR-TPS3808G01DBVR,A    I90 @SCM_LIB.SCM(SCH_1):PAGE22

PWRGD_P1V0_AUX_R @SCM_LIB.SCM(SCH_1):PWRGD_P1V0_AUX_R
  PU42   13     PG NB695GDZ-NB695GD-Z,SMLF,IC,AL0A    I15 @SCM_LIB.SCM(SCH_1):PAGE56
 PR500    2      B Q_RES_0402LF-10K,1%,1/16W,CHIPA    I18 @SCM_LIB.SCM(SCH_1):PAGE56
  C156    1      A Q_CAP_C0402-0.001UF,50V,10%,EMA    I51 @SCM_LIB.SCM(SCH_1):PAGE56
  R277    1      A Q_RES_0402LF-0,5%,1/16W,CHIP,CA    I54 @SCM_LIB.SCM(SCH_1):PAGE56

PWRGD_P1V0_AUX_R1 @SCM_LIB.SCM(SCH_1):PWRGD_P1V0_AUX_R1
   U25   P9 PB16B||PCLKC2_1 LCMXO3LF2100C5BG256C-LCMXO3LF-A     I1 @SCM_LIB.SCM(SCH_1):PAGE36
  R379    1      A Q_RES_0402LF-0,5%,1/16W,CHIP,CA    I36 @SCM_LIB.SCM(SCH_1):PAGE36

PWRGD_P1V0_AUX_R2 @SCM_LIB.SCM(SCH_1):PWRGD_P1V0_AUX_R2
   R49    2      B Q_RES_0402LF-0,5%,1/16W,CHIP,CA    I72 @SCM_LIB.SCM(SCH_1):PAGE22
   U43    3    #MR TPS3808G18DBVR-TPS3808G01DBVR,A    I90 @SCM_LIB.SCM(SCH_1):PAGE22

PWRGD_P1V2_AUX @SCM_LIB.SCM(SCH_1):PWRGD_P1V2_AUX
  R323    2      B Q_RES_0402LF-0,5%,1/16W,CHIP,CA    I34 @SCM_LIB.SCM(SCH_1):PAGE36
  R276    2      B Q_RES_0402LF-0,5%,1/16W,CHIP,CA    I50 @SCM_LIB.SCM(SCH_1):PAGE55
   U53    2      A 74LVC1G08GW_SM-74LVC1G08GW,IC,A    I66 @SCM_LIB.SCM(SCH_1):PAGE56

PWRGD_P1V2_AUX_R @SCM_LIB.SCM(SCH_1):PWRGD_P1V2_AUX_R
  PU41   13     PG NB695GDZ-NB695GD-Z,SMLF,IC,AL0A    I15 @SCM_LIB.SCM(SCH_1):PAGE55
 PR498    2      B Q_RES_0402LF-10K,1%,1/16W,CHIPA    I18 @SCM_LIB.SCM(SCH_1):PAGE55
  R276    1      A Q_RES_0402LF-0,5%,1/16W,CHIP,CA    I50 @SCM_LIB.SCM(SCH_1):PAGE55
  C155    1      A Q_CAP_C0402-0.001UF,50V,10%,EMA    I52 @SCM_LIB.SCM(SCH_1):PAGE55
  R877    1      A Q_RES_0402LF-0,5%,1/16W,EMPTY,A    I70 @SCM_LIB.SCM(SCH_1):PAGE55

PWRGD_P1V2_AUX_R1 @SCM_LIB.SCM(SCH_1):PWRGD_P1V2_AUX_R1
   U25   T9 PB16A||PCLKT2_1 LCMXO3LF2100C5BG256C-LCMXO3LF-A     I1 @SCM_LIB.SCM(SCH_1):PAGE36
  R323    1      A Q_RES_0402LF-0,5%,1/16W,CHIP,CA    I34 @SCM_LIB.SCM(SCH_1):PAGE36

PWRGD_P1V2_AUX_R2 @SCM_LIB.SCM(SCH_1):PWRGD_P1V2_AUX_R2
  R877    2      B Q_RES_0402LF-0,5%,1/16W,EMPTY,A    I70 @SCM_LIB.SCM(SCH_1):PAGE55
  R878    1      A Q_RES_0402LF-0,5%,1/16W,EMPTY,A    I72 @SCM_LIB.SCM(SCH_1):PAGE56

PWRGD_P1V8_AUX @SCM_LIB.SCM(SCH_1):PWRGD_P1V8_AUX
  R321    2      B Q_RES_0402LF-0,5%,1/16W,CHIP,CA    I33 @SCM_LIB.SCM(SCH_1):PAGE36
  R275    1      A Q_RES_0402LF-0,5%,1/16W,CHIP,CA    I99 @SCM_LIB.SCM(SCH_1):PAGE54
  R764    1      A Q_RES_0402LF-0,5%,1/16W,EMPTY,A    I41 @SCM_LIB.SCM(SCH_1):PAGE55
   U42    2   IN_A MC74VHC1G32DTT1G-MC74VHC1G32DTA   I104 @SCM_LIB.SCM(SCH_1):PAGE52
  R529    1      A Q_RES_0402LF-100,1%,1/16W,CHIPA   I127 @SCM_LIB.SCM(SCH_1):PAGE52

PWRGD_P1V8_AUX_R @SCM_LIB.SCM(SCH_1):PWRGD_P1V8_AUX_R
   U41    5  PGOOD RT9059GQW-RT9059GQW,SMLF,IC,ALA    I96 @SCM_LIB.SCM(SCH_1):PAGE54
  R275    2      B Q_RES_0402LF-0,5%,1/16W,CHIP,CA    I99 @SCM_LIB.SCM(SCH_1):PAGE54
  C154    1      A Q_CAP_C0402-0.001UF,50V,10%,EMA   I100 @SCM_LIB.SCM(SCH_1):PAGE54
  R406    2      B Q_RES_0402LF-10K,1%,1/16W,CHIPA   I108 @SCM_LIB.SCM(SCH_1):PAGE54
  R874    2      B Q_RES_0402LF-0,5%,1/16W,EMPTY,A   I139 @SCM_LIB.SCM(SCH_1):PAGE54

PWRGD_P1V8_AUX_R1 @SCM_LIB.SCM(SCH_1):PWRGD_P1V8_AUX_R1
   U25   M8  PB16C LCMXO3LF2100C5BG256C-LCMXO3LF-A     I1 @SCM_LIB.SCM(SCH_1):PAGE36
  R321    1      A Q_RES_0402LF-0,5%,1/16W,CHIP,CA    I33 @SCM_LIB.SCM(SCH_1):PAGE36

PWRGD_P1V8_AUX_R2 @SCM_LIB.SCM(SCH_1):PWRGD_P1V8_AUX_R2
   U18    2      A 74LVC1G08GW_SM-74LVC1G08GW,IC,A   I114 @SCM_LIB.SCM(SCH_1):PAGE52
  C305    1      A Q_CAP_C0402-1UF,25V,10%,X6S,CHA   I125 @SCM_LIB.SCM(SCH_1):PAGE52
  R529    2      B Q_RES_0402LF-100,1%,1/16W,CHIPA   I127 @SCM_LIB.SCM(SCH_1):PAGE52

PWRGD_P1V8_AUX_R3 @SCM_LIB.SCM(SCH_1):PWRGD_P1V8_AUX_R3
  R869    1      A Q_RES_0402LF-0,5%,1/16W,EMPTY,A   I139 @SCM_LIB.SCM(SCH_1):PAGE52
  R874    1      A Q_RES_0402LF-0,5%,1/16W,EMPTY,A   I139 @SCM_LIB.SCM(SCH_1):PAGE54

PWRGD_P2V5_AUX @SCM_LIB.SCM(SCH_1):PWRGD_P2V5_AUX
  R320    2      B Q_RES_0402LF-0,5%,1/16W,CHIP,CA    I95 @SCM_LIB.SCM(SCH_1):PAGE35
   R35    1      A Q_RES_0402LF-0,5%,1/16W,CHIP,CA    I58 @SCM_LIB.SCM(SCH_1):PAGE53
  R873    2      B Q_RES_0402LF-0,5%,1/16W,EMPTY,A    I72 @SCM_LIB.SCM(SCH_1):PAGE53

PWRGD_P2V5_AUX_R @SCM_LIB.SCM(SCH_1):PWRGD_P2V5_AUX_R
   R35    2      B Q_RES_0402LF-0,5%,1/16W,CHIP,CA    I58 @SCM_LIB.SCM(SCH_1):PAGE53
   U39    5  PGOOD RT9059GQW-RT9059GQW,SMLF,IC,ALA    I60 @SCM_LIB.SCM(SCH_1):PAGE53
  C153    1      A Q_CAP_C0402-0.001UF,50V,10%,EMA    I64 @SCM_LIB.SCM(SCH_1):PAGE53
  R403    2      B Q_RES_0402LF-10K,1%,1/16W,CHIPA    I68 @SCM_LIB.SCM(SCH_1):PAGE53

PWRGD_P2V5_AUX_R1 @SCM_LIB.SCM(SCH_1):PWRGD_P2V5_AUX_R1
   U25  N14  PR14B LCMXO3LF2100C5BG256C-LCMXO3LF-A     I1 @SCM_LIB.SCM(SCH_1):PAGE35
  R320    1      A Q_RES_0402LF-0,5%,1/16W,CHIP,CA    I95 @SCM_LIB.SCM(SCH_1):PAGE35

PWRGD_P2V5_AUX_R3 @SCM_LIB.SCM(SCH_1):PWRGD_P2V5_AUX_R3
  R875    1      A Q_RES_0402LF-0,5%,1/16W,EMPTY,A   I137 @SCM_LIB.SCM(SCH_1):PAGE54
  R873    1      A Q_RES_0402LF-0,5%,1/16W,EMPTY,A    I72 @SCM_LIB.SCM(SCH_1):PAGE53

PWRGD_P3V3_AUX @SCM_LIB.SCM(SCH_1):PWRGD_P3V3_AUX
  R318    2      B Q_RES_0402LF-0,5%,1/16W,CHIP,CA    I98 @SCM_LIB.SCM(SCH_1):PAGE35
  R293    2      B Q_RES_0402LF-0,5%,1/16W,CHIP,CA    I95 @SCM_LIB.SCM(SCH_1):PAGE52
  R382    1      A Q_RES_0402LF-0,5%,1/16W,CHIP,CA    I65 @SCM_LIB.SCM(SCH_1):PAGE53

PWRGD_P3V3_AUX_R @SCM_LIB.SCM(SCH_1):PWRGD_P3V3_AUX_R
 PR242    2      B Q_RES_0402LF-10K,1%,1/16W,CHIPA    I13 @SCM_LIB.SCM(SCH_1):PAGE52
   PU1    9  PGOOD MPQ8626GDZ-MPQ8626GD-Z,SMLF,ICA    I82 @SCM_LIB.SCM(SCH_1):PAGE52
  C151    1      A Q_CAP_C0402-0.001UF,50V,10%,EMA    I93 @SCM_LIB.SCM(SCH_1):PAGE52
  R293    1      A Q_RES_0402LF-0,5%,1/16W,CHIP,CA    I95 @SCM_LIB.SCM(SCH_1):PAGE52

PWRGD_P3V3_AUX_R1 @SCM_LIB.SCM(SCH_1):PWRGD_P3V3_AUX_R1
   U25  N16  PR14A LCMXO3LF2100C5BG256C-LCMXO3LF-A     I1 @SCM_LIB.SCM(SCH_1):PAGE35
  R318    1      A Q_RES_0402LF-0,5%,1/16W,CHIP,CA    I98 @SCM_LIB.SCM(SCH_1):PAGE35

PWRGD_P3V3_AUX_R2 @SCM_LIB.SCM(SCH_1):PWRGD_P3V3_AUX_R2
   U39    6     EN RT9059GQW-RT9059GQW,SMLF,IC,ALA    I60 @SCM_LIB.SCM(SCH_1):PAGE53
  R382    2      B Q_RES_0402LF-0,5%,1/16W,CHIP,CA    I65 @SCM_LIB.SCM(SCH_1):PAGE53

PWRGD_P3V3_RGM @SCM_LIB.SCM(SCH_1):PWRGD_P3V3_RGM
  R322    2      B Q_RES_0402LF-0,5%,1/16W,CHIP,CA    I35 @SCM_LIB.SCM(SCH_1):PAGE36
   R99    2      B Q_RES_0402LF-0,5%,1/16W,CHIP,CA    I96 @SCM_LIB.SCM(SCH_1):PAGE52
   U52    2      A 74LVC1G08GW_SM-74LVC1G08GW,IC,A    I63 @SCM_LIB.SCM(SCH_1):PAGE55
  R530    1      A Q_RES_0402LF-100,1%,1/16W,CHIPA   I132 @SCM_LIB.SCM(SCH_1):PAGE54

PWRGD_P3V3_RGM_R @SCM_LIB.SCM(SCH_1):PWRGD_P3V3_RGM_R
  C252    1      A Q_CAP_C0402-1UF,25V,10%,EMPTY,A    I73 @SCM_LIB.SCM(SCH_1):PAGE52
   R99    1      A Q_RES_0402LF-0,5%,1/16W,CHIP,CA    I96 @SCM_LIB.SCM(SCH_1):PAGE52
  R872    1      A Q_RES_0402LF-0,5%,1/16W,EMPTY,A   I141 @SCM_LIB.SCM(SCH_1):PAGE52
  R709    2      B Q_RES_0402LF-2.2K,5%,1/16W,CHIA   I145 @SCM_LIB.SCM(SCH_1):PAGE52

PWRGD_P3V3_RGM_R1 @SCM_LIB.SCM(SCH_1):PWRGD_P3V3_RGM_R1
   U25   N9  PB16D LCMXO3LF2100C5BG256C-LCMXO3LF-A     I1 @SCM_LIB.SCM(SCH_1):PAGE36
  R322    1      A Q_RES_0402LF-0,5%,1/16W,CHIP,CA    I35 @SCM_LIB.SCM(SCH_1):PAGE36

PWRGD_P3V3_RGM_R2 @SCM_LIB.SCM(SCH_1):PWRGD_P3V3_RGM_R2
   U49    2   IN_A MC74VHC1G32DTT1G-MC74VHC1G32DTA   I116 @SCM_LIB.SCM(SCH_1):PAGE54
  C310    1      A Q_CAP_C0402-1UF,25V,10%,X6S,CHA   I130 @SCM_LIB.SCM(SCH_1):PAGE54
  R530    2      B Q_RES_0402LF-100,1%,1/16W,CHIPA   I132 @SCM_LIB.SCM(SCH_1):PAGE54

PWRGD_P3V3_RGM_R3 @SCM_LIB.SCM(SCH_1):PWRGD_P3V3_RGM_R3
  R872    2      B Q_RES_0402LF-0,5%,1/16W,EMPTY,A   I141 @SCM_LIB.SCM(SCH_1):PAGE52
  R876    1      A Q_RES_0402LF-0,5%,1/16W,EMPTY,A    I68 @SCM_LIB.SCM(SCH_1):PAGE55

PWRGD_P5V_AUX @SCM_LIB.SCM(SCH_1):PWRGD_P5V_AUX
  R292    2      B Q_RES_0402LF-0,5%,1/16W,CHIP,CA    I51 @SCM_LIB.SCM(SCH_1):PAGE51
   U49    1   IN_B MC74VHC1G32DTT1G-MC74VHC1G32DTA   I116 @SCM_LIB.SCM(SCH_1):PAGE54
   U53    1      B 74LVC1G08GW_SM-74LVC1G08GW,IC,A    I66 @SCM_LIB.SCM(SCH_1):PAGE56
   U52    1      B 74LVC1G08GW_SM-74LVC1G08GW,IC,A    I63 @SCM_LIB.SCM(SCH_1):PAGE55
   U42    1   IN_B MC74VHC1G32DTT1G-MC74VHC1G32DTA   I104 @SCM_LIB.SCM(SCH_1):PAGE52
   U18    1      B 74LVC1G08GW_SM-74LVC1G08GW,IC,A   I114 @SCM_LIB.SCM(SCH_1):PAGE52
   D23    1      1 Q_DIODE_SMLF-SDMK0340L-7-F,EMPA   I150 @SCM_LIB.SCM(SCH_1):PAGE35

PWRGD_P5V_AUX_R @SCM_LIB.SCM(SCH_1):PWRGD_P5V_AUX_R
 PR241    2      B Q_RES_0402LF-10K,1%,1/16W,CHIPA    I21 @SCM_LIB.SCM(SCH_1):PAGE51
  PU38    9  PGOOD MPQ8633AGLEC807Z-MPQ8633AGLE-CA    I42 @SCM_LIB.SCM(SCH_1):PAGE51
 PR245    1      A Q_RES_0402LF-100K,1%,1/16W,EMPA    I43 @SCM_LIB.SCM(SCH_1):PAGE51
  C150    1      A Q_CAP_C0402-0.001UF,50V,10%,EMA    I49 @SCM_LIB.SCM(SCH_1):PAGE51
  R292    1      A Q_RES_0402LF-0,5%,1/16W,CHIP,CA    I51 @SCM_LIB.SCM(SCH_1):PAGE51
  R868    1      A Q_RES_0402LF-0,5%,1/16W,EMPTY,A    I54 @SCM_LIB.SCM(SCH_1):PAGE51

PWRGD_P5V_AUX_R1 @SCM_LIB.SCM(SCH_1):PWRGD_P5V_AUX_R1
   U25  M15  PR13B LCMXO3LF2100C5BG256C-LCMXO3LF-A     I1 @SCM_LIB.SCM(SCH_1):PAGE35
   D23    2      2 Q_DIODE_SMLF-SDMK0340L-7-F,EMPA   I150 @SCM_LIB.SCM(SCH_1):PAGE35
  R886    2      B Q_RES_0402LF-4.7K,1%,1/16W,CHIA   I151 @SCM_LIB.SCM(SCH_1):PAGE35

PWRGD_PCH_PWROK @SCM_LIB.SCM(SCH_1):PWRGD_PCH_PWROK
    U5  T23 GPIOR5||TACH13 AST2600A3GP-AST2600A3-GP,SMLF,A   I350 @SCM_LIB.SCM(SCH_1):PAGE15
   U25   E7  PT12B LCMXO3LF2100C5BG256C-LCMXO3LF-A     I1 @SCM_LIB.SCM(SCH_1):PAGE34

PWRGD_PSU_AC_PWROK @SCM_LIB.SCM(SCH_1):PWRGD_PSU_AC_PWROK
  R243    1      A Q_RES_0402LF-33.2,1%,1/16W,CHIA   I293 @SCM_LIB.SCM(SCH_1):PAGE10
   R66    2      B Q_RES_0402LF-100K,1%,1/16W,CHIA   I181 @SCM_LIB.SCM(SCH_1):PAGE11
  R836    1      A Q_RES_0402LF-33.2,1%,1/16W,CHIA   I225 @SCM_LIB.SCM(SCH_1):PAGE13
  R711    1      A Q_RES_0402LF-0,5%,1/16W,EMPTY,A    I49 @SCM_LIB.SCM(SCH_1):PAGE22
  R719    1      A Q_RES_0402LF-0,5%,1/16W,EMPTY,A   I128 @SCM_LIB.SCM(SCH_1):PAGE28
  R837    1      A Q_RES_0402LF-33.2,1%,1/16W,CHIA   I158 @SCM_LIB.SCM(SCH_1):PAGE34

PWRGD_PSU_AC_PWROK_BMC @SCM_LIB.SCM(SCH_1):PWRGD_PSU_AC_PWROK_BMC
  R836    2      B Q_RES_0402LF-33.2,1%,1/16W,CHIA   I225 @SCM_LIB.SCM(SCH_1):PAGE13
    U5  A12 GPIOM2||NDSR1 AST2600A3GP-AST2600A3-GP,SMLF,A   I363 @SCM_LIB.SCM(SCH_1):PAGE13

PWRGD_PSU_AC_PWROK_PLD @SCM_LIB.SCM(SCH_1):PWRGD_PSU_AC_PWROK_PLD
   U25   C5  PT10B LCMXO3LF2100C5BG256C-LCMXO3LF-A     I1 @SCM_LIB.SCM(SCH_1):PAGE34
  R837    2      B Q_RES_0402LF-33.2,1%,1/16W,CHIA   I158 @SCM_LIB.SCM(SCH_1):PAGE34

PWRGD_PSU_AC_PWROK_R @SCM_LIB.SCM(SCH_1):PWRGD_PSU_AC_PWROK_R
  R243    2      B Q_RES_0402LF-33.2,1%,1/16W,CHIA   I293 @SCM_LIB.SCM(SCH_1):PAGE10
   GF1  A44 HPM_STBY_RDY FCONN168_ME1016810202011_SCM-FA   I553 @SCM_LIB.SCM(SCH_1):PAGE10

PWRGD_SYS_PWROK @SCM_LIB.SCM(SCH_1):PWRGD_SYS_PWROK
   GF1  A48 SYS_PWROK FCONN168_ME1016810202011_SCM-FA   I553 @SCM_LIB.SCM(SCH_1):PAGE10
   R40    2      B Q_RES_0402LF-2K,1%,1/16W,EMPTYA   I171 @SCM_LIB.SCM(SCH_1):PAGE11
  R840    1      A Q_RES_0402LF-33.2,1%,1/16W,CHIA   I295 @SCM_LIB.SCM(SCH_1):PAGE13
  R701    1      A Q_RES_0402LF-0,5%,1/16W,CHIP,CA   I125 @SCM_LIB.SCM(SCH_1):PAGE28
  R841    2      B Q_RES_0402LF-33.2,1%,1/16W,CHIA   I142 @SCM_LIB.SCM(SCH_1):PAGE35

PWRGD_SYS_PWROK_BMC @SCM_LIB.SCM(SCH_1):PWRGD_SYS_PWROK_BMC
  R840    2      B Q_RES_0402LF-33.2,1%,1/16W,CHIA   I295 @SCM_LIB.SCM(SCH_1):PAGE13
    U5  B12 GPIOM4||NDTR1 AST2600A3GP-AST2600A3-GP,SMLF,A   I363 @SCM_LIB.SCM(SCH_1):PAGE13

PWRGD_SYS_PWROK_PLD @SCM_LIB.SCM(SCH_1):PWRGD_SYS_PWROK_PLD
   U25  K15  PR10B LCMXO3LF2100C5BG256C-LCMXO3LF-A     I1 @SCM_LIB.SCM(SCH_1):PAGE35
  R841    1      A Q_RES_0402LF-33.2,1%,1/16W,CHIA   I142 @SCM_LIB.SCM(SCH_1):PAGE35

PWRGD_SYS_PWROK_R1 @SCM_LIB.SCM(SCH_1):PWRGD_SYS_PWROK_R1
  R701    2      B Q_RES_0402LF-0,5%,1/16W,CHIP,CA   I125 @SCM_LIB.SCM(SCH_1):PAGE28
   U40   15    P12 PCA9555PW_SMLF-PCA9555PW,IC,TMA   I141 @SCM_LIB.SCM(SCH_1):PAGE28

PWR_BTN_BMC_N @SCM_LIB.SCM(SCH_1):PWR_BTN_BMC_N
   R81    2      B Q_RES_0402LF-4.7K,1%,1/16W,CHIA   I245 @SCM_LIB.SCM(SCH_1):PAGE11
   U31    4      Y 74LVC1G07GW-74LVC1G07GW,SMLF,IA   I151 @SCM_LIB.SCM(SCH_1):PAGE50
   U15    2      A 74LVC1G08GW_SM-74LVC1G08GW,IC,A   I393 @SCM_LIB.SCM(SCH_1):PAGE15
  R225    2      B Q_RES_0402LF-100,1%,1/16W,CHIPA   I405 @SCM_LIB.SCM(SCH_1):PAGE15

PWR_LED @SCM_LIB.SCM(SCH_1):PWR_LED
  R316    2      B Q_RES_0402LF-0,5%,1/16W,CHIP,CA   I318 @SCM_LIB.SCM(SCH_1):PAGE15
  R317    2      B Q_RES_0402LF-0,5%,1/16W,CHIP,CA    I99 @SCM_LIB.SCM(SCH_1):PAGE35
  R839    1      A Q_RES_0402LF-8.2K,5%,1/16W,CHIA    I22 @SCM_LIB.SCM(SCH_1):PAGE49
   Q12    2     G1 MOSFET_DUAL_6P-2N7002KDW,SMLF,A    I24 @SCM_LIB.SCM(SCH_1):PAGE49

PWR_LED_BUF_N @SCM_LIB.SCM(SCH_1):PWR_LED_BUF_N
   Q12    6     D1 MOSFET_DUAL_6P-2N7002KDW,SMLF,A    I24 @SCM_LIB.SCM(SCH_1):PAGE49
  R812    1      A Q_RES_0402LF-33.2,1%,1/16W,CHIA    I34 @SCM_LIB.SCM(SCH_1):PAGE49

PWR_LED_BUF_N_R @SCM_LIB.SCM(SCH_1):PWR_LED_BUF_N_R
  R812    2      B Q_RES_0402LF-33.2,1%,1/16W,CHIA    I34 @SCM_LIB.SCM(SCH_1):PAGE49
  R814    2      B Q_RES_0402LF-10K,1%,1/16W,CHIPA    I36 @SCM_LIB.SCM(SCH_1):PAGE49
  C326    1      A Q_CAP_0402-470PF,50V,10%,X7R,TA    I38 @SCM_LIB.SCM(SCH_1):PAGE49
   D14    C      C Q_LED_THLF-LED_BLUE,HV-312470/A    I94 @SCM_LIB.SCM(SCH_1):PAGE49

PWR_LED_CPLD @SCM_LIB.SCM(SCH_1):PWR_LED_CPLD
   U25  M14  PR13A LCMXO3LF2100C5BG256C-LCMXO3LF-A     I1 @SCM_LIB.SCM(SCH_1):PAGE35
  R317    1      A Q_RES_0402LF-0,5%,1/16W,CHIP,CA    I99 @SCM_LIB.SCM(SCH_1):PAGE35

PWR_LED_P5V_AUX @SCM_LIB.SCM(SCH_1):PWR_LED_P5V_AUX
  C321    1      A Q_CAP_0402-0.1UF,25V,10%,X7R,CA    I43 @SCM_LIB.SCM(SCH_1):PAGE49
  R568    1      A Q_RES_0402LF-220,1%,1/16W,CHIPA    I59 @SCM_LIB.SCM(SCH_1):PAGE49
   D14    A      A Q_LED_THLF-LED_BLUE,HV-312470/A    I94 @SCM_LIB.SCM(SCH_1):PAGE49

Q7_D @SCM_LIB.SCM(SCH_1):Q7_D
   R42    2      B Q_RES_0402LF-4.7K,1%,1/16W,CHIA   I222 @SCM_LIB.SCM(SCH_1):PAGE27
    Q7    D      D 2N7002A7-2N7002A-7,SMLF,IC,BAMA   I243 @SCM_LIB.SCM(SCH_1):PAGE27

QSPI_2_PLD_CLK @SCM_LIB.SCM(SCH_1):QSPI_2_PLD_CLK
   GF1  B43 QSPI1_CLK FCONN168_ME1016810202011_SCM-FA   I553 @SCM_LIB.SCM(SCH_1):PAGE10
  R678    2      B Q_RES_0402LF-33.2,1%,1/16W,EMPA   I239 @SCM_LIB.SCM(SCH_1):PAGE13

QSPI_2_PLD_IO0 @SCM_LIB.SCM(SCH_1):QSPI_2_PLD_IO0
   GF1  B45 QSPI1_D0 FCONN168_ME1016810202011_SCM-FA   I553 @SCM_LIB.SCM(SCH_1):PAGE10
  R679    2      B Q_RES_0402LF-33.2,1%,1/16W,EMPA   I247 @SCM_LIB.SCM(SCH_1):PAGE13

QSPI_2_PLD_IO1 @SCM_LIB.SCM(SCH_1):QSPI_2_PLD_IO1
   GF1  B46 QSPI1_D1 FCONN168_ME1016810202011_SCM-FA   I553 @SCM_LIB.SCM(SCH_1):PAGE10
  R680    2      B Q_RES_0402LF-33.2,1%,1/16W,EMPA   I248 @SCM_LIB.SCM(SCH_1):PAGE13

QSPI_2_PLD_IO2 @SCM_LIB.SCM(SCH_1):QSPI_2_PLD_IO2
   GF1  B47 QSPI1_D2 FCONN168_ME1016810202011_SCM-FA   I553 @SCM_LIB.SCM(SCH_1):PAGE10
  R681    2      B Q_RES_0402LF-33.2,1%,1/16W,EMPA   I245 @SCM_LIB.SCM(SCH_1):PAGE13

QSPI_2_PLD_IO3 @SCM_LIB.SCM(SCH_1):QSPI_2_PLD_IO3
   GF1  B48 QSPI1_D3 FCONN168_ME1016810202011_SCM-FA   I553 @SCM_LIB.SCM(SCH_1):PAGE10
  R682    2      B Q_RES_0402LF-33.2,1%,1/16W,EMPA   I246 @SCM_LIB.SCM(SCH_1):PAGE13

RD_N @SCM_LIB.SCM(SCH_1):RD_N
   U54    6   RD_N 74LVC1G74DP-74LVC1G74DP,SMLF,IA   I138 @SCM_LIB.SCM(SCH_1):PAGE25
  R548    2      B Q_RES_0402LF-33.2,1%,1/16W,CHIA   I172 @SCM_LIB.SCM(SCH_1):PAGE25

REAR_AC_PWR_BMC_BTN_N @SCM_LIB.SCM(SCH_1):REAR_AC_PWR_BMC_BTN_N
   U57    2      A 74LVC1G07GW-74LVC1G07GW,SMLF,IA   I278 @SCM_LIB.SCM(SCH_1):PAGE50
  R883    2      B Q_RES_0402LF-8.2K,5%,1/16W,EMPA   I284 @SCM_LIB.SCM(SCH_1):PAGE50
  C335    1      A Q_CAP_C0402-1UF,25V,10%,X6S,CHA   I285 @SCM_LIB.SCM(SCH_1):PAGE50
  R882    2      B Q_RES_0402LF-0,5%,1/16W,CHIP,CA   I286 @SCM_LIB.SCM(SCH_1):PAGE50

REAR_AC_PWR_BTN @SCM_LIB.SCM(SCH_1):REAR_AC_PWR_BTN
  R470    1      A Q_RES_0402LF-0,5%,1/16W,EMPTY,A   I241 @SCM_LIB.SCM(SCH_1):PAGE50
  R471    1      A Q_RES_0402LF-0,5%,1/16W,CHIP,CA   I242 @SCM_LIB.SCM(SCH_1):PAGE50
   D10    A      A DIODE_BIDIRECTIONAL-UCLAMP0511A   I244 @SCM_LIB.SCM(SCH_1):PAGE50
  C181    1      A Q_CAP_0402-0.1UF,25V,10%,X7R,CA   I246 @SCM_LIB.SCM(SCH_1):PAGE50
  R882    1      A Q_RES_0402LF-0,5%,1/16W,CHIP,CA   I286 @SCM_LIB.SCM(SCH_1):PAGE50
   SW8    2      2 SW_PUSHBUTTON4P_12_G34_H2-SW4SA   I293 @SCM_LIB.SCM(SCH_1):PAGE50

REAR_AC_PWR_BTN_N @SCM_LIB.SCM(SCH_1):REAR_AC_PWR_BTN_N
   U16    2      A 74LVC1G07GW-74LVC1G07GW,SMLF,EA   I227 @SCM_LIB.SCM(SCH_1):PAGE50
  R391    2      B Q_RES_0402LF-8.2K,5%,1/16W,EMPA   I235 @SCM_LIB.SCM(SCH_1):PAGE50
   C28    1      A Q_CAP_C0402-1UF,25V,10%,EMPTY,A   I236 @SCM_LIB.SCM(SCH_1):PAGE50
  R470    2      B Q_RES_0402LF-0,5%,1/16W,EMPTY,A   I241 @SCM_LIB.SCM(SCH_1):PAGE50

REAR_ID_RST_BTN_N @SCM_LIB.SCM(SCH_1):REAR_ID_RST_BTN_N
   U32    2      A 74LVC1G17GW-74LVC1G17GW,SMLF,IA    I49 @SCM_LIB.SCM(SCH_1):PAGE50
  C199    1      A Q_CAP_C0402-1UF,25V,10%,X6S,CHA    I55 @SCM_LIB.SCM(SCH_1):PAGE50
  R504    2      B Q_RES_0402LF-8.2K,5%,1/16W,CHIA    I82 @SCM_LIB.SCM(SCH_1):PAGE50
  R733    1      A Q_RES_0402LF-0,5%,1/16W,CHIP,CA   I154 @SCM_LIB.SCM(SCH_1):PAGE50
   SW7    2      2 SW_PUSHBUTTON4P_12_G34_H2-SW4SA   I204 @SCM_LIB.SCM(SCH_1):PAGE50

REAR_PWR_BTN_N @SCM_LIB.SCM(SCH_1):REAR_PWR_BTN_N
  C198    1      A Q_CAP_C0402-1UF,25V,10%,X6S,CHA    I44 @SCM_LIB.SCM(SCH_1):PAGE50
  R768    2      B Q_RES_0402LF-8.2K,5%,1/16W,CHIA    I89 @SCM_LIB.SCM(SCH_1):PAGE50
   U31    2      A 74LVC1G07GW-74LVC1G07GW,SMLF,IA   I151 @SCM_LIB.SCM(SCH_1):PAGE50
  R734    1      A Q_RES_0402LF-0,5%,1/16W,CHIP,CA   I152 @SCM_LIB.SCM(SCH_1):PAGE50
   SW6    2      2 SW_PUSHBUTTON4P_12_G34_H2-SW4SA   I292 @SCM_LIB.SCM(SCH_1):PAGE50

RMII_CSRDV @SCM_LIB.SCM(SCH_1):RMII_CSRDV
   GF1  B19 NCSI_CRS_DV FCONN168_ME1016810202011_SCM-FA   I553 @SCM_LIB.SCM(SCH_1):PAGE10
  R161    2      B Q_RES_0402LF-4.7K,1%,1/16W,CHIA   I218 @SCM_LIB.SCM(SCH_1):PAGE11
    U5  B25 RGMII4RXD2||RMII4CRSDV||NDTR4||GPIOE6 AST2600A3GP-AST2600A3-GP,SMLF,A   I363 @SCM_LIB.SCM(SCH_1):PAGE13

RMII_OCP_RCLKI @SCM_LIB.SCM(SCH_1):RMII_OCP_RCLKI
   GF1  B18 NCSI_CLK FCONN168_ME1016810202011_SCM-FA   I553 @SCM_LIB.SCM(SCH_1):PAGE10
   U28    1      Y 74LVC1G66GV-74LVC1G66GV,SMLF,IA   I435 @SCM_LIB.SCM(SCH_1):PAGE13

RMII_OCP_RCLKI_ISO @SCM_LIB.SCM(SCH_1):RMII_OCP_RCLKI_ISO
   U28    2      Z 74LVC1G66GV-74LVC1G66GV,SMLF,IA   I435 @SCM_LIB.SCM(SCH_1):PAGE13
  R392    1      A Q_RES_0402LF-0,5%,1/16W,CHIP,CA   I447 @SCM_LIB.SCM(SCH_1):PAGE13

RMII_OCP_RCLKI_R_ISO @SCM_LIB.SCM(SCH_1):RMII_OCP_RCLKI_R_ISO
    U5  C25 RGMII4RXCK||RMII4RCLKI||NCTS4||GPIOE2 AST2600A3GP-AST2600A3-GP,SMLF,A   I363 @SCM_LIB.SCM(SCH_1):PAGE13
  R392    2      B Q_RES_0402LF-0,5%,1/16W,CHIP,CA   I447 @SCM_LIB.SCM(SCH_1):PAGE13

RMII_RXD0 @SCM_LIB.SCM(SCH_1):RMII_RXD0
   GF1  B24 NCSI_RXD0 FCONN168_ME1016810202011_SCM-FA   I553 @SCM_LIB.SCM(SCH_1):PAGE10
    U5  C24 RGMII4RXD0||RMII4RXD0||NDSR4||GPIOE4 AST2600A3GP-AST2600A3-GP,SMLF,A   I363 @SCM_LIB.SCM(SCH_1):PAGE13

RMII_RXD1 @SCM_LIB.SCM(SCH_1):RMII_RXD1
   GF1  B25 NCSI_RXD1 FCONN168_ME1016810202011_SCM-FA   I553 @SCM_LIB.SCM(SCH_1):PAGE10
    U5  B26 RGMII4RXD1||RMII4RXD1||NRI4||GPIOE5 AST2600A3GP-AST2600A3-GP,SMLF,A   I363 @SCM_LIB.SCM(SCH_1):PAGE13

RMII_RXER @SCM_LIB.SCM(SCH_1):RMII_RXER
   GF1  B23 NCSI_RXER FCONN168_ME1016810202011_SCM-FA   I553 @SCM_LIB.SCM(SCH_1):PAGE10
  R101    2      B Q_RES_0402LF-4.7K,1%,1/16W,CHIA   I214 @SCM_LIB.SCM(SCH_1):PAGE11
    U5  B24 RGMII4RXD3||RMII4RXER||NRTS4||GPIOE7 AST2600A3GP-AST2600A3-GP,SMLF,A   I363 @SCM_LIB.SCM(SCH_1):PAGE13

RMII_TXD0 @SCM_LIB.SCM(SCH_1):RMII_TXD0
   GF1  B21 NCSI_TXD0 FCONN168_ME1016810202011_SCM-FA   I553 @SCM_LIB.SCM(SCH_1):PAGE10
  R172    2      B Q_RES_0402LF-22,1%,1/16W,CHIP,A   I452 @SCM_LIB.SCM(SCH_1):PAGE13

RMII_TXD0_R @SCM_LIB.SCM(SCH_1):RMII_TXD0_R
    U5  E24 RGMII4TXD0||RMII4TXD0||NDSR3||GPIOD6 AST2600A3GP-AST2600A3-GP,SMLF,A   I363 @SCM_LIB.SCM(SCH_1):PAGE13
  R172    1      A Q_RES_0402LF-22,1%,1/16W,CHIP,A   I452 @SCM_LIB.SCM(SCH_1):PAGE13

RMII_TXD1 @SCM_LIB.SCM(SCH_1):RMII_TXD1
   GF1  B22 NCSI_TXD1 FCONN168_ME1016810202011_SCM-FA   I553 @SCM_LIB.SCM(SCH_1):PAGE10
  R173    2      B Q_RES_0402LF-22,1%,1/16W,CHIP,A   I453 @SCM_LIB.SCM(SCH_1):PAGE13

RMII_TXD1_R @SCM_LIB.SCM(SCH_1):RMII_TXD1_R
    U5  E25 RGMII4TXD1||RMII4TXD1||NRI3||GPIOD7 AST2600A3GP-AST2600A3-GP,SMLF,A   I363 @SCM_LIB.SCM(SCH_1):PAGE13
  R173    1      A Q_RES_0402LF-22,1%,1/16W,CHIP,A   I453 @SCM_LIB.SCM(SCH_1):PAGE13

RMII_TXEN @SCM_LIB.SCM(SCH_1):RMII_TXEN
   GF1  B20 NCSI_TXEN FCONN168_ME1016810202011_SCM-FA   I553 @SCM_LIB.SCM(SCH_1):PAGE10
  R103    2      B Q_RES_0402LF-4.7K,1%,1/16W,CHIA   I219 @SCM_LIB.SCM(SCH_1):PAGE11
  R171    2      B Q_RES_0402LF-22,1%,1/16W,CHIP,A   I451 @SCM_LIB.SCM(SCH_1):PAGE13

RMII_TXEN_R @SCM_LIB.SCM(SCH_1):RMII_TXEN_R
    U5  E23 RGMII4TXCTL||RMII4TXEN||NDCD3||GPIOD5 AST2600A3GP-AST2600A3-GP,SMLF,A   I363 @SCM_LIB.SCM(SCH_1):PAGE13
  R171    1      A Q_RES_0402LF-22,1%,1/16W,CHIP,A   I451 @SCM_LIB.SCM(SCH_1):PAGE13

RST_BMC_EXTRST_R1_N @SCM_LIB.SCM(SCH_1):RST_BMC_EXTRST_R1_N
  R290    2      B Q_RES_0402LF-47K,1%,1/16W,CHIPA     I8 @SCM_LIB.SCM(SCH_1):PAGE22
  R291    2      B Q_RES_0402LF-4.7K,1%,1/16W,CHIA     I9 @SCM_LIB.SCM(SCH_1):PAGE22
   U12    D  DRAIN MOSFET_N_SMLF-BSS138K,BSS138K,A    I14 @SCM_LIB.SCM(SCH_1):PAGE22
   U13    4  OUT_Y MC74VHC1G07DFT2G-MC74VHC1G07DFA    I89 @SCM_LIB.SCM(SCH_1):PAGE22

RST_BMC_EXTRST_R2_N @SCM_LIB.SCM(SCH_1):RST_BMC_EXTRST_R2_N
    Q1    C      3 MMBT39047F-MMBT3904-7-F,SMLF,IA     I2 @SCM_LIB.SCM(SCH_1):PAGE22
  R287    2      B Q_RES_0402LF-499,1%,1/16W,CHIPA     I5 @SCM_LIB.SCM(SCH_1):PAGE22
  R636    2      B Q_RES_0402LF-0,5%,1/16W,CHIP,CA    I10 @SCM_LIB.SCM(SCH_1):PAGE22
  R106    2      B Q_RES_0402LF-0,5%,1/16W,EMPTY,A    I12 @SCM_LIB.SCM(SCH_1):PAGE22
  R110    2      B Q_RES_0402LF-0,5%,1/16W,CHIP,CA   I116 @SCM_LIB.SCM(SCH_1):PAGE46

RST_BMC_EXTRST_R3_N @SCM_LIB.SCM(SCH_1):RST_BMC_EXTRST_R3_N
   J10    2      2 SCONN11_9192031111LF-SCONN11_9A   I113 @SCM_LIB.SCM(SCH_1):PAGE46
  R110    1      A Q_RES_0402LF-0,5%,1/16W,CHIP,CA   I116 @SCM_LIB.SCM(SCH_1):PAGE46

RST_BMC_HW @SCM_LIB.SCM(SCH_1):RST_BMC_HW
  R638    2      B Q_RES_0402LF-33.2,1%,1/16W,CHIA   I143 @SCM_LIB.SCM(SCH_1):PAGE35
  R282    2      B Q_RES_0402LF-0,5%,1/16W,CHIP,CA   I100 @SCM_LIB.SCM(SCH_1):PAGE22
  R887    2      B Q_RES_0402LF-4.7K,1%,1/16W,EMPA   I106 @SCM_LIB.SCM(SCH_1):PAGE22

RST_BMC_HW_OUT @SCM_LIB.SCM(SCH_1):RST_BMC_HW_OUT
   D17    1      1 Q_DIODE_SMLF-SDMK0340L-7-F,IC,A    I28 @SCM_LIB.SCM(SCH_1):PAGE22
  R633    2      B Q_RES_0402LF-1K,1%,1/16W,EMPTYA    I81 @SCM_LIB.SCM(SCH_1):PAGE22
   U58    4  OUT_Y MC74VHC1G32DTT1G-MC74VHC1G32DTA    I94 @SCM_LIB.SCM(SCH_1):PAGE22

RST_BMC_HW_R @SCM_LIB.SCM(SCH_1):RST_BMC_HW_R
   U25  J15   PR9A LCMXO3LF2100C5BG256C-LCMXO3LF-A     I1 @SCM_LIB.SCM(SCH_1):PAGE35
  R638    1      A Q_RES_0402LF-33.2,1%,1/16W,CHIA   I143 @SCM_LIB.SCM(SCH_1):PAGE35

RST_BMC_HW_R1 @SCM_LIB.SCM(SCH_1):RST_BMC_HW_R1
   U58    2   IN_A MC74VHC1G32DTT1G-MC74VHC1G32DTA    I94 @SCM_LIB.SCM(SCH_1):PAGE22
  R282    1      A Q_RES_0402LF-0,5%,1/16W,CHIP,CA   I100 @SCM_LIB.SCM(SCH_1):PAGE22

RST_BMC_LPC_ESPI_N @SCM_LIB.SCM(SCH_1):RST_BMC_LPC_ESPI_N
   GF1   B4 ESPI_RESET_N FCONN168_ME1016810202011_SCM-FA   I553 @SCM_LIB.SCM(SCH_1):PAGE10
  R117    2      B Q_RES_0402LF-4.7K,1%,1/16W,EMPA     I2 @SCM_LIB.SCM(SCH_1):PAGE12
  R120    1      A Q_RES_0402LF-33.2,1%,1/16W,CHIA    I33 @SCM_LIB.SCM(SCH_1):PAGE12
  R312    1      A Q_RES_0402LF-47K,1%,1/16W,CHIPA   I456 @SCM_LIB.SCM(SCH_1):PAGE12

RST_BMC_RSTBTN_OUT_N @SCM_LIB.SCM(SCH_1):RST_BMC_RSTBTN_OUT_N
  R566    2      B Q_RES_0402LF-0,5%,1/16W,CHIP,CA   I128 @SCM_LIB.SCM(SCH_1):PAGE15
  R717    2      B Q_RES_0402LF-4.7K,1%,1/16W,CHIA   I174 @SCM_LIB.SCM(SCH_1):PAGE15
   U25   C7  PT13B LCMXO3LF2100C5BG256C-LCMXO3LF-A     I1 @SCM_LIB.SCM(SCH_1):PAGE34

RST_BMC_RSTBTN_OUT_R_N @SCM_LIB.SCM(SCH_1):RST_BMC_RSTBTN_OUT_R_N
  R566    1      A Q_RES_0402LF-0,5%,1/16W,CHIP,CA   I128 @SCM_LIB.SCM(SCH_1):PAGE15
    U5 AA24 GPIOP3||PWM11||THRUOUT1 AST2600A3GP-AST2600A3-GP,SMLF,A   I350 @SCM_LIB.SCM(SCH_1):PAGE15

RST_BMC_SELF_HW @SCM_LIB.SCM(SCH_1):RST_BMC_SELF_HW
  R494    2      B Q_RES_0402LF-33.2,1%,1/16W,CHIA   I335 @SCM_LIB.SCM(SCH_1):PAGE13
  R271    1      A Q_RES_0402LF-0,5%,1/16W,CHIP,CA    I88 @SCM_LIB.SCM(SCH_1):PAGE35
  R450    1      A Q_RES_0402LF-0,5%,1/16W,CHIP,CA   I101 @SCM_LIB.SCM(SCH_1):PAGE22
  R888    2      B Q_RES_0402LF-1K,1%,1/16W,EMPTYA   I102 @SCM_LIB.SCM(SCH_1):PAGE22

RST_BMC_SELF_HW_D @SCM_LIB.SCM(SCH_1):RST_BMC_SELF_HW_D
  C161    1      A Q_CAP_C0402-1UF,25V,10%,X6S,CHA    I23 @SCM_LIB.SCM(SCH_1):PAGE22
   D17    2      2 Q_DIODE_SMLF-SDMK0340L-7-F,IC,A    I28 @SCM_LIB.SCM(SCH_1):PAGE22
  R313    1      A Q_RES_0402LF-470K,1%,1/16W,CHIA    I30 @SCM_LIB.SCM(SCH_1):PAGE22

RST_BMC_SELF_HW_D_C @SCM_LIB.SCM(SCH_1):RST_BMC_SELF_HW_D_C
   U12    G   GATE MOSFET_N_SMLF-BSS138K,BSS138K,A    I14 @SCM_LIB.SCM(SCH_1):PAGE22
  C161    2      B Q_CAP_C0402-1UF,25V,10%,X6S,CHA    I23 @SCM_LIB.SCM(SCH_1):PAGE22
  R314    1      A Q_RES_0402LF-100K,1%,1/16W,CHIA    I26 @SCM_LIB.SCM(SCH_1):PAGE22
  C173    1      A Q_CAP_0402-2200PF,50V,10%,X7R,A   I107 @SCM_LIB.SCM(SCH_1):PAGE22

RST_BMC_SELF_HW_R1 @SCM_LIB.SCM(SCH_1):RST_BMC_SELF_HW_R1
  R494    1      A Q_RES_0402LF-33.2,1%,1/16W,CHIA   I335 @SCM_LIB.SCM(SCH_1):PAGE13
    U5 AF11 GPIOY0||SALT5||WDTRST1# AST2600A3GP-AST2600A3-GP,SMLF,A   I363 @SCM_LIB.SCM(SCH_1):PAGE13

RST_BMC_SELF_HW_R2 @SCM_LIB.SCM(SCH_1):RST_BMC_SELF_HW_R2
   U25  G13   PR4D LCMXO3LF2100C5BG256C-LCMXO3LF-A     I1 @SCM_LIB.SCM(SCH_1):PAGE35
  R271    2      B Q_RES_0402LF-0,5%,1/16W,CHIP,CA    I88 @SCM_LIB.SCM(SCH_1):PAGE35
  R641    2      B Q_RES_0402LF-4.7K,1%,1/16W,EMPA    I53 @SCM_LIB.SCM(SCH_1):PAGE42

RST_BMC_SELF_HW_R3 @SCM_LIB.SCM(SCH_1):RST_BMC_SELF_HW_R3
   U58    1   IN_B MC74VHC1G32DTT1G-MC74VHC1G32DTA    I94 @SCM_LIB.SCM(SCH_1):PAGE22
  R450    2      B Q_RES_0402LF-0,5%,1/16W,CHIP,CA   I101 @SCM_LIB.SCM(SCH_1):PAGE22

RST_BMC_SRST_BUF_R1_N @SCM_LIB.SCM(SCH_1):RST_BMC_SRST_BUF_R1_N
  R315    2      B Q_RES_0402LF-0,5%,1/16W,EMPTY,A    I71 @SCM_LIB.SCM(SCH_1):PAGE22
   U13    2   IN_A MC74VHC1G07DFT2G-MC74VHC1G07DFA    I89 @SCM_LIB.SCM(SCH_1):PAGE22

RST_BMC_SRST_BUF_R_N @SCM_LIB.SCM(SCH_1):RST_BMC_SRST_BUF_R_N
  R192    2      B Q_RES_0402LF-49.9,1%,1/16W,CHIA    I41 @SCM_LIB.SCM(SCH_1):PAGE22
  C223    1      A Q_CAP_C0402-4700P,25V,10%,EMPTA    I46 @SCM_LIB.SCM(SCH_1):PAGE22
  R108    2      B Q_RES_0402LF-49.9,1%,1/16W,CHIA    I65 @SCM_LIB.SCM(SCH_1):PAGE22
  R124    2      B Q_RES_0402LF-2K,1%,1/16W,CHIP,A    I67 @SCM_LIB.SCM(SCH_1):PAGE22
  R125    1      A Q_RES_0402LF-100,1%,1/16W,CHIPA    I69 @SCM_LIB.SCM(SCH_1):PAGE22
  R315    1      A Q_RES_0402LF-0,5%,1/16W,EMPTY,A    I71 @SCM_LIB.SCM(SCH_1):PAGE22

RST_BMC_SRST_N @SCM_LIB.SCM(SCH_1):RST_BMC_SRST_N
  R491    2      B Q_RES_0402LF-4.7K,1%,1/16W,EMPA   I346 @SCM_LIB.SCM(SCH_1):PAGE15
    U5  E10  SRST# AST2600A3GP-AST2600A3-GP,SMLF,A   I350 @SCM_LIB.SCM(SCH_1):PAGE15
  R106    1      A Q_RES_0402LF-0,5%,1/16W,EMPTY,A    I12 @SCM_LIB.SCM(SCH_1):PAGE22
  R125    2      B Q_RES_0402LF-100,1%,1/16W,CHIPA    I69 @SCM_LIB.SCM(SCH_1):PAGE22

RST_ESPI_LPC_BMC_N @SCM_LIB.SCM(SCH_1):RST_ESPI_LPC_BMC_N
  R120    2      B Q_RES_0402LF-33.2,1%,1/16W,CHIA    I33 @SCM_LIB.SCM(SCH_1):PAGE12
    U5  AD8 GPIOW7||LPCRST#||ESPIRST# AST2600A3GP-AST2600A3-GP,SMLF,A   I436 @SCM_LIB.SCM(SCH_1):PAGE12

RST_EXTRST_N @SCM_LIB.SCM(SCH_1):RST_EXTRST_N
  R623    2      B Q_RES_0402LF-4.7K,1%,1/16W,EMPA   I152 @SCM_LIB.SCM(SCH_1):PAGE15
    U5  B10 EXTRST# AST2600A3GP-AST2600A3-GP,SMLF,A   I350 @SCM_LIB.SCM(SCH_1):PAGE15
  R636    1      A Q_RES_0402LF-0,5%,1/16W,CHIP,CA    I10 @SCM_LIB.SCM(SCH_1):PAGE22
  R447    2      B Q_RES_0402LF-0,5%,1/16W,CHIP,CA   I168 @SCM_LIB.SCM(SCH_1):PAGE34

RST_EXTRST_R_N @SCM_LIB.SCM(SCH_1):RST_EXTRST_R_N
   U25  A11  PT21A LCMXO3LF2100C5BG256C-LCMXO3LF-A     I1 @SCM_LIB.SCM(SCH_1):PAGE34
  R447    1      A Q_RES_0402LF-0,5%,1/16W,CHIP,CA   I168 @SCM_LIB.SCM(SCH_1):PAGE34

RST_MB_STBY_N @SCM_LIB.SCM(SCH_1):RST_MB_STBY_N
   GF1  A46 HPM_STBY_RST_N FCONN168_ME1016810202011_SCM-FA   I553 @SCM_LIB.SCM(SCH_1):PAGE10
  R263    1      A Q_RES_0402LF-33.2,1%,1/16W,CHIA   I141 @SCM_LIB.SCM(SCH_1):PAGE35

RST_MB_STBY_R_N @SCM_LIB.SCM(SCH_1):RST_MB_STBY_R_N
   U25  H11   PR9C LCMXO3LF2100C5BG256C-LCMXO3LF-A     I1 @SCM_LIB.SCM(SCH_1):PAGE35
  R263    2      B Q_RES_0402LF-33.2,1%,1/16W,CHIA   I141 @SCM_LIB.SCM(SCH_1):PAGE35

RST_PCA9548_SENSOR_N @SCM_LIB.SCM(SCH_1):RST_PCA9548_SENSOR_N
   U25   B4  PT11D LCMXO3LF2100C5BG256C-LCMXO3LF-A     I1 @SCM_LIB.SCM(SCH_1):PAGE34
  R169    2      B Q_RES_0402LF-4.7K,1%,1/16W,CHIA   I256 @SCM_LIB.SCM(SCH_1):PAGE11
   R70    2      B Q_RES_0402LF-33.2,1%,1/16W,CHIA   I419 @SCM_LIB.SCM(SCH_1):PAGE13

RST_PCA9548_SENSOR_R_N @SCM_LIB.SCM(SCH_1):RST_PCA9548_SENSOR_R_N
    U5  P23 GPIOS6||TXD11 AST2600A3GP-AST2600A3-GP,SMLF,A   I363 @SCM_LIB.SCM(SCH_1):PAGE13
   R70    1      A Q_RES_0402LF-33.2,1%,1/16W,CHIA   I419 @SCM_LIB.SCM(SCH_1):PAGE13

RST_PFR_OVR_RTC_R @SCM_LIB.SCM(SCH_1):RST_PFR_OVR_RTC_R
    U5  M25 GPIOA1||SDA11||MDIO3 AST2600A3GP-AST2600A3-GP,SMLF,A   I436 @SCM_LIB.SCM(SCH_1):PAGE12
   U25   T7 PB11A||PCLKT2_0 LCMXO3LF2100C5BG256C-LCMXO3LF-A     I1 @SCM_LIB.SCM(SCH_1):PAGE36

RST_PLTRST_N @SCM_LIB.SCM(SCH_1):RST_PLTRST_N
   GF1  A51 RST_PLTRST_BUF_N FCONN168_ME1016810202011_SCM-FA   I553 @SCM_LIB.SCM(SCH_1):PAGE10
   R34    2      B Q_RES_0402LF-4.7K,1%,1/16W,EMPA   I194 @SCM_LIB.SCM(SCH_1):PAGE11
  R118    2      B Q_RES_0402LF-100K,1%,1/16W,CHIA    I53 @SCM_LIB.SCM(SCH_1):PAGE12
  R168    1      A Q_RES_0402LF-33.2,1%,1/16W,CHIA   I268 @SCM_LIB.SCM(SCH_1):PAGE12
    U5   A7 PERST# AST2600A3GP-AST2600A3-GP,SMLF,A   I436 @SCM_LIB.SCM(SCH_1):PAGE12
  R702    1      A Q_RES_0402LF-0,5%,1/16W,CHIP,CA   I126 @SCM_LIB.SCM(SCH_1):PAGE28
  R503    2      B Q_RES_0402LF-0,5%,1/16W,CHIP,CA    I60 @SCM_LIB.SCM(SCH_1):PAGE46
  R718    1      A Q_RES_0402LF-33.2,1%,1/16W,CHIA   I157 @SCM_LIB.SCM(SCH_1):PAGE34

RST_PLTRST_R1_N @SCM_LIB.SCM(SCH_1):RST_PLTRST_R1_N
   U25   A4  PT10A LCMXO3LF2100C5BG256C-LCMXO3LF-A     I1 @SCM_LIB.SCM(SCH_1):PAGE34
  R718    2      B Q_RES_0402LF-33.2,1%,1/16W,CHIA   I157 @SCM_LIB.SCM(SCH_1):PAGE34

RST_PLTRST_R2_N @SCM_LIB.SCM(SCH_1):RST_PLTRST_R2_N
  R702    2      B Q_RES_0402LF-0,5%,1/16W,CHIP,CA   I126 @SCM_LIB.SCM(SCH_1):PAGE28
   U40   16    P13 PCA9555PW_SMLF-PCA9555PW,IC,TMA   I141 @SCM_LIB.SCM(SCH_1):PAGE28

RST_PLTRST_R_N @SCM_LIB.SCM(SCH_1):RST_PLTRST_R_N
  R168    2      B Q_RES_0402LF-33.2,1%,1/16W,CHIA   I268 @SCM_LIB.SCM(SCH_1):PAGE12
    U5  H24 RGMII3TXCK||RMII3RCLKO||GPIOC0 AST2600A3GP-AST2600A3-GP,SMLF,A   I363 @SCM_LIB.SCM(SCH_1):PAGE13

RST_PLTRST_TPM_N @SCM_LIB.SCM(SCH_1):RST_PLTRST_TPM_N
    J5    2      2 SCONN11_9192031111LF-SCONN11_9A    I56 @SCM_LIB.SCM(SCH_1):PAGE46
  R503    1      A Q_RES_0402LF-0,5%,1/16W,CHIP,CA    I60 @SCM_LIB.SCM(SCH_1):PAGE46

RST_ROT_CPU_N @SCM_LIB.SCM(SCH_1):RST_ROT_CPU_N
   GF1  A53 ROT_CPU_RST_N FCONN168_ME1016810202011_SCM-FA   I553 @SCM_LIB.SCM(SCH_1):PAGE10
  R828    2      B Q_RES_0402LF-4.7K,1%,1/16W,EMPA   I241 @SCM_LIB.SCM(SCH_1):PAGE11
   R60    2      B Q_RES_0402LF-33.2,1%,1/16W,CHIA   I382 @SCM_LIB.SCM(SCH_1):PAGE13
  R748    2      B Q_RES_0402LF-0,5%,1/16W,CHIP,CA    I78 @SCM_LIB.SCM(SCH_1):PAGE36
  R825    1      A Q_RES_0402LF-33.2,1%,1/16W,CHIA   I138 @SCM_LIB.SCM(SCH_1):PAGE35

RST_ROT_CPU_R1_N @SCM_LIB.SCM(SCH_1):RST_ROT_CPU_R1_N
    U5  G22 RGMII3TXD2||GPIOC4 AST2600A3GP-AST2600A3-GP,SMLF,A   I363 @SCM_LIB.SCM(SCH_1):PAGE13
   R60    1      A Q_RES_0402LF-33.2,1%,1/16W,CHIA   I382 @SCM_LIB.SCM(SCH_1):PAGE13

RST_ROT_CPU_R_N @SCM_LIB.SCM(SCH_1):RST_ROT_CPU_R_N
   U25  H12   PR5D LCMXO3LF2100C5BG256C-LCMXO3LF-A     I1 @SCM_LIB.SCM(SCH_1):PAGE35
  R825    2      B Q_RES_0402LF-33.2,1%,1/16W,CHIA   I138 @SCM_LIB.SCM(SCH_1):PAGE35

RST_RSMRST_N @SCM_LIB.SCM(SCH_1):RST_RSMRST_N
  R160    1      A Q_RES_0402LF-33.2,1%,1/16W,CHIA   I159 @SCM_LIB.SCM(SCH_1):PAGE13
   U25   A5  PT11A LCMXO3LF2100C5BG256C-LCMXO3LF-A     I1 @SCM_LIB.SCM(SCH_1):PAGE34
  R625    2      B Q_RES_0402LF-4.7K,1%,1/16W,CHIA    I17 @SCM_LIB.SCM(SCH_1):PAGE34

RST_RSMRST_R_N @SCM_LIB.SCM(SCH_1):RST_RSMRST_R_N
  R160    2      B Q_RES_0402LF-33.2,1%,1/16W,CHIA   I159 @SCM_LIB.SCM(SCH_1):PAGE13
    U5 AF14 GPIOV1||SIOS5# AST2600A3GP-AST2600A3-GP,SMLF,A   I363 @SCM_LIB.SCM(SCH_1):PAGE13

RST_SGPIO_RESET_BMC_N @SCM_LIB.SCM(SCH_1):RST_SGPIO_RESET_BMC_N
    U5  H23 RGMII3TXD1||RMII3TXD1||GPIOC3 AST2600A3GP-AST2600A3-GP,SMLF,A   I363 @SCM_LIB.SCM(SCH_1):PAGE13
  R688    1      A Q_RES_0402LF-33.2,1%,1/16W,CHIA   I383 @SCM_LIB.SCM(SCH_1):PAGE13

RST_SGPIO_RESET_N @SCM_LIB.SCM(SCH_1):RST_SGPIO_RESET_N
   GF1  B39 SGPIO_RESET_N FCONN168_ME1016810202011_SCM-FA   I553 @SCM_LIB.SCM(SCH_1):PAGE10
   R69    2      B Q_RES_0402LF-4.7K,1%,1/16W,CHIA   I227 @SCM_LIB.SCM(SCH_1):PAGE11
  R688    2      B Q_RES_0402LF-33.2,1%,1/16W,CHIA   I383 @SCM_LIB.SCM(SCH_1):PAGE13
  R691    2      B Q_RES_0402LF-33.2,1%,1/16W,CHIA   I148 @SCM_LIB.SCM(SCH_1):PAGE35

RST_SGPIO_RESET_R_N @SCM_LIB.SCM(SCH_1):RST_SGPIO_RESET_R_N
   U25  E16   PR3A LCMXO3LF2100C5BG256C-LCMXO3LF-A     I1 @SCM_LIB.SCM(SCH_1):PAGE35
  R691    1      A Q_RES_0402LF-33.2,1%,1/16W,CHIA   I148 @SCM_LIB.SCM(SCH_1):PAGE35

RST_SPI_BMC_FLASH_R1_N @SCM_LIB.SCM(SCH_1):RST_SPI_BMC_FLASH_R1_N
    J4   21     21 SCONN67_NASA0S6730TS67-SCONN67A    I84 @SCM_LIB.SCM(SCH_1):PAGE21
  R562    1      A Q_RES_0402LF-33.2,1%,1/16W,CHIA   I180 @SCM_LIB.SCM(SCH_1):PAGE21

RST_SPI_BMC_FLASH_R2_N @SCM_LIB.SCM(SCH_1):RST_SPI_BMC_FLASH_R2_N
    J4   19     19 SCONN67_NASA0S6730TS67-SCONN67A    I84 @SCM_LIB.SCM(SCH_1):PAGE21
  R561    1      A Q_RES_0402LF-33.2,1%,1/16W,EMPA   I181 @SCM_LIB.SCM(SCH_1):PAGE21
   R90    2      B Q_RES_0402LF-4.7K,1%,1/16W,EMPA   I182 @SCM_LIB.SCM(SCH_1):PAGE21

RST_SPI_FLASH_BUF_N @SCM_LIB.SCM(SCH_1):RST_SPI_FLASH_BUF_N
  R563    2      B Q_RES_0402LF-4.7K,1%,1/16W,CHIA     I3 @SCM_LIB.SCM(SCH_1):PAGE25
  R827    2      B Q_RES_0402LF-33.2,1%,1/16W,CHIA    I73 @SCM_LIB.SCM(SCH_1):PAGE25
  R562    2      B Q_RES_0402LF-33.2,1%,1/16W,CHIA   I180 @SCM_LIB.SCM(SCH_1):PAGE21
  R561    2      B Q_RES_0402LF-33.2,1%,1/16W,EMPA   I181 @SCM_LIB.SCM(SCH_1):PAGE21

RST_SPI_FLASH_BUF_R3_N @SCM_LIB.SCM(SCH_1):RST_SPI_FLASH_BUF_R3_N
   U44    4      Y SN74LVC1G07DCKR-SN74LVC1G07DCKA    I61 @SCM_LIB.SCM(SCH_1):PAGE25
  R827    1      A Q_RES_0402LF-33.2,1%,1/16W,CHIA    I73 @SCM_LIB.SCM(SCH_1):PAGE25

RST_SPI_FLASH_N @SCM_LIB.SCM(SCH_1):RST_SPI_FLASH_N
    U5   B7 RSTIND# AST2600A3GP-AST2600A3-GP,SMLF,A   I350 @SCM_LIB.SCM(SCH_1):PAGE15
  R752    1      A Q_RES_0402LF-33.2,1%,1/16W,CHIA    I67 @SCM_LIB.SCM(SCH_1):PAGE25
  R585    2      B Q_RES_0402LF-33.2,1%,1/16W,CHIA   I404 @SCM_LIB.SCM(SCH_1):PAGE15

RST_SPI_FLASH_R_N @SCM_LIB.SCM(SCH_1):RST_SPI_FLASH_R_N
   U44    2      A SN74LVC1G07DCKR-SN74LVC1G07DCKA    I61 @SCM_LIB.SCM(SCH_1):PAGE25
  R752    2      B Q_RES_0402LF-33.2,1%,1/16W,CHIA    I67 @SCM_LIB.SCM(SCH_1):PAGE25

RST_SPI_PCH_FLASH_R1_N @SCM_LIB.SCM(SCH_1):RST_SPI_PCH_FLASH_R1_N
  R496    2      B Q_RES_0402LF-4.7K,1%,1/16W,EMPA    I48 @SCM_LIB.SCM(SCH_1):PAGE45
   J40    3    NC0 SCONN16_ACASPI006P06-SCONN16_AA    I53 @SCM_LIB.SCM(SCH_1):PAGE45
   U17    3 RESET# MX25L51245GMI10G-MX25L51245GMIA    I54 @SCM_LIB.SCM(SCH_1):PAGE45

RST_SRST_PLD_BMC_BUF_N @SCM_LIB.SCM(SCH_1):RST_SRST_PLD_BMC_BUF_N
  R108    1      A Q_RES_0402LF-49.9,1%,1/16W,CHIA    I65 @SCM_LIB.SCM(SCH_1):PAGE22
    U6    4     2Y 74LVC2G07DW7-74LVC2G07DW-7,SMLA    I87 @SCM_LIB.SCM(SCH_1):PAGE22

RST_SRST_PLD_BMC_R1_N @SCM_LIB.SCM(SCH_1):RST_SRST_PLD_BMC_R1_N
  R614    1      A Q_RES_0402LF-100K,1%,1/16W,CHIA    I35 @SCM_LIB.SCM(SCH_1):PAGE22
    U6    3     2A 74LVC2G07DW7-74LVC2G07DW-7,SMLA    I87 @SCM_LIB.SCM(SCH_1):PAGE22
  R388    2      B Q_RES_0402LF-33.2,1%,1/16W,CHIA    I92 @SCM_LIB.SCM(SCH_1):PAGE22

RST_SRST_PLD_BMC_R2_N @SCM_LIB.SCM(SCH_1):RST_SRST_PLD_BMC_R2_N
   U25   F8  PT18A LCMXO3LF2100C5BG256C-LCMXO3LF-A     I1 @SCM_LIB.SCM(SCH_1):PAGE34
   R10    1      A Q_RES_0402LF-0,5%,1/16W,CHIP,CA   I155 @SCM_LIB.SCM(SCH_1):PAGE34

RST_SRST_PLD_BMC_R_N @SCM_LIB.SCM(SCH_1):RST_SRST_PLD_BMC_R_N
   GF1 OB11 SPI0_CLK FCONN168_ME1016810202011_SCM-FA   I553 @SCM_LIB.SCM(SCH_1):PAGE10
   R10    2      B Q_RES_0402LF-0,5%,1/16W,CHIP,CA   I155 @SCM_LIB.SCM(SCH_1):PAGE34
  R388    1      A Q_RES_0402LF-33.2,1%,1/16W,CHIA    I92 @SCM_LIB.SCM(SCH_1):PAGE22

RST_WDTRST_PLD_N @SCM_LIB.SCM(SCH_1):RST_WDTRST_PLD_N
  R637    2      B Q_RES_0402LF-0,5%,1/16W,CHIP,CA   I337 @SCM_LIB.SCM(SCH_1):PAGE13
  R452    2      B Q_RES_0402LF-4.7K,1%,1/16W,CHIA   I339 @SCM_LIB.SCM(SCH_1):PAGE13
  R635    1      A Q_RES_0402LF-33.2,1%,1/16W,CHIA    I80 @SCM_LIB.SCM(SCH_1):PAGE36

RST_WDTRST_PLD_R1_N @SCM_LIB.SCM(SCH_1):RST_WDTRST_PLD_R1_N
  R637    1      A Q_RES_0402LF-0,5%,1/16W,CHIP,CA   I337 @SCM_LIB.SCM(SCH_1):PAGE13
    U5 AD12 GPIOY1||SALT6||WDTRST2# AST2600A3GP-AST2600A3-GP,SMLF,A   I363 @SCM_LIB.SCM(SCH_1):PAGE13

RST_WDTRST_PLD_R2_N @SCM_LIB.SCM(SCH_1):RST_WDTRST_PLD_R2_N
   U25   T3   PB6C LCMXO3LF2100C5BG256C-LCMXO3LF-A     I1 @SCM_LIB.SCM(SCH_1):PAGE36
  R635    2      B Q_RES_0402LF-33.2,1%,1/16W,CHIA    I80 @SCM_LIB.SCM(SCH_1):PAGE36

SGPIO_BMC_M1_CLK @SCM_LIB.SCM(SCH_1):SGPIO_BMC_M1_CLK
  R148    2      B Q_RES_0402LF-33.2,1%,1/16W,CHIA   I379 @SCM_LIB.SCM(SCH_1):PAGE12
    U5  A18 GPIOH0||SGPM1CK AST2600A3GP-AST2600A3-GP,SMLF,A   I436 @SCM_LIB.SCM(SCH_1):PAGE12

SGPIO_BMC_M1_DI @SCM_LIB.SCM(SCH_1):SGPIO_BMC_M1_DI
  R433    2      B Q_RES_0402LF-33.2,1%,1/16W,CHIA   I382 @SCM_LIB.SCM(SCH_1):PAGE12
    U5  A17 GPIOH3||SGPM1I AST2600A3GP-AST2600A3-GP,SMLF,A   I436 @SCM_LIB.SCM(SCH_1):PAGE12

SGPIO_BMC_M1_DO @SCM_LIB.SCM(SCH_1):SGPIO_BMC_M1_DO
  R151    2      B Q_RES_0402LF-33.2,1%,1/16W,CHIA   I381 @SCM_LIB.SCM(SCH_1):PAGE12
    U5  C18 GPIOH2||SGPM1O AST2600A3GP-AST2600A3-GP,SMLF,A   I436 @SCM_LIB.SCM(SCH_1):PAGE12

SGPIO_BMC_M1_LD @SCM_LIB.SCM(SCH_1):SGPIO_BMC_M1_LD
  R150    2      B Q_RES_0402LF-33.2,1%,1/16W,CHIA   I380 @SCM_LIB.SCM(SCH_1):PAGE12
    U5  B18 GPIOH1||SGPM1LD AST2600A3GP-AST2600A3-GP,SMLF,A   I436 @SCM_LIB.SCM(SCH_1):PAGE12

SGPIO_CLK_0 @SCM_LIB.SCM(SCH_1):SGPIO_CLK_0
   GF1  B30 SGPIO_CLK FCONN168_ME1016810202011_SCM-FA   I553 @SCM_LIB.SCM(SCH_1):PAGE10
   R82    2      B Q_RES_0402LF-2K,1%,1/16W,CHIP,A   I232 @SCM_LIB.SCM(SCH_1):PAGE11
   R64    1      A Q_RES_0402LF-0,5%,1/16W,EMPTY,A   I233 @SCM_LIB.SCM(SCH_1):PAGE11
  R434    2      B Q_RES_0402LF-33.2,1%,1/16W,CHIA   I160 @SCM_LIB.SCM(SCH_1):PAGE34

SGPIO_CLK_1 @SCM_LIB.SCM(SCH_1):SGPIO_CLK_1
   GF1  B35  RSVD2 FCONN168_ME1016810202011_SCM-FA   I553 @SCM_LIB.SCM(SCH_1):PAGE10
   R76    2      B Q_RES_0402LF-2K,1%,1/16W,CHIP,A   I230 @SCM_LIB.SCM(SCH_1):PAGE11
   R63    1      A Q_RES_0402LF-0,5%,1/16W,EMPTY,A   I231 @SCM_LIB.SCM(SCH_1):PAGE11
  R148    1      A Q_RES_0402LF-33.2,1%,1/16W,CHIA   I379 @SCM_LIB.SCM(SCH_1):PAGE12

SGPIO_CLK_PLD_0 @SCM_LIB.SCM(SCH_1):SGPIO_CLK_PLD_0
   U25  A14  PT22D LCMXO3LF2100C5BG256C-LCMXO3LF-A     I1 @SCM_LIB.SCM(SCH_1):PAGE34
  R434    1      A Q_RES_0402LF-33.2,1%,1/16W,CHIA   I160 @SCM_LIB.SCM(SCH_1):PAGE34

SGPIO_DI_0 @SCM_LIB.SCM(SCH_1):SGPIO_DI_0
   GF1  B31 SGPIO0_DI FCONN168_ME1016810202011_SCM-FA   I553 @SCM_LIB.SCM(SCH_1):PAGE10
   R78    2      B Q_RES_0402LF-2K,1%,1/16W,CHIP,A   I129 @SCM_LIB.SCM(SCH_1):PAGE11
  R437    2      B Q_RES_0402LF-33.2,1%,1/16W,CHIA   I163 @SCM_LIB.SCM(SCH_1):PAGE34

SGPIO_DI_1 @SCM_LIB.SCM(SCH_1):SGPIO_DI_1
   GF1  B36 SGPIO1_DI FCONN168_ME1016810202011_SCM-FA   I553 @SCM_LIB.SCM(SCH_1):PAGE10
   R74    2      B Q_RES_0402LF-2K,1%,1/16W,CHIP,A   I117 @SCM_LIB.SCM(SCH_1):PAGE11
  R433    1      A Q_RES_0402LF-33.2,1%,1/16W,CHIA   I382 @SCM_LIB.SCM(SCH_1):PAGE12

SGPIO_DO_0 @SCM_LIB.SCM(SCH_1):SGPIO_DO_0
   GF1  B29 SGPIO0_DO FCONN168_ME1016810202011_SCM-FA   I553 @SCM_LIB.SCM(SCH_1):PAGE10
   R79    2      B Q_RES_0402LF-2K,1%,1/16W,CHIP,A   I130 @SCM_LIB.SCM(SCH_1):PAGE11
  R435    2      B Q_RES_0402LF-33.2,1%,1/16W,CHIA   I161 @SCM_LIB.SCM(SCH_1):PAGE34

SGPIO_DO_1 @SCM_LIB.SCM(SCH_1):SGPIO_DO_1
   GF1  B34 SGPIO1_DO FCONN168_ME1016810202011_SCM-FA   I553 @SCM_LIB.SCM(SCH_1):PAGE10
   R75    2      B Q_RES_0402LF-2K,1%,1/16W,CHIP,A   I110 @SCM_LIB.SCM(SCH_1):PAGE11
  R151    1      A Q_RES_0402LF-33.2,1%,1/16W,CHIA   I381 @SCM_LIB.SCM(SCH_1):PAGE12

SGPIO_LD_0 @SCM_LIB.SCM(SCH_1):SGPIO_LD_0
   GF1  B32 SGPIO0_LD FCONN168_ME1016810202011_SCM-FA   I553 @SCM_LIB.SCM(SCH_1):PAGE10
   R77    2      B Q_RES_0402LF-1K,1%,1/16W,EMPTYA   I128 @SCM_LIB.SCM(SCH_1):PAGE11
  R436    2      B Q_RES_0402LF-33.2,1%,1/16W,CHIA   I162 @SCM_LIB.SCM(SCH_1):PAGE34

SGPIO_LD_1 @SCM_LIB.SCM(SCH_1):SGPIO_LD_1
   GF1  B37 SGPIO1_LD FCONN168_ME1016810202011_SCM-FA   I553 @SCM_LIB.SCM(SCH_1):PAGE10
   R73    2      B Q_RES_0402LF-1K,1%,1/16W,EMPTYA   I118 @SCM_LIB.SCM(SCH_1):PAGE11
  R150    1      A Q_RES_0402LF-33.2,1%,1/16W,CHIA   I380 @SCM_LIB.SCM(SCH_1):PAGE12

SGPIO_PLD_DI_0 @SCM_LIB.SCM(SCH_1):SGPIO_PLD_DI_0
   U25  B14  PT24A LCMXO3LF2100C5BG256C-LCMXO3LF-A     I1 @SCM_LIB.SCM(SCH_1):PAGE34
  R437    1      A Q_RES_0402LF-33.2,1%,1/16W,CHIA   I163 @SCM_LIB.SCM(SCH_1):PAGE34

SGPIO_PLD_DO_0 @SCM_LIB.SCM(SCH_1):SGPIO_PLD_DO_0
   U25  C12  PT23A LCMXO3LF2100C5BG256C-LCMXO3LF-A     I1 @SCM_LIB.SCM(SCH_1):PAGE34
  R435    1      A Q_RES_0402LF-33.2,1%,1/16W,CHIA   I161 @SCM_LIB.SCM(SCH_1):PAGE34

SGPIO_PLD_LD_0 @SCM_LIB.SCM(SCH_1):SGPIO_PLD_LD_0
   U25  B12  PT23B LCMXO3LF2100C5BG256C-LCMXO3LF-A     I1 @SCM_LIB.SCM(SCH_1):PAGE34
  R436    1      A Q_RES_0402LF-33.2,1%,1/16W,CHIA   I162 @SCM_LIB.SCM(SCH_1):PAGE34

SMB_BMC_ALERT10_N @SCM_LIB.SCM(SCH_1):SMB_BMC_ALERT10_N
  R449    1      A Q_RES_0402LF-33.2,1%,1/16W,CHIA   I321 @SCM_LIB.SCM(SCH_1):PAGE15
  R843    2      B Q_RES_0402LF-4.7K,1%,1/16W,CHIA   I177 @SCM_LIB.SCM(SCH_1):PAGE27
  R457    1      A Q_RES_0402LF-0,5%,1/16W,CHIP,CA     I5 @SCM_LIB.SCM(SCH_1):PAGE35

SMB_BMC_ALERT10_R1_N @SCM_LIB.SCM(SCH_1):SMB_BMC_ALERT10_R1_N
   U25  G12   PR3D LCMXO3LF2100C5BG256C-LCMXO3LF-A     I1 @SCM_LIB.SCM(SCH_1):PAGE35
  R457    2      B Q_RES_0402LF-0,5%,1/16W,CHIP,CA     I5 @SCM_LIB.SCM(SCH_1):PAGE35

SMB_BMC_ALERT10_R_N @SCM_LIB.SCM(SCH_1):SMB_BMC_ALERT10_R_N
  R449    2      B Q_RES_0402LF-33.2,1%,1/16W,CHIA   I321 @SCM_LIB.SCM(SCH_1):PAGE15
    U5 AA17 ADC9||GPIU1||SALT10 AST2600A3GP-AST2600A3-GP,SMLF,A   I350 @SCM_LIB.SCM(SCH_1):PAGE15

SMB_BMC_ALERT12_N @SCM_LIB.SCM(SCH_1):SMB_BMC_ALERT12_N
    U5 AE16 ADC11||GPIU3||SALT12 AST2600A3GP-AST2600A3-GP,SMLF,A   I350 @SCM_LIB.SCM(SCH_1):PAGE15
  R844    2      B Q_RES_0402LF-4.7K,1%,1/16W,CHIA   I179 @SCM_LIB.SCM(SCH_1):PAGE27
   U25  L14  PR11B LCMXO3LF2100C5BG256C-LCMXO3LF-A     I1 @SCM_LIB.SCM(SCH_1):PAGE35

SMB_BMC_ALERT15_N @SCM_LIB.SCM(SCH_1):SMB_BMC_ALERT15_N
    U5  D21 GPIOG6||TXD9||SD2CD#||SALT15 AST2600A3GP-AST2600A3-GP,SMLF,A   I436 @SCM_LIB.SCM(SCH_1):PAGE12
  R851    2      B Q_RES_0402LF-4.7K,1%,1/16W,CHIA   I184 @SCM_LIB.SCM(SCH_1):PAGE27

SMB_BMC_ALERT16_N @SCM_LIB.SCM(SCH_1):SMB_BMC_ALERT16_N
    U5 AC17 ADC15||GPIU7||SALT16 AST2600A3GP-AST2600A3-GP,SMLF,A   I350 @SCM_LIB.SCM(SCH_1):PAGE15
  R848    2      B Q_RES_0402LF-4.7K,1%,1/16W,CHIA   I182 @SCM_LIB.SCM(SCH_1):PAGE27
  R574    1      A Q_RES_0402LF-0,5%,1/16W,CHIP,CA    I76 @SCM_LIB.SCM(SCH_1):PAGE35
   R54    2      B Q_RES_0402LF-10K,1%,1/16W,CHIPA    I65 @SCM_LIB.SCM(SCH_1):PAGE26

SMB_BMC_ALERT16_R2_N @SCM_LIB.SCM(SCH_1):SMB_BMC_ALERT16_R2_N
   U25  R16  PR14D LCMXO3LF2100C5BG256C-LCMXO3LF-A     I1 @SCM_LIB.SCM(SCH_1):PAGE35
  R574    2      B Q_RES_0402LF-0,5%,1/16W,CHIP,CA    I76 @SCM_LIB.SCM(SCH_1):PAGE35

SMB_BMC_ALERT16_R_N @SCM_LIB.SCM(SCH_1):SMB_BMC_ALERT16_R_N
   R54    1      A Q_RES_0402LF-10K,1%,1/16W,CHIPA    I65 @SCM_LIB.SCM(SCH_1):PAGE26
   J14    6      6 CONN8_TSW10407FD-CONN8_TSW-104A    I71 @SCM_LIB.SCM(SCH_1):PAGE26

SMB_BMC_ALERT3_N @SCM_LIB.SCM(SCH_1):SMB_BMC_ALERT3_N
  R442    1      A Q_RES_0402LF-33.2,1%,1/16W,CHIA   I301 @SCM_LIB.SCM(SCH_1):PAGE13
  R268    2      B Q_RES_0402LF-4.7K,1%,1/16W,CHIA    I86 @SCM_LIB.SCM(SCH_1):PAGE27
  R453    1      A Q_RES_0402LF-0,5%,1/16W,CHIP,CA     I2 @SCM_LIB.SCM(SCH_1):PAGE35

SMB_BMC_ALERT3_R1_N @SCM_LIB.SCM(SCH_1):SMB_BMC_ALERT3_R1_N
   U25  C16   PR2C LCMXO3LF2100C5BG256C-LCMXO3LF-A     I1 @SCM_LIB.SCM(SCH_1):PAGE35
  R453    2      B Q_RES_0402LF-0,5%,1/16W,CHIP,CA     I2 @SCM_LIB.SCM(SCH_1):PAGE35

SMB_BMC_ALERT3_R_N @SCM_LIB.SCM(SCH_1):SMB_BMC_ALERT3_R_N
  R442    2      B Q_RES_0402LF-33.2,1%,1/16W,CHIA   I301 @SCM_LIB.SCM(SCH_1):PAGE13
    U5  H26 GPIOB2||SALT3 AST2600A3GP-AST2600A3-GP,SMLF,A   I363 @SCM_LIB.SCM(SCH_1):PAGE13

SMB_BMC_ALERT4_N @SCM_LIB.SCM(SCH_1):SMB_BMC_ALERT4_N
  R443    1      A Q_RES_0402LF-33.2,1%,1/16W,CHIA   I300 @SCM_LIB.SCM(SCH_1):PAGE13
  R269    2      B Q_RES_0402LF-4.7K,1%,1/16W,CHIA    I84 @SCM_LIB.SCM(SCH_1):PAGE27
  R454    1      A Q_RES_0402LF-0,5%,1/16W,CHIP,CA     I3 @SCM_LIB.SCM(SCH_1):PAGE35

SMB_BMC_ALERT4_R1_N @SCM_LIB.SCM(SCH_1):SMB_BMC_ALERT4_R1_N
   U25  D15   PR2D LCMXO3LF2100C5BG256C-LCMXO3LF-A     I1 @SCM_LIB.SCM(SCH_1):PAGE35
  R454    2      B Q_RES_0402LF-0,5%,1/16W,CHIP,CA     I3 @SCM_LIB.SCM(SCH_1):PAGE35

SMB_BMC_ALERT4_R_N @SCM_LIB.SCM(SCH_1):SMB_BMC_ALERT4_R_N
  R443    2      B Q_RES_0402LF-33.2,1%,1/16W,CHIA   I300 @SCM_LIB.SCM(SCH_1):PAGE13
    U5  J25 GPIOB3||SALT4 AST2600A3GP-AST2600A3-GP,SMLF,A   I363 @SCM_LIB.SCM(SCH_1):PAGE13

SMB_BMC_ALERT9_N @SCM_LIB.SCM(SCH_1):SMB_BMC_ALERT9_N
  R448    1      A Q_RES_0402LF-33.2,1%,1/16W,CHIA   I320 @SCM_LIB.SCM(SCH_1):PAGE15
  R842    2      B Q_RES_0402LF-4.7K,1%,1/16W,CHIA   I168 @SCM_LIB.SCM(SCH_1):PAGE27
  R456    1      A Q_RES_0402LF-0,5%,1/16W,CHIP,CA     I4 @SCM_LIB.SCM(SCH_1):PAGE35

SMB_BMC_ALERT9_R1_N @SCM_LIB.SCM(SCH_1):SMB_BMC_ALERT9_R1_N
   U25  F13   PR3C LCMXO3LF2100C5BG256C-LCMXO3LF-A     I1 @SCM_LIB.SCM(SCH_1):PAGE35
  R456    2      B Q_RES_0402LF-0,5%,1/16W,CHIP,CA     I4 @SCM_LIB.SCM(SCH_1):PAGE35

SMB_BMC_ALERT9_R_N @SCM_LIB.SCM(SCH_1):SMB_BMC_ALERT9_R_N
  R448    2      B Q_RES_0402LF-33.2,1%,1/16W,CHIA   I320 @SCM_LIB.SCM(SCH_1):PAGE15
    U5 AB16 ADC8||GPIU0||SALT9 AST2600A3GP-AST2600A3-GP,SMLF,A   I350 @SCM_LIB.SCM(SCH_1):PAGE15

SMB_BMC_MM10_R_SCL @SCM_LIB.SCM(SCH_1):SMB_BMC_MM10_R_SCL
  R583    1      A Q_RES_0402LF-33.2,1%,1/16W,CHIA   I319 @SCM_LIB.SCM(SCH_1):PAGE12
    U5  E15 GPIOL2||SCL10 AST2600A3GP-AST2600A3-GP,SMLF,A   I436 @SCM_LIB.SCM(SCH_1):PAGE12

SMB_BMC_MM10_R_SDA @SCM_LIB.SCM(SCH_1):SMB_BMC_MM10_R_SDA
  R584    1      A Q_RES_0402LF-33.2,1%,1/16W,CHIA   I320 @SCM_LIB.SCM(SCH_1):PAGE12
    U5  A13 GPIOL3||SDA10 AST2600A3GP-AST2600A3-GP,SMLF,A   I436 @SCM_LIB.SCM(SCH_1):PAGE12

SMB_BMC_MM10_SCL @SCM_LIB.SCM(SCH_1):SMB_BMC_MM10_SCL
   GF1  A31 I2C_10_SCL FCONN168_ME1016810202011_SCM-FA   I553 @SCM_LIB.SCM(SCH_1):PAGE10
  R583    2      B Q_RES_0402LF-33.2,1%,1/16W,CHIA   I319 @SCM_LIB.SCM(SCH_1):PAGE12
  R262    2      B Q_RES_0402LF-10K,1%,1/16W,CHIPA    I93 @SCM_LIB.SCM(SCH_1):PAGE27

SMB_BMC_MM10_SDA @SCM_LIB.SCM(SCH_1):SMB_BMC_MM10_SDA
   GF1  A32 I2C_10_SDA FCONN168_ME1016810202011_SCM-FA   I553 @SCM_LIB.SCM(SCH_1):PAGE10
  R584    2      B Q_RES_0402LF-33.2,1%,1/16W,CHIA   I320 @SCM_LIB.SCM(SCH_1):PAGE12
  R521    2      B Q_RES_0402LF-10K,1%,1/16W,CHIPA   I234 @SCM_LIB.SCM(SCH_1):PAGE27

SMB_BMC_MM12_R_SCL @SCM_LIB.SCM(SCH_1):SMB_BMC_MM12_R_SCL
  R137    1      A Q_RES_0402LF-33.2,1%,1/16W,CHIA   I385 @SCM_LIB.SCM(SCH_1):PAGE12
    U5  L26 GPIOA2||SCL12||MDC4 AST2600A3GP-AST2600A3-GP,SMLF,A   I436 @SCM_LIB.SCM(SCH_1):PAGE12

SMB_BMC_MM12_R_SDA @SCM_LIB.SCM(SCH_1):SMB_BMC_MM12_R_SDA
  R144    1      A Q_RES_0402LF-33.2,1%,1/16W,CHIA   I386 @SCM_LIB.SCM(SCH_1):PAGE12
    U5  K24 GPIOA3||SDA12||MDIO4 AST2600A3GP-AST2600A3-GP,SMLF,A   I436 @SCM_LIB.SCM(SCH_1):PAGE12

SMB_BMC_MM12_SCL @SCM_LIB.SCM(SCH_1):SMB_BMC_MM12_SCL
   GF1  A38 I2C_11_SCL FCONN168_ME1016810202011_SCM-FA   I553 @SCM_LIB.SCM(SCH_1):PAGE10
  R137    2      B Q_RES_0402LF-33.2,1%,1/16W,CHIA   I385 @SCM_LIB.SCM(SCH_1):PAGE12
  R145    2      B Q_RES_0402LF-10K,1%,1/16W,CHIPA   I235 @SCM_LIB.SCM(SCH_1):PAGE27

SMB_BMC_MM12_SDA @SCM_LIB.SCM(SCH_1):SMB_BMC_MM12_SDA
   GF1  A39 I2C_11_SDA FCONN168_ME1016810202011_SCM-FA   I553 @SCM_LIB.SCM(SCH_1):PAGE10
  R144    2      B Q_RES_0402LF-33.2,1%,1/16W,CHIA   I386 @SCM_LIB.SCM(SCH_1):PAGE12
  R149    2      B Q_RES_0402LF-10K,1%,1/16W,CHIPA   I236 @SCM_LIB.SCM(SCH_1):PAGE27

SMB_BMC_MM13_R_SCL @SCM_LIB.SCM(SCH_1):SMB_BMC_MM13_R_SCL
  R423    1      A Q_RES_0402LF-33.2,1%,1/16W,CHIA   I252 @SCM_LIB.SCM(SCH_1):PAGE12
  R817    1      A Q_RES_0402LF-100K,1%,1/16W,EMPA   I393 @SCM_LIB.SCM(SCH_1):PAGE12
    U5  K26 GPIOA4||MAC1LINK||SCL13||SGPM2CK||SGPS2CK AST2600A3GP-AST2600A3-GP,SMLF,A   I436 @SCM_LIB.SCM(SCH_1):PAGE12

SMB_BMC_MM13_R_SDA @SCM_LIB.SCM(SCH_1):SMB_BMC_MM13_R_SDA
  R424    1      A Q_RES_0402LF-33.2,1%,1/16W,CHIA   I253 @SCM_LIB.SCM(SCH_1):PAGE12
  R818    1      A Q_RES_0402LF-100K,1%,1/16W,EMPA   I392 @SCM_LIB.SCM(SCH_1):PAGE12
    U5  L24 GPIOA5||MAC2LINK||SDA13||SGPM2LD||SGPS2LD AST2600A3GP-AST2600A3-GP,SMLF,A   I436 @SCM_LIB.SCM(SCH_1):PAGE12

SMB_BMC_MM13_SCL @SCM_LIB.SCM(SCH_1):SMB_BMC_MM13_SCL
   GF1  A40 I2C_12_SCL FCONN168_ME1016810202011_SCM-FA   I553 @SCM_LIB.SCM(SCH_1):PAGE10
  R423    2      B Q_RES_0402LF-33.2,1%,1/16W,CHIA   I252 @SCM_LIB.SCM(SCH_1):PAGE12
  R422    2      B Q_RES_0402LF-2.2K,5%,1/16W,CHIA   I239 @SCM_LIB.SCM(SCH_1):PAGE27

SMB_BMC_MM13_SDA @SCM_LIB.SCM(SCH_1):SMB_BMC_MM13_SDA
   GF1  A41 I2C_12_SDA FCONN168_ME1016810202011_SCM-FA   I553 @SCM_LIB.SCM(SCH_1):PAGE10
  R424    2      B Q_RES_0402LF-33.2,1%,1/16W,CHIA   I253 @SCM_LIB.SCM(SCH_1):PAGE12
  R428    2      B Q_RES_0402LF-2.2K,5%,1/16W,CHIA   I240 @SCM_LIB.SCM(SCH_1):PAGE27

SMB_BMC_MM14_R1_SCL @SCM_LIB.SCM(SCH_1):SMB_BMC_MM14_R1_SCL
   R36    2      B Q_RES_0402LF-33.2,1%,1/16W,CHIA   I458 @SCM_LIB.SCM(SCH_1):PAGE10
   GF1   A1 I2C_0_SCL FCONN168_ME1016810202011_SCM-FA   I553 @SCM_LIB.SCM(SCH_1):PAGE10

SMB_BMC_MM14_R1_SDA @SCM_LIB.SCM(SCH_1):SMB_BMC_MM14_R1_SDA
   R46    2      B Q_RES_0402LF-33.2,1%,1/16W,CHIA   I459 @SCM_LIB.SCM(SCH_1):PAGE10
   GF1   A2 I2C_0_SDA FCONN168_ME1016810202011_SCM-FA   I553 @SCM_LIB.SCM(SCH_1):PAGE10

SMB_BMC_MM14_R_SCL @SCM_LIB.SCM(SCH_1):SMB_BMC_MM14_R_SCL
  R425    1      A Q_RES_0402LF-33.2,1%,1/16W,CHIA   I254 @SCM_LIB.SCM(SCH_1):PAGE12
  R819    1      A Q_RES_0402LF-100K,1%,1/16W,EMPA   I391 @SCM_LIB.SCM(SCH_1):PAGE12
    U5  L23 GPIOA6||MAC3LINK||SCL14||SGPM2O||SGPS2I0 AST2600A3GP-AST2600A3-GP,SMLF,A   I436 @SCM_LIB.SCM(SCH_1):PAGE12

SMB_BMC_MM14_R_SDA @SCM_LIB.SCM(SCH_1):SMB_BMC_MM14_R_SDA
  R426    1      A Q_RES_0402LF-33.2,1%,1/16W,CHIA   I255 @SCM_LIB.SCM(SCH_1):PAGE12
  R820    1      A Q_RES_0402LF-100K,1%,1/16W,EMPA   I390 @SCM_LIB.SCM(SCH_1):PAGE12
    U5  K25 GPIOA7||MAC4LINK||SDA14||SGPM2I||SGPS2I1 AST2600A3GP-AST2600A3-GP,SMLF,A   I436 @SCM_LIB.SCM(SCH_1):PAGE12

SMB_BMC_MM14_SCL @SCM_LIB.SCM(SCH_1):SMB_BMC_MM14_SCL
   R36    1      A Q_RES_0402LF-33.2,1%,1/16W,CHIA   I458 @SCM_LIB.SCM(SCH_1):PAGE10
  R425    2      B Q_RES_0402LF-33.2,1%,1/16W,CHIA   I254 @SCM_LIB.SCM(SCH_1):PAGE12
  R429    2      B Q_RES_0402LF-2.2K,5%,1/16W,CHIA   I241 @SCM_LIB.SCM(SCH_1):PAGE27

SMB_BMC_MM14_SDA @SCM_LIB.SCM(SCH_1):SMB_BMC_MM14_SDA
   R46    1      A Q_RES_0402LF-33.2,1%,1/16W,CHIA   I459 @SCM_LIB.SCM(SCH_1):PAGE10
  R426    2      B Q_RES_0402LF-33.2,1%,1/16W,CHIA   I255 @SCM_LIB.SCM(SCH_1):PAGE12
  R438    2      B Q_RES_0402LF-2.2K,5%,1/16W,CHIA   I242 @SCM_LIB.SCM(SCH_1):PAGE27

SMB_BMC_MM15_R1_SCL @SCM_LIB.SCM(SCH_1):SMB_BMC_MM15_R1_SCL
   U37    2   SCLA PCA9517ADP_SMLF-PCA9517ADP,IC,A    I99 @SCM_LIB.SCM(SCH_1):PAGE28
  R135    2      B Q_RES_0402LF-0,5%,1/16W,CHIP,CA   I109 @SCM_LIB.SCM(SCH_1):PAGE28

SMB_BMC_MM15_R1_SDA @SCM_LIB.SCM(SCH_1):SMB_BMC_MM15_R1_SDA
   U37    3   SDAA PCA9517ADP_SMLF-PCA9517ADP,IC,A    I99 @SCM_LIB.SCM(SCH_1):PAGE28
  R294    2      B Q_RES_0402LF-0,5%,1/16W,CHIP,CA   I108 @SCM_LIB.SCM(SCH_1):PAGE28

SMB_BMC_MM15_R_SCL @SCM_LIB.SCM(SCH_1):SMB_BMC_MM15_R_SCL
  R162    2      B Q_RES_0402LF-33.2,1%,1/16W,CHIA   I245 @SCM_LIB.SCM(SCH_1):PAGE12
    U5  D18 GPIOH4||SGPS1CK||SCL15 AST2600A3GP-AST2600A3-GP,SMLF,A   I436 @SCM_LIB.SCM(SCH_1):PAGE12

SMB_BMC_MM15_R_SDA @SCM_LIB.SCM(SCH_1):SMB_BMC_MM15_R_SDA
  R236    2      B Q_RES_0402LF-33.2,1%,1/16W,CHIA   I244 @SCM_LIB.SCM(SCH_1):PAGE12
    U5  B17 GPIOH5||SGPS1LD||SDA15 AST2600A3GP-AST2600A3-GP,SMLF,A   I436 @SCM_LIB.SCM(SCH_1):PAGE12

SMB_BMC_MM15_SCL @SCM_LIB.SCM(SCH_1):SMB_BMC_MM15_SCL
  R162    1      A Q_RES_0402LF-33.2,1%,1/16W,CHIA   I245 @SCM_LIB.SCM(SCH_1):PAGE12
  R135    1      A Q_RES_0402LF-0,5%,1/16W,CHIP,CA   I109 @SCM_LIB.SCM(SCH_1):PAGE28
  R610    2      B Q_RES_0402LF-2.2K,5%,1/16W,CHIA   I237 @SCM_LIB.SCM(SCH_1):PAGE27

SMB_BMC_MM15_SDA @SCM_LIB.SCM(SCH_1):SMB_BMC_MM15_SDA
  R236    1      A Q_RES_0402LF-33.2,1%,1/16W,CHIA   I244 @SCM_LIB.SCM(SCH_1):PAGE12
  R294    1      A Q_RES_0402LF-0,5%,1/16W,CHIP,CA   I108 @SCM_LIB.SCM(SCH_1):PAGE28
  R692    2      B Q_RES_0402LF-2.2K,5%,1/16W,CHIA   I238 @SCM_LIB.SCM(SCH_1):PAGE27

SMB_BMC_MM16_R1_SCL @SCM_LIB.SCM(SCH_1):SMB_BMC_MM16_R1_SCL
    J4   40     40 SCONN67_NASA0S6730TS67-SCONN67A    I84 @SCM_LIB.SCM(SCH_1):PAGE21
  R849    2      B Q_RES_0402LF-33.2,1%,1/16W,CHIA   I157 @SCM_LIB.SCM(SCH_1):PAGE21

SMB_BMC_MM16_R1_SDA @SCM_LIB.SCM(SCH_1):SMB_BMC_MM16_R1_SDA
    J4   42     42 SCONN67_NASA0S6730TS67-SCONN67A    I84 @SCM_LIB.SCM(SCH_1):PAGE21
  R850    2      B Q_RES_0402LF-33.2,1%,1/16W,CHIA   I156 @SCM_LIB.SCM(SCH_1):PAGE21

SMB_BMC_MM16_R2_SCL @SCM_LIB.SCM(SCH_1):SMB_BMC_MM16_R2_SCL
   U19    6    SCL M24128BWDW6TP-M24128-BWDW6TP,SA    I15 @SCM_LIB.SCM(SCH_1):PAGE26
  R420    1      A Q_RES_0402LF-150,1%,1/16W,CHIPA    I69 @SCM_LIB.SCM(SCH_1):PAGE26

SMB_BMC_MM16_R2_SDA @SCM_LIB.SCM(SCH_1):SMB_BMC_MM16_R2_SDA
   U19    5    SDA M24128BWDW6TP-M24128-BWDW6TP,SA    I15 @SCM_LIB.SCM(SCH_1):PAGE26
  R421    1      A Q_RES_0402LF-33.2,1%,1/16W,CHIA    I33 @SCM_LIB.SCM(SCH_1):PAGE26

SMB_BMC_MM16_R3_SCL @SCM_LIB.SCM(SCH_1):SMB_BMC_MM16_R3_SCL
   U25   A9 PT18C||SCL||PCLKT0_0 LCMXO3LF2100C5BG256C-LCMXO3LF-A     I1 @SCM_LIB.SCM(SCH_1):PAGE34
  R272    1      A Q_RES_0402LF-0,5%,1/16W,CHIP,CA   I165 @SCM_LIB.SCM(SCH_1):PAGE34

SMB_BMC_MM16_R3_SDA @SCM_LIB.SCM(SCH_1):SMB_BMC_MM16_R3_SDA
   U25   C9 PT18D||SDA||PCLKC0_0 LCMXO3LF2100C5BG256C-LCMXO3LF-A     I1 @SCM_LIB.SCM(SCH_1):PAGE34
  R303    1      A Q_RES_0402LF-0,5%,1/16W,CHIP,CA   I166 @SCM_LIB.SCM(SCH_1):PAGE34

SMB_BMC_MM16_R4_SCL @SCM_LIB.SCM(SCH_1):SMB_BMC_MM16_R4_SCL
   U25  T15  PB25C LCMXO3LF2100C5BG256C-LCMXO3LF-A     I1 @SCM_LIB.SCM(SCH_1):PAGE36
  R105    1      A Q_RES_0402LF-0,5%,1/16W,CHIP,CA    I58 @SCM_LIB.SCM(SCH_1):PAGE36

SMB_BMC_MM16_R4_SDA @SCM_LIB.SCM(SCH_1):SMB_BMC_MM16_R4_SDA
   U25  R14  PB25D LCMXO3LF2100C5BG256C-LCMXO3LF-A     I1 @SCM_LIB.SCM(SCH_1):PAGE36
  R114    1      A Q_RES_0402LF-0,5%,1/16W,CHIP,CA    I57 @SCM_LIB.SCM(SCH_1):PAGE36

SMB_BMC_MM16_R5_SCL @SCM_LIB.SCM(SCH_1):SMB_BMC_MM16_R5_SCL
   R47    2      B Q_RES_0402LF-33.2,1%,1/16W,CHIA   I106 @SCM_LIB.SCM(SCH_1):PAGE46
  R105    2      B Q_RES_0402LF-0,5%,1/16W,CHIP,CA    I58 @SCM_LIB.SCM(SCH_1):PAGE36
  R849    1      A Q_RES_0402LF-33.2,1%,1/16W,CHIA   I157 @SCM_LIB.SCM(SCH_1):PAGE21
  R879    1      A Q_RES_0402LF-200,1%,1/16W,CHIPA   I510 @SCM_LIB.SCM(SCH_1):PAGE12
  R272    2      B Q_RES_0402LF-0,5%,1/16W,CHIP,CA   I165 @SCM_LIB.SCM(SCH_1):PAGE34

SMB_BMC_MM16_R5_SDA @SCM_LIB.SCM(SCH_1):SMB_BMC_MM16_R5_SDA
   R33    1      A Q_RES_0402LF-33.2,1%,1/16W,CHIA   I117 @SCM_LIB.SCM(SCH_1):PAGE46
  R114    2      B Q_RES_0402LF-0,5%,1/16W,CHIP,CA    I57 @SCM_LIB.SCM(SCH_1):PAGE36
  R850    1      A Q_RES_0402LF-33.2,1%,1/16W,CHIA   I156 @SCM_LIB.SCM(SCH_1):PAGE21
  R880    1      A Q_RES_0402LF-33.2,1%,1/16W,CHIA   I458 @SCM_LIB.SCM(SCH_1):PAGE12
  R303    2      B Q_RES_0402LF-0,5%,1/16W,CHIP,CA   I166 @SCM_LIB.SCM(SCH_1):PAGE34

SMB_BMC_MM16_R_SCL @SCM_LIB.SCM(SCH_1):SMB_BMC_MM16_R_SCL
  R152    2      B Q_RES_0402LF-33.2,1%,1/16W,CHIA   I249 @SCM_LIB.SCM(SCH_1):PAGE12
    U5  C17 GPIOH6||SGPS1I0||SCL16 AST2600A3GP-AST2600A3-GP,SMLF,A   I436 @SCM_LIB.SCM(SCH_1):PAGE12

SMB_BMC_MM16_R_SDA @SCM_LIB.SCM(SCH_1):SMB_BMC_MM16_R_SDA
  R153    2      B Q_RES_0402LF-33.2,1%,1/16W,CHIA   I248 @SCM_LIB.SCM(SCH_1):PAGE12
    U5  E18 GPIOH7||SGPS1I1||SDA16 AST2600A3GP-AST2600A3-GP,SMLF,A   I436 @SCM_LIB.SCM(SCH_1):PAGE12

SMB_BMC_MM16_SCL @SCM_LIB.SCM(SCH_1):SMB_BMC_MM16_SCL
  R152    1      A Q_RES_0402LF-33.2,1%,1/16W,CHIA   I249 @SCM_LIB.SCM(SCH_1):PAGE12
  R264    2      B Q_RES_0402LF-2.2K,5%,1/16W,CHIA    I89 @SCM_LIB.SCM(SCH_1):PAGE27
  R879    2      B Q_RES_0402LF-200,1%,1/16W,CHIPA   I510 @SCM_LIB.SCM(SCH_1):PAGE12
  R420    2      B Q_RES_0402LF-150,1%,1/16W,CHIPA    I69 @SCM_LIB.SCM(SCH_1):PAGE26

SMB_BMC_MM16_SDA @SCM_LIB.SCM(SCH_1):SMB_BMC_MM16_SDA
  R153    1      A Q_RES_0402LF-33.2,1%,1/16W,CHIA   I248 @SCM_LIB.SCM(SCH_1):PAGE12
  R421    2      B Q_RES_0402LF-33.2,1%,1/16W,CHIA    I33 @SCM_LIB.SCM(SCH_1):PAGE26
  R265    2      B Q_RES_0402LF-2.2K,5%,1/16W,CHIA    I88 @SCM_LIB.SCM(SCH_1):PAGE27
  R880    2      B Q_RES_0402LF-33.2,1%,1/16W,CHIA   I458 @SCM_LIB.SCM(SCH_1):PAGE12

SMB_BMC_MM1_R_SCL @SCM_LIB.SCM(SCH_1):SMB_BMC_MM1_R_SCL
  R132    1      A Q_RES_0402LF-33.2,1%,1/16W,CHIA    I98 @SCM_LIB.SCM(SCH_1):PAGE12
    U5  B20 GPIOJ0||HVI3C3SCL||SCL1 AST2600A3GP-AST2600A3-GP,SMLF,A   I436 @SCM_LIB.SCM(SCH_1):PAGE12

SMB_BMC_MM1_R_SDA @SCM_LIB.SCM(SCH_1):SMB_BMC_MM1_R_SDA
  R133    1      A Q_RES_0402LF-33.2,1%,1/16W,CHIA    I97 @SCM_LIB.SCM(SCH_1):PAGE12
    U5  A20 GPIOJ1||HVI3C3SDA||SDA1 AST2600A3GP-AST2600A3-GP,SMLF,A   I436 @SCM_LIB.SCM(SCH_1):PAGE12

SMB_BMC_MM1_SCL @SCM_LIB.SCM(SCH_1):SMB_BMC_MM1_SCL
   GF1   A3 I2C_1_SCL FCONN168_ME1016810202011_SCM-FA   I553 @SCM_LIB.SCM(SCH_1):PAGE10
  R132    2      B Q_RES_0402LF-33.2,1%,1/16W,CHIA    I98 @SCM_LIB.SCM(SCH_1):PAGE12
  R244    2      B Q_RES_0402LF-1.8K,1%,1/16W,CHIA   I147 @SCM_LIB.SCM(SCH_1):PAGE27

SMB_BMC_MM1_SDA @SCM_LIB.SCM(SCH_1):SMB_BMC_MM1_SDA
   GF1   A4 I2C_1_SDA FCONN168_ME1016810202011_SCM-FA   I553 @SCM_LIB.SCM(SCH_1):PAGE10
  R133    2      B Q_RES_0402LF-33.2,1%,1/16W,CHIA    I97 @SCM_LIB.SCM(SCH_1):PAGE12
  R245    2      B Q_RES_0402LF-1.8K,1%,1/16W,CHIA   I146 @SCM_LIB.SCM(SCH_1):PAGE27

SMB_BMC_MM2_R_SCL @SCM_LIB.SCM(SCH_1):SMB_BMC_MM2_R_SCL
  R165    1      A Q_RES_0402LF-33.2,1%,1/16W,CHIA   I315 @SCM_LIB.SCM(SCH_1):PAGE12
    U5  E19 GPIOJ2||HVI3C4SCL||SCL2 AST2600A3GP-AST2600A3-GP,SMLF,A   I436 @SCM_LIB.SCM(SCH_1):PAGE12

SMB_BMC_MM2_R_SDA @SCM_LIB.SCM(SCH_1):SMB_BMC_MM2_R_SDA
  R394    1      A Q_RES_0402LF-33.2,1%,1/16W,CHIA   I314 @SCM_LIB.SCM(SCH_1):PAGE12
    U5  D20 GPIOJ3||HVI3C4SDA||SDA2 AST2600A3GP-AST2600A3-GP,SMLF,A   I436 @SCM_LIB.SCM(SCH_1):PAGE12

SMB_BMC_MM2_SCL @SCM_LIB.SCM(SCH_1):SMB_BMC_MM2_SCL
  R165    2      B Q_RES_0402LF-33.2,1%,1/16W,CHIA   I315 @SCM_LIB.SCM(SCH_1):PAGE12
  R410    2      B Q_RES_0402LF-49.9,1%,1/16W,CHIA    I56 @SCM_LIB.SCM(SCH_1):PAGE26
  R246    2      B Q_RES_0402LF-2.2K,5%,1/16W,CHIA   I145 @SCM_LIB.SCM(SCH_1):PAGE27
  R455    1      A Q_RES_0402LF-33.2,1%,1/16W,CHIA   I557 @SCM_LIB.SCM(SCH_1):PAGE10

SMB_BMC_MM2_SCL_R1 @SCM_LIB.SCM(SCH_1):SMB_BMC_MM2_SCL_R1
   GF1   A5 I2C_2_SCL FCONN168_ME1016810202011_SCM-FA   I553 @SCM_LIB.SCM(SCH_1):PAGE10
  R455    2      B Q_RES_0402LF-33.2,1%,1/16W,CHIA   I557 @SCM_LIB.SCM(SCH_1):PAGE10

SMB_BMC_MM2_SDA @SCM_LIB.SCM(SCH_1):SMB_BMC_MM2_SDA
   GF1   A6 I2C_2_SDA FCONN168_ME1016810202011_SCM-FA   I553 @SCM_LIB.SCM(SCH_1):PAGE10
  R394    2      B Q_RES_0402LF-33.2,1%,1/16W,CHIA   I314 @SCM_LIB.SCM(SCH_1):PAGE12
  R409    2      B Q_RES_0402LF-49.9,1%,1/16W,CHIA    I57 @SCM_LIB.SCM(SCH_1):PAGE26
  R247    2      B Q_RES_0402LF-2.2K,5%,1/16W,CHIA   I109 @SCM_LIB.SCM(SCH_1):PAGE27

SMB_BMC_MM3_R_SCL @SCM_LIB.SCM(SCH_1):SMB_BMC_MM3_R_SCL
  R589    1      A Q_RES_0402LF-33.2,1%,1/16W,CHIA   I316 @SCM_LIB.SCM(SCH_1):PAGE12
    U5  C19 GPIOJ4||HVI3C5SCL||SCL3 AST2600A3GP-AST2600A3-GP,SMLF,A   I436 @SCM_LIB.SCM(SCH_1):PAGE12

SMB_BMC_MM3_R_SDA @SCM_LIB.SCM(SCH_1):SMB_BMC_MM3_R_SDA
  R590    1      A Q_RES_0402LF-33.2,1%,1/16W,CHIA   I317 @SCM_LIB.SCM(SCH_1):PAGE12
    U5  A19 GPIOJ5||HVI3C5SDA||SDA3 AST2600A3GP-AST2600A3-GP,SMLF,A   I436 @SCM_LIB.SCM(SCH_1):PAGE12

SMB_BMC_MM3_SCL @SCM_LIB.SCM(SCH_1):SMB_BMC_MM3_SCL
   GF1   A7 I2C_3_SCL FCONN168_ME1016810202011_SCM-FA   I553 @SCM_LIB.SCM(SCH_1):PAGE10
  R589    2      B Q_RES_0402LF-33.2,1%,1/16W,CHIA   I316 @SCM_LIB.SCM(SCH_1):PAGE12
  R248    2      B Q_RES_0402LF-2.2K,5%,1/16W,CHIA   I107 @SCM_LIB.SCM(SCH_1):PAGE27

SMB_BMC_MM3_SDA @SCM_LIB.SCM(SCH_1):SMB_BMC_MM3_SDA
   GF1   A8 I2C_3_SDA FCONN168_ME1016810202011_SCM-FA   I553 @SCM_LIB.SCM(SCH_1):PAGE10
  R590    2      B Q_RES_0402LF-33.2,1%,1/16W,CHIA   I317 @SCM_LIB.SCM(SCH_1):PAGE12
  R249    2      B Q_RES_0402LF-2.2K,5%,1/16W,CHIA   I108 @SCM_LIB.SCM(SCH_1):PAGE27

SMB_BMC_MM4_R_SCL @SCM_LIB.SCM(SCH_1):SMB_BMC_MM4_R_SCL
    U5  C20 GPIOJ6||HVI3C6SCL||SCL4 AST2600A3GP-AST2600A3-GP,SMLF,A   I436 @SCM_LIB.SCM(SCH_1):PAGE12
  R138    1      A Q_RES_0402LF-40.2,1%,1/16W,CHIA   I513 @SCM_LIB.SCM(SCH_1):PAGE12

SMB_BMC_MM4_R_SDA @SCM_LIB.SCM(SCH_1):SMB_BMC_MM4_R_SDA
    U5  D19 GPIOJ7||HVI3C6SDA||SDA4 AST2600A3GP-AST2600A3-GP,SMLF,A   I436 @SCM_LIB.SCM(SCH_1):PAGE12
  R139    1      A Q_RES_0402LF-33.2,1%,1/16W,CHIA   I512 @SCM_LIB.SCM(SCH_1):PAGE12

SMB_BMC_MM4_SCL @SCM_LIB.SCM(SCH_1):SMB_BMC_MM4_SCL
   GF1   A9 I2C_4_SCL FCONN168_ME1016810202011_SCM-FA   I553 @SCM_LIB.SCM(SCH_1):PAGE10
  R250    2      B Q_RES_0402LF-402,1%,1/16W,CHIPA   I106 @SCM_LIB.SCM(SCH_1):PAGE27
  R138    2      B Q_RES_0402LF-40.2,1%,1/16W,CHIA   I513 @SCM_LIB.SCM(SCH_1):PAGE12

SMB_BMC_MM4_SDA @SCM_LIB.SCM(SCH_1):SMB_BMC_MM4_SDA
   GF1  A10 I2C_4_SDA FCONN168_ME1016810202011_SCM-FA   I553 @SCM_LIB.SCM(SCH_1):PAGE10
  R251    2      B Q_RES_0402LF-499,1%,1/16W,CHIPA   I247 @SCM_LIB.SCM(SCH_1):PAGE27
  R139    2      B Q_RES_0402LF-33.2,1%,1/16W,CHIA   I512 @SCM_LIB.SCM(SCH_1):PAGE12

SMB_BMC_MM5_R_SCL @SCM_LIB.SCM(SCH_1):SMB_BMC_MM5_R_SCL
   R71    1      A Q_RES_0402LF-33.2,1%,1/16W,CHIA   I277 @SCM_LIB.SCM(SCH_1):PAGE12
    U5  A11 GPIOK0||SCL5 AST2600A3GP-AST2600A3-GP,SMLF,A   I436 @SCM_LIB.SCM(SCH_1):PAGE12
  R252    2      B Q_RES_0402LF-2.2K,5%,1/16W,CHIA   I105 @SCM_LIB.SCM(SCH_1):PAGE27

SMB_BMC_MM5_R_SDA @SCM_LIB.SCM(SCH_1):SMB_BMC_MM5_R_SDA
   R93    1      A Q_RES_0402LF-33.2,1%,1/16W,CHIA   I276 @SCM_LIB.SCM(SCH_1):PAGE12
    U5  C11 GPIOK1||SDA5 AST2600A3GP-AST2600A3-GP,SMLF,A   I436 @SCM_LIB.SCM(SCH_1):PAGE12
  R253    2      B Q_RES_0402LF-2.2K,5%,1/16W,CHIA   I103 @SCM_LIB.SCM(SCH_1):PAGE27

SMB_BMC_MM5_SCL @SCM_LIB.SCM(SCH_1):SMB_BMC_MM5_SCL
   GF1  A11 I2C_5_SCL FCONN168_ME1016810202011_SCM-FA   I553 @SCM_LIB.SCM(SCH_1):PAGE10
   R71    2      B Q_RES_0402LF-33.2,1%,1/16W,CHIA   I277 @SCM_LIB.SCM(SCH_1):PAGE12

SMB_BMC_MM5_SDA @SCM_LIB.SCM(SCH_1):SMB_BMC_MM5_SDA
   GF1  A12 I2C_5_SDA FCONN168_ME1016810202011_SCM-FA   I553 @SCM_LIB.SCM(SCH_1):PAGE10
   R93    2      B Q_RES_0402LF-33.2,1%,1/16W,CHIA   I276 @SCM_LIB.SCM(SCH_1):PAGE12

SMB_BMC_MM6_R_SCL @SCM_LIB.SCM(SCH_1):SMB_BMC_MM6_R_SCL
  R142    1      A Q_RES_0402LF-33.2,1%,1/16W,CHIA    I88 @SCM_LIB.SCM(SCH_1):PAGE12
    U5  D12 GPIOK2||SCL6 AST2600A3GP-AST2600A3-GP,SMLF,A   I436 @SCM_LIB.SCM(SCH_1):PAGE12

SMB_BMC_MM6_R_SDA @SCM_LIB.SCM(SCH_1):SMB_BMC_MM6_R_SDA
  R143    1      A Q_RES_0402LF-33.2,1%,1/16W,CHIA    I89 @SCM_LIB.SCM(SCH_1):PAGE12
    U5  E13 GPIOK3||SDA6 AST2600A3GP-AST2600A3-GP,SMLF,A   I436 @SCM_LIB.SCM(SCH_1):PAGE12

SMB_BMC_MM6_SCL @SCM_LIB.SCM(SCH_1):SMB_BMC_MM6_SCL
   GF1  A23 I2C_6_SCL FCONN168_ME1016810202011_SCM-FA   I553 @SCM_LIB.SCM(SCH_1):PAGE10
  R142    2      B Q_RES_0402LF-33.2,1%,1/16W,CHIA    I88 @SCM_LIB.SCM(SCH_1):PAGE12
  R254    2      B Q_RES_0402LF-10K,1%,1/16W,CHIPA   I101 @SCM_LIB.SCM(SCH_1):PAGE27

SMB_BMC_MM6_SDA @SCM_LIB.SCM(SCH_1):SMB_BMC_MM6_SDA
   GF1  A24 I2C_6_SDA FCONN168_ME1016810202011_SCM-FA   I553 @SCM_LIB.SCM(SCH_1):PAGE10
  R143    2      B Q_RES_0402LF-33.2,1%,1/16W,CHIA    I89 @SCM_LIB.SCM(SCH_1):PAGE12
  R255    2      B Q_RES_0402LF-10K,1%,1/16W,CHIPA   I102 @SCM_LIB.SCM(SCH_1):PAGE27

SMB_BMC_MM7_R_SCL @SCM_LIB.SCM(SCH_1):SMB_BMC_MM7_R_SCL
  R567    1      A Q_RES_0402LF-33.2,1%,1/16W,CHIA   I274 @SCM_LIB.SCM(SCH_1):PAGE12
    U5  D11 GPIOK4||SCL7 AST2600A3GP-AST2600A3-GP,SMLF,A   I436 @SCM_LIB.SCM(SCH_1):PAGE12
  R256    2      B Q_RES_0402LF-2.2K,5%,1/16W,CHIA   I100 @SCM_LIB.SCM(SCH_1):PAGE27

SMB_BMC_MM7_R_SDA @SCM_LIB.SCM(SCH_1):SMB_BMC_MM7_R_SDA
  R570    1      A Q_RES_0402LF-33.2,1%,1/16W,CHIA   I275 @SCM_LIB.SCM(SCH_1):PAGE12
    U5  E11 GPIOK5||SDA7 AST2600A3GP-AST2600A3-GP,SMLF,A   I436 @SCM_LIB.SCM(SCH_1):PAGE12
  R257    2      B Q_RES_0402LF-2.2K,5%,1/16W,CHIA    I99 @SCM_LIB.SCM(SCH_1):PAGE27

SMB_BMC_MM7_SCL @SCM_LIB.SCM(SCH_1):SMB_BMC_MM7_SCL
   GF1  A25 I2C_7_SCL FCONN168_ME1016810202011_SCM-FA   I553 @SCM_LIB.SCM(SCH_1):PAGE10
  R567    2      B Q_RES_0402LF-33.2,1%,1/16W,CHIA   I274 @SCM_LIB.SCM(SCH_1):PAGE12

SMB_BMC_MM7_SDA @SCM_LIB.SCM(SCH_1):SMB_BMC_MM7_SDA
   GF1  A26 I2C_7_SDA FCONN168_ME1016810202011_SCM-FA   I553 @SCM_LIB.SCM(SCH_1):PAGE10
  R570    2      B Q_RES_0402LF-33.2,1%,1/16W,CHIA   I275 @SCM_LIB.SCM(SCH_1):PAGE12

SMB_BMC_MM8_R_SCL @SCM_LIB.SCM(SCH_1):SMB_BMC_MM8_R_SCL
  R146    1      A Q_RES_0402LF-33.2,1%,1/16W,CHIA   I235 @SCM_LIB.SCM(SCH_1):PAGE12
    U5  F13 GPIOK6||SCL8 AST2600A3GP-AST2600A3-GP,SMLF,A   I436 @SCM_LIB.SCM(SCH_1):PAGE12

SMB_BMC_MM8_R_SDA @SCM_LIB.SCM(SCH_1):SMB_BMC_MM8_R_SDA
  R147    1      A Q_RES_0402LF-33.2,1%,1/16W,CHIA   I236 @SCM_LIB.SCM(SCH_1):PAGE12
    U5  E12 GPIOK7||SDA8 AST2600A3GP-AST2600A3-GP,SMLF,A   I436 @SCM_LIB.SCM(SCH_1):PAGE12

SMB_BMC_MM8_SCL @SCM_LIB.SCM(SCH_1):SMB_BMC_MM8_SCL
   GF1  A27 I2C_8_SCL FCONN168_ME1016810202011_SCM-FA   I553 @SCM_LIB.SCM(SCH_1):PAGE10
  R146    2      B Q_RES_0402LF-33.2,1%,1/16W,CHIA   I235 @SCM_LIB.SCM(SCH_1):PAGE12
  R258    2      B Q_RES_0402LF-2.2K,5%,1/16W,CHIA    I98 @SCM_LIB.SCM(SCH_1):PAGE27

SMB_BMC_MM8_SDA @SCM_LIB.SCM(SCH_1):SMB_BMC_MM8_SDA
   GF1  A28 I2C_8_SDA FCONN168_ME1016810202011_SCM-FA   I553 @SCM_LIB.SCM(SCH_1):PAGE10
  R147    2      B Q_RES_0402LF-33.2,1%,1/16W,CHIA   I236 @SCM_LIB.SCM(SCH_1):PAGE12
  R259    2      B Q_RES_0402LF-2.2K,5%,1/16W,CHIA    I96 @SCM_LIB.SCM(SCH_1):PAGE27

SMB_BMC_MM9_R_SCL @SCM_LIB.SCM(SCH_1):SMB_BMC_MM9_R_SCL
  R580    1      A Q_RES_0402LF-33.2,1%,1/16W,CHIA   I321 @SCM_LIB.SCM(SCH_1):PAGE12
    U5  D15 GPIOL0||SCL9 AST2600A3GP-AST2600A3-GP,SMLF,A   I436 @SCM_LIB.SCM(SCH_1):PAGE12

SMB_BMC_MM9_R_SDA @SCM_LIB.SCM(SCH_1):SMB_BMC_MM9_R_SDA
  R582    1      A Q_RES_0402LF-33.2,1%,1/16W,CHIA   I318 @SCM_LIB.SCM(SCH_1):PAGE12
    U5  A14 GPIOL1||SDA9 AST2600A3GP-AST2600A3-GP,SMLF,A   I436 @SCM_LIB.SCM(SCH_1):PAGE12

SMB_BMC_MM9_SCL @SCM_LIB.SCM(SCH_1):SMB_BMC_MM9_SCL
   GF1  A29 I2C_9_SCL FCONN168_ME1016810202011_SCM-FA   I553 @SCM_LIB.SCM(SCH_1):PAGE10
  R580    2      B Q_RES_0402LF-33.2,1%,1/16W,CHIA   I321 @SCM_LIB.SCM(SCH_1):PAGE12
  R260    2      B Q_RES_0402LF-10K,1%,1/16W,CHIPA    I97 @SCM_LIB.SCM(SCH_1):PAGE27

SMB_BMC_MM9_SDA @SCM_LIB.SCM(SCH_1):SMB_BMC_MM9_SDA
   GF1  A30 I2C_9_SDA FCONN168_ME1016810202011_SCM-FA   I553 @SCM_LIB.SCM(SCH_1):PAGE10
  R582    2      B Q_RES_0402LF-33.2,1%,1/16W,CHIA   I318 @SCM_LIB.SCM(SCH_1):PAGE12
  R261    2      B Q_RES_0402LF-10K,1%,1/16W,CHIPA    I94 @SCM_LIB.SCM(SCH_1):PAGE27

SMB_BMC_TPM_MM16_SCL @SCM_LIB.SCM(SCH_1):SMB_BMC_TPM_MM16_SCL
   R47    1      A Q_RES_0402LF-33.2,1%,1/16W,CHIA   I106 @SCM_LIB.SCM(SCH_1):PAGE46
   J10   10     10 SCONN11_9192031111LF-SCONN11_9A   I113 @SCM_LIB.SCM(SCH_1):PAGE46

SMB_BMC_TPM_MM16_SDA @SCM_LIB.SCM(SCH_1):SMB_BMC_TPM_MM16_SDA
   J10    6      6 SCONN11_9192031111LF-SCONN11_9A   I113 @SCM_LIB.SCM(SCH_1):PAGE46
   R33    2      B Q_RES_0402LF-33.2,1%,1/16W,CHIA   I117 @SCM_LIB.SCM(SCH_1):PAGE46

SMB_DEBUG_AUX_LVC3_USB_R1_SCL @SCM_LIB.SCM(SCH_1):SMB_DEBUG_AUX_LVC3_USB_R1_SCL
  R298    2      B Q_RES_0402LF-4.7K,1%,1/16W,CHIA    I96 @SCM_LIB.SCM(SCH_1):PAGE28
   U37    7   SCLB PCA9517ADP_SMLF-PCA9517ADP,IC,A    I99 @SCM_LIB.SCM(SCH_1):PAGE28
  R300    1      A Q_RES_0402LF-33.2,1%,1/16W,CHIA   I183 @SCM_LIB.SCM(SCH_1):PAGE28

SMB_DEBUG_AUX_LVC3_USB_R1_SDA @SCM_LIB.SCM(SCH_1):SMB_DEBUG_AUX_LVC3_USB_R1_SDA
  R299    2      B Q_RES_0402LF-4.7K,1%,1/16W,CHIA    I91 @SCM_LIB.SCM(SCH_1):PAGE28
   U37    6   SDAB PCA9517ADP_SMLF-PCA9517ADP,IC,A    I99 @SCM_LIB.SCM(SCH_1):PAGE28
  R302    1      A Q_RES_0402LF-33.2,1%,1/16W,CHIA   I184 @SCM_LIB.SCM(SCH_1):PAGE28

SMB_DEBUG_AUX_LVC3_USB_R2_SCL @SCM_LIB.SCM(SCH_1):SMB_DEBUG_AUX_LVC3_USB_R2_SCL
  R732    2      B Q_RES_0402LF-0,5%,1/16W,CHIP,CA   I136 @SCM_LIB.SCM(SCH_1):PAGE29
   U22   12   C1_N PI3PCIE3212ZBEX-PI3PCIE3212ZBEA   I206 @SCM_LIB.SCM(SCH_1):PAGE29

SMB_DEBUG_AUX_LVC3_USB_R2_SDA @SCM_LIB.SCM(SCH_1):SMB_DEBUG_AUX_LVC3_USB_R2_SDA
  R731    2      B Q_RES_0402LF-0,5%,1/16W,CHIP,CA   I135 @SCM_LIB.SCM(SCH_1):PAGE29
   U22   13   C1_P PI3PCIE3212ZBEX-PI3PCIE3212ZBEA   I206 @SCM_LIB.SCM(SCH_1):PAGE29

SMB_DEBUG_AUX_LVC3_USB_R3_SCL @SCM_LIB.SCM(SCH_1):SMB_DEBUG_AUX_LVC3_USB_R3_SCL
   U40   22    SCL PCA9555PW_SMLF-PCA9555PW,IC,TMA   I141 @SCM_LIB.SCM(SCH_1):PAGE28
  R632    2      B Q_RES_0402LF-0,5%,1/16W,CHIP,CA   I153 @SCM_LIB.SCM(SCH_1):PAGE28

SMB_DEBUG_AUX_LVC3_USB_R3_SDA @SCM_LIB.SCM(SCH_1):SMB_DEBUG_AUX_LVC3_USB_R3_SDA
   U40   23    SDA PCA9555PW_SMLF-PCA9555PW,IC,TMA   I141 @SCM_LIB.SCM(SCH_1):PAGE28
   R95    2      B Q_RES_0402LF-0,5%,1/16W,CHIP,CA   I152 @SCM_LIB.SCM(SCH_1):PAGE28

SMB_DEBUG_AUX_LVC3_USB_SCL @SCM_LIB.SCM(SCH_1):SMB_DEBUG_AUX_LVC3_USB_SCL
  R632    1      A Q_RES_0402LF-0,5%,1/16W,CHIP,CA   I153 @SCM_LIB.SCM(SCH_1):PAGE28
  R732    1      A Q_RES_0402LF-0,5%,1/16W,CHIP,CA   I136 @SCM_LIB.SCM(SCH_1):PAGE29
  R300    2      B Q_RES_0402LF-33.2,1%,1/16W,CHIA   I183 @SCM_LIB.SCM(SCH_1):PAGE28

SMB_DEBUG_AUX_LVC3_USB_SDA @SCM_LIB.SCM(SCH_1):SMB_DEBUG_AUX_LVC3_USB_SDA
   R95    1      A Q_RES_0402LF-0,5%,1/16W,CHIP,CA   I152 @SCM_LIB.SCM(SCH_1):PAGE28
  R731    1      A Q_RES_0402LF-0,5%,1/16W,CHIP,CA   I135 @SCM_LIB.SCM(SCH_1):PAGE29
  R302    2      B Q_RES_0402LF-33.2,1%,1/16W,CHIA   I184 @SCM_LIB.SCM(SCH_1):PAGE28

SMB_PCH_TPM_SCL @SCM_LIB.SCM(SCH_1):SMB_PCH_TPM_SCL
    J5   10     10 SCONN11_9192031111LF-SCONN11_9A    I56 @SCM_LIB.SCM(SCH_1):PAGE46
  R136    2      B Q_RES_0402LF-10K,1%,1/16W,CHIPA   I132 @SCM_LIB.SCM(SCH_1):PAGE46

SMB_PCH_TPM_SDA @SCM_LIB.SCM(SCH_1):SMB_PCH_TPM_SDA
    J5    6      6 SCONN11_9192031111LF-SCONN11_9A    I56 @SCM_LIB.SCM(SCH_1):PAGE46
  R126    1      A Q_RES_0402LF-10K,1%,1/16W,CHIPA   I134 @SCM_LIB.SCM(SCH_1):PAGE46

SMB_TMP421_BMC_MM2_SCL @SCM_LIB.SCM(SCH_1):SMB_TMP421_BMC_MM2_SCL
  R410    1      A Q_RES_0402LF-49.9,1%,1/16W,CHIA    I56 @SCM_LIB.SCM(SCH_1):PAGE26
   J14    4      4 CONN8_TSW10407FD-CONN8_TSW-104A    I71 @SCM_LIB.SCM(SCH_1):PAGE26

SMB_TMP421_BMC_MM2_SDA @SCM_LIB.SCM(SCH_1):SMB_TMP421_BMC_MM2_SDA
  R409    1      A Q_RES_0402LF-49.9,1%,1/16W,CHIA    I57 @SCM_LIB.SCM(SCH_1):PAGE26
   J14    2      2 CONN8_TSW10407FD-CONN8_TSW-104A    I71 @SCM_LIB.SCM(SCH_1):PAGE26

SPA_SIN_SW_BUF @SCM_LIB.SCM(SCH_1):SPA_SIN_SW_BUF
  R737    2      B Q_RES_0402LF-4.7K,1%,1/16W,EMPA   I192 @SCM_LIB.SCM(SCH_1):PAGE30
    U3    7      A FSA3357K8X-FSA3357K8X,SMLF,IC,A   I251 @SCM_LIB.SCM(SCH_1):PAGE30
  R726    2      B Q_RES_0402LF-0,5%,1/16W,CHIP,CA   I266 @SCM_LIB.SCM(SCH_1):PAGE30

SPA_SIN_SW_BUF_R @SCM_LIB.SCM(SCH_1):SPA_SIN_SW_BUF_R
  R726    1      A Q_RES_0402LF-0,5%,1/16W,CHIP,CA   I266 @SCM_LIB.SCM(SCH_1):PAGE30
   U20    4      A NC7SB3157_SMLF-NC7SB3157P6X,NCA    I38 @SCM_LIB.SCM(SCH_1):PAGE31

SPA_SIN_SW_DBG @SCM_LIB.SCM(SCH_1):SPA_SIN_SW_DBG
   U36    4      4 74HC1G126GW-74HC1G126GW,SMLF,IA   I164 @SCM_LIB.SCM(SCH_1):PAGE29
  R193    2      B Q_RES_0402LF-100K,1%,1/16W,CHIA   I166 @SCM_LIB.SCM(SCH_1):PAGE29
  R628    1      A Q_RES_0402LF-100,1%,1/16W,CHIPA    I77 @SCM_LIB.SCM(SCH_1):PAGE31

SPA_SIN_SW_DBG_R @SCM_LIB.SCM(SCH_1):SPA_SIN_SW_DBG_R
   U20    1     B1 NC7SB3157_SMLF-NC7SB3157P6X,NCA    I38 @SCM_LIB.SCM(SCH_1):PAGE31
  R628    2      B Q_RES_0402LF-100,1%,1/16W,CHIPA    I77 @SCM_LIB.SCM(SCH_1):PAGE31

SPA_SOUT_SW_BUF @SCM_LIB.SCM(SCH_1):SPA_SOUT_SW_BUF
  R742    2      B Q_RES_0402LF-4.7K,1%,1/16W,EMPA   I195 @SCM_LIB.SCM(SCH_1):PAGE30
    U2    7      A FSA3357K8X-FSA3357K8X,SMLF,IC,A   I250 @SCM_LIB.SCM(SCH_1):PAGE30
   R39    2      B Q_RES_0402LF-0,5%,1/16W,CHIP,CA   I267 @SCM_LIB.SCM(SCH_1):PAGE30

SPA_SOUT_SW_BUF_R @SCM_LIB.SCM(SCH_1):SPA_SOUT_SW_BUF_R
   R39    1      A Q_RES_0402LF-0,5%,1/16W,CHIP,CA   I267 @SCM_LIB.SCM(SCH_1):PAGE30
    U7    4      A NC7SB3157_SMLF-NC7SB3157P6X,NCA    I27 @SCM_LIB.SCM(SCH_1):PAGE31

SPA_SOUT_SW_DBG @SCM_LIB.SCM(SCH_1):SPA_SOUT_SW_DBG
   U29    2      2 74HC1G126GW-74HC1G126GW,SMLF,IA   I174 @SCM_LIB.SCM(SCH_1):PAGE29
  R546    1      A Q_RES_0402LF-0,5%,1/16W,CHIP,CA    I75 @SCM_LIB.SCM(SCH_1):PAGE31

SPA_SOUT_SW_DBG_R @SCM_LIB.SCM(SCH_1):SPA_SOUT_SW_DBG_R
    U7    1     B1 NC7SB3157_SMLF-NC7SB3157P6X,NCA    I27 @SCM_LIB.SCM(SCH_1):PAGE31
  R546    2      B Q_RES_0402LF-0,5%,1/16W,CHIP,CA    I75 @SCM_LIB.SCM(SCH_1):PAGE31

SPI_BMC_BIOS_CS0_N @SCM_LIB.SCM(SCH_1):SPI_BMC_BIOS_CS0_N
  R799    1      A Q_RES_0402LF-33.2,1%,1/16W,CHIA   I215 @SCM_LIB.SCM(SCH_1):PAGE13
  R728    1      A Q_RES_0402LF-0,5%,1/16W,CHIP,CA   I336 @SCM_LIB.SCM(SCH_1):PAGE44

SPI_BMC_BIOS_CS0_R1_N @SCM_LIB.SCM(SCH_1):SPI_BMC_BIOS_CS0_R1_N
  R799    2      B Q_RES_0402LF-33.2,1%,1/16W,CHIA   I215 @SCM_LIB.SCM(SCH_1):PAGE13
    U5  AE8 GPIOX0||SPI2CS0# AST2600A3GP-AST2600A3-GP,SMLF,A   I363 @SCM_LIB.SCM(SCH_1):PAGE13

SPI_BMC_BIOS_ROM_CLK @SCM_LIB.SCM(SCH_1):SPI_BMC_BIOS_ROM_CLK
    U5  AF8 GPIOX3||SPI2CK AST2600A3GP-AST2600A3-GP,SMLF,A   I363 @SCM_LIB.SCM(SCH_1):PAGE13
  R174    1      A Q_RES_0402LF-33.2,1%,1/16W,CHIA   I331 @SCM_LIB.SCM(SCH_1):PAGE44

SPI_BMC_BIOS_ROM_IO2 @SCM_LIB.SCM(SCH_1):SPI_BMC_BIOS_ROM_IO2
    U5  AF9 GPIOX6||SPI2DQ2||TXD12 AST2600A3GP-AST2600A3-GP,SMLF,A   I363 @SCM_LIB.SCM(SCH_1):PAGE13
  R724    1      A Q_RES_0402LF-33.2,1%,1/16W,CHIA   I333 @SCM_LIB.SCM(SCH_1):PAGE44

SPI_BMC_BIOS_ROM_IO3 @SCM_LIB.SCM(SCH_1):SPI_BMC_BIOS_ROM_IO3
    U5 AB10 GPIOX7||SPI2DQ3||RXD12 AST2600A3GP-AST2600A3-GP,SMLF,A   I363 @SCM_LIB.SCM(SCH_1):PAGE13
  R725    1      A Q_RES_0402LF-33.2,1%,1/16W,CHIA   I334 @SCM_LIB.SCM(SCH_1):PAGE44

SPI_BMC_BIOS_ROM_MISO @SCM_LIB.SCM(SCH_1):SPI_BMC_BIOS_ROM_MISO
    U5  AD9 GPIOX5||SPI2MISO AST2600A3GP-AST2600A3-GP,SMLF,A   I363 @SCM_LIB.SCM(SCH_1):PAGE13
  R176    1      A Q_RES_0402LF-33.2,1%,1/16W,CHIA   I332 @SCM_LIB.SCM(SCH_1):PAGE44

SPI_BMC_BIOS_ROM_MOSI @SCM_LIB.SCM(SCH_1):SPI_BMC_BIOS_ROM_MOSI
    U5  AB9 GPIOX4||SPI2MOSI AST2600A3GP-AST2600A3-GP,SMLF,A   I363 @SCM_LIB.SCM(SCH_1):PAGE13
  R175    1      A Q_RES_0402LF-33.2,1%,1/16W,CHIA   I330 @SCM_LIB.SCM(SCH_1):PAGE44

SPI_BMC_BIOS_ROM_R_CLK @SCM_LIB.SCM(SCH_1):SPI_BMC_BIOS_ROM_R_CLK
   U30   10   I_1C IDTQS3VH257PAG_SMLF-IDTQS3VH25A   I271 @SCM_LIB.SCM(SCH_1):PAGE44
  R174    2      B Q_RES_0402LF-33.2,1%,1/16W,CHIA   I331 @SCM_LIB.SCM(SCH_1):PAGE44

SPI_BMC_BIOS_ROM_R_IO2 @SCM_LIB.SCM(SCH_1):SPI_BMC_BIOS_ROM_R_IO2
   U21    3   I_1A IDTQS3VH257PAG_SMLF-IDTQS3VH25A   I296 @SCM_LIB.SCM(SCH_1):PAGE44
  R724    2      B Q_RES_0402LF-33.2,1%,1/16W,CHIA   I333 @SCM_LIB.SCM(SCH_1):PAGE44

SPI_BMC_BIOS_ROM_R_IO3 @SCM_LIB.SCM(SCH_1):SPI_BMC_BIOS_ROM_R_IO3
   U30    6   I_1B IDTQS3VH257PAG_SMLF-IDTQS3VH25A   I271 @SCM_LIB.SCM(SCH_1):PAGE44
  R725    2      B Q_RES_0402LF-33.2,1%,1/16W,CHIA   I334 @SCM_LIB.SCM(SCH_1):PAGE44

SPI_BMC_BIOS_ROM_R_MISO @SCM_LIB.SCM(SCH_1):SPI_BMC_BIOS_ROM_R_MISO
   U21    6   I_1B IDTQS3VH257PAG_SMLF-IDTQS3VH25A   I296 @SCM_LIB.SCM(SCH_1):PAGE44
  R176    2      B Q_RES_0402LF-33.2,1%,1/16W,CHIA   I332 @SCM_LIB.SCM(SCH_1):PAGE44

SPI_BMC_BIOS_ROM_R_MOSI @SCM_LIB.SCM(SCH_1):SPI_BMC_BIOS_ROM_R_MOSI
   U30    3   I_1A IDTQS3VH257PAG_SMLF-IDTQS3VH25A   I271 @SCM_LIB.SCM(SCH_1):PAGE44
  R175    2      B Q_RES_0402LF-33.2,1%,1/16W,CHIA   I330 @SCM_LIB.SCM(SCH_1):PAGE44

SPI_BMC_BIOS_SOURCE_CS0_N @SCM_LIB.SCM(SCH_1):SPI_BMC_BIOS_SOURCE_CS0_N
   U21   10   I_1C IDTQS3VH257PAG_SMLF-IDTQS3VH25A   I296 @SCM_LIB.SCM(SCH_1):PAGE44
  R728    2      B Q_RES_0402LF-0,5%,1/16W,CHIP,CA   I336 @SCM_LIB.SCM(SCH_1):PAGE44

SPI_BMC_BOOT_CLK @SCM_LIB.SCM(SCH_1):SPI_BMC_BOOT_CLK
  R178    2      B Q_RES_0402LF-33.2,1%,1/16W,CHIA    I94 @SCM_LIB.SCM(SCH_1):PAGE13
  R699    2      B Q_RES_0402LF-4.7K,1%,1/16W,EMPA   I163 @SCM_LIB.SCM(SCH_1):PAGE27
  R549    2      B Q_RES_0402LF-33.2,1%,1/16W,CHIA   I177 @SCM_LIB.SCM(SCH_1):PAGE21

SPI_BMC_BOOT_CS0_R1_N @SCM_LIB.SCM(SCH_1):SPI_BMC_BOOT_CS0_R1_N
  R801    2      B Q_RES_0402LF-33.2,1%,1/16W,CHIA   I217 @SCM_LIB.SCM(SCH_1):PAGE13
    U5 AB14 FWSPICS0# AST2600A3GP-AST2600A3-GP,SMLF,A   I363 @SCM_LIB.SCM(SCH_1):PAGE13

SPI_BMC_BOOT_CS0_R_N @SCM_LIB.SCM(SCH_1):SPI_BMC_BOOT_CS0_R_N
  R801    1      A Q_RES_0402LF-33.2,1%,1/16W,CHIA   I217 @SCM_LIB.SCM(SCH_1):PAGE13
  R553    2      B Q_RES_0402LF-33.2,1%,1/16W,CHIA   I175 @SCM_LIB.SCM(SCH_1):PAGE21

SPI_BMC_BOOT_CS1_R1_N @SCM_LIB.SCM(SCH_1):SPI_BMC_BOOT_CS1_R1_N
  R802    2      B Q_RES_0402LF-33.2,1%,1/16W,CHIA   I218 @SCM_LIB.SCM(SCH_1):PAGE13
    U5 AA13 FWSPICS1# AST2600A3GP-AST2600A3-GP,SMLF,A   I363 @SCM_LIB.SCM(SCH_1):PAGE13

SPI_BMC_BOOT_CS1_R_N @SCM_LIB.SCM(SCH_1):SPI_BMC_BOOT_CS1_R_N
  R802    1      A Q_RES_0402LF-33.2,1%,1/16W,CHIA   I218 @SCM_LIB.SCM(SCH_1):PAGE13
  R547    2      B Q_RES_0402LF-33.2,1%,1/16W,CHIA   I176 @SCM_LIB.SCM(SCH_1):PAGE21

SPI_BMC_BOOT_MISO @SCM_LIB.SCM(SCH_1):SPI_BMC_BOOT_MISO
  R180    2      B Q_RES_0402LF-33.2,1%,1/16W,CHIA    I96 @SCM_LIB.SCM(SCH_1):PAGE13
  R753    2      B Q_RES_0402LF-4.7K,1%,1/16W,EMPA   I233 @SCM_LIB.SCM(SCH_1):PAGE27
  R164    1      A Q_RES_0402LF-100,1%,1/16W,EMPTA   I244 @SCM_LIB.SCM(SCH_1):PAGE27
  R552    2      B Q_RES_0402LF-33.2,1%,1/16W,CHIA   I179 @SCM_LIB.SCM(SCH_1):PAGE21

SPI_BMC_BOOT_MOSI @SCM_LIB.SCM(SCH_1):SPI_BMC_BOOT_MOSI
  R179    2      B Q_RES_0402LF-33.2,1%,1/16W,CHIA    I95 @SCM_LIB.SCM(SCH_1):PAGE13
  R140    2      B Q_RES_0402LF-4.7K,1%,1/16W,EMPA   I228 @SCM_LIB.SCM(SCH_1):PAGE27
   R94    1      A Q_RES_0402LF-4.7K,1%,1/16W,CHIA   I246 @SCM_LIB.SCM(SCH_1):PAGE27
  R550    2      B Q_RES_0402LF-33.2,1%,1/16W,CHIA   I178 @SCM_LIB.SCM(SCH_1):PAGE21

SPI_BMC_BT_WP0_N_R @SCM_LIB.SCM(SCH_1):SPI_BMC_BT_WP0_N_R
    J4    5      5 SCONN67_NASA0S6730TS67-SCONN67A    I84 @SCM_LIB.SCM(SCH_1):PAGE21
  R665    1      A Q_RES_0402LF-1K,1%,1/16W,EMPTYB   I125 @SCM_LIB.SCM(SCH_1):PAGE21
  R559    1      A Q_RES_0402LF-33.2,1%,1/16W,CHIA   I176 @SCM_LIB.SCM(SCH_1):PAGE25

SPI_BMC_BT_WP1_N_R @SCM_LIB.SCM(SCH_1):SPI_BMC_BT_WP1_N_R
    J4    3      3 SCONN67_NASA0S6730TS67-SCONN67A    I84 @SCM_LIB.SCM(SCH_1):PAGE21
  R664    1      A Q_RES_0402LF-1K,1%,1/16W,EMPTYB   I128 @SCM_LIB.SCM(SCH_1):PAGE21
  R556    1      A Q_RES_0402LF-33.2,1%,1/16W,CHIA   I175 @SCM_LIB.SCM(SCH_1):PAGE25

SPI_BMC_CLK_FLASH_R @SCM_LIB.SCM(SCH_1):SPI_BMC_CLK_FLASH_R
    J4   31     31 SCONN67_NASA0S6730TS67-SCONN67A    I84 @SCM_LIB.SCM(SCH_1):PAGE21
  R549    1      A Q_RES_0402LF-33.2,1%,1/16W,CHIA   I177 @SCM_LIB.SCM(SCH_1):PAGE21

SPI_BMC_CLK_R @SCM_LIB.SCM(SCH_1):SPI_BMC_CLK_R
  R178    1      A Q_RES_0402LF-33.2,1%,1/16W,CHIA    I94 @SCM_LIB.SCM(SCH_1):PAGE13
  R678    1      A Q_RES_0402LF-33.2,1%,1/16W,EMPA   I239 @SCM_LIB.SCM(SCH_1):PAGE13
    U5 AF13 FWSPICK AST2600A3GP-AST2600A3-GP,SMLF,A   I363 @SCM_LIB.SCM(SCH_1):PAGE13

SPI_BMC_CS0_FLASH_R_N @SCM_LIB.SCM(SCH_1):SPI_BMC_CS0_FLASH_R_N
    J4   37     37 SCONN67_NASA0S6730TS67-SCONN67A    I84 @SCM_LIB.SCM(SCH_1):PAGE21
  R557    2      B Q_RES_0402LF-4.7K,1%,1/16W,CHIA   I173 @SCM_LIB.SCM(SCH_1):PAGE21
  R553    1      A Q_RES_0402LF-33.2,1%,1/16W,CHIA   I175 @SCM_LIB.SCM(SCH_1):PAGE21

SPI_BMC_CS1_FLASH_R_N @SCM_LIB.SCM(SCH_1):SPI_BMC_CS1_FLASH_R_N
    J4   35     35 SCONN67_NASA0S6730TS67-SCONN67A    I84 @SCM_LIB.SCM(SCH_1):PAGE21
  R558    2      B Q_RES_0402LF-4.7K,1%,1/16W,CHIA   I174 @SCM_LIB.SCM(SCH_1):PAGE21
  R547    1      A Q_RES_0402LF-33.2,1%,1/16W,CHIA   I176 @SCM_LIB.SCM(SCH_1):PAGE21

SPI_BMC_HOLD0_N @SCM_LIB.SCM(SCH_1):SPI_BMC_HOLD0_N
    J4   28     28 SCONN67_NASA0S6730TS67-SCONN67A    I84 @SCM_LIB.SCM(SCH_1):PAGE21
   R58    2      B Q_RES_0402LF-4.7K,1%,1/16W,EMPB   I168 @SCM_LIB.SCM(SCH_1):PAGE21

SPI_BMC_HOLD1_N @SCM_LIB.SCM(SCH_1):SPI_BMC_HOLD1_N
    J4   26     26 SCONN67_NASA0S6730TS67-SCONN67A    I84 @SCM_LIB.SCM(SCH_1):PAGE21
  R543    2      B Q_RES_0402LF-4.7K,1%,1/16W,EMPB   I147 @SCM_LIB.SCM(SCH_1):PAGE21

SPI_BMC_IO0_FLASH_R @SCM_LIB.SCM(SCH_1):SPI_BMC_IO0_FLASH_R
    J4   27     27 SCONN67_NASA0S6730TS67-SCONN67A    I84 @SCM_LIB.SCM(SCH_1):PAGE21
  R550    1      A Q_RES_0402LF-33.2,1%,1/16W,CHIA   I178 @SCM_LIB.SCM(SCH_1):PAGE21

SPI_BMC_IO1_FLASH_R @SCM_LIB.SCM(SCH_1):SPI_BMC_IO1_FLASH_R
    J4   25     25 SCONN67_NASA0S6730TS67-SCONN67A    I84 @SCM_LIB.SCM(SCH_1):PAGE21
  R552    1      A Q_RES_0402LF-33.2,1%,1/16W,CHIA   I179 @SCM_LIB.SCM(SCH_1):PAGE21

SPI_BMC_IO2_R @SCM_LIB.SCM(SCH_1):SPI_BMC_IO2_R
  R681    1      A Q_RES_0402LF-33.2,1%,1/16W,EMPA   I245 @SCM_LIB.SCM(SCH_1):PAGE13
    U5 AE12 GPIOY4||FWSPIDQ2 AST2600A3GP-AST2600A3-GP,SMLF,A   I363 @SCM_LIB.SCM(SCH_1):PAGE13

SPI_BMC_IO3_R @SCM_LIB.SCM(SCH_1):SPI_BMC_IO3_R
  R682    1      A Q_RES_0402LF-33.2,1%,1/16W,EMPA   I246 @SCM_LIB.SCM(SCH_1):PAGE13
    U5 AF12 GPIOY5||FWSPIDQ3 AST2600A3GP-AST2600A3-GP,SMLF,A   I363 @SCM_LIB.SCM(SCH_1):PAGE13

SPI_BMC_MISO_IO1_R @SCM_LIB.SCM(SCH_1):SPI_BMC_MISO_IO1_R
  R180    1      A Q_RES_0402LF-33.2,1%,1/16W,CHIA    I96 @SCM_LIB.SCM(SCH_1):PAGE13
  R680    1      A Q_RES_0402LF-33.2,1%,1/16W,EMPA   I248 @SCM_LIB.SCM(SCH_1):PAGE13
    U5 AB13 FWSPIMISO AST2600A3GP-AST2600A3-GP,SMLF,A   I363 @SCM_LIB.SCM(SCH_1):PAGE13

SPI_BMC_MOSI_IO0_R @SCM_LIB.SCM(SCH_1):SPI_BMC_MOSI_IO0_R
  R179    1      A Q_RES_0402LF-33.2,1%,1/16W,CHIA    I95 @SCM_LIB.SCM(SCH_1):PAGE13
  R679    1      A Q_RES_0402LF-33.2,1%,1/16W,EMPA   I247 @SCM_LIB.SCM(SCH_1):PAGE13
    U5 AC14 FWSPIMOSI AST2600A3GP-AST2600A3-GP,SMLF,A   I363 @SCM_LIB.SCM(SCH_1):PAGE13

SPI_BMC_TPM_CLK @SCM_LIB.SCM(SCH_1):SPI_BMC_TPM_CLK
  R109    2      B Q_RES_0402LF-0,5%,1/16W,CHIP,CA   I114 @SCM_LIB.SCM(SCH_1):PAGE46
  R408    2      B Q_RES_0402LF-4.7K,1%,1/16W,EMPB   I139 @SCM_LIB.SCM(SCH_1):PAGE46
  R468    2      B Q_RES_0402LF-90.9,1%,1/16W,CHIA   I449 @SCM_LIB.SCM(SCH_1):PAGE13

SPI_BMC_TPM_CLK_R @SCM_LIB.SCM(SCH_1):SPI_BMC_TPM_CLK_R
   J10    1      1 SCONN11_9192031111LF-SCONN11_9A   I113 @SCM_LIB.SCM(SCH_1):PAGE46
  R109    1      A Q_RES_0402LF-0,5%,1/16W,CHIP,CA   I114 @SCM_LIB.SCM(SCH_1):PAGE46

SPI_BMC_TPM_CLK_R1 @SCM_LIB.SCM(SCH_1):SPI_BMC_TPM_CLK_R1
    U5 AB11 GPIOZ3||SPI1CK AST2600A3GP-AST2600A3-GP,SMLF,A   I363 @SCM_LIB.SCM(SCH_1):PAGE13
  R468    1      A Q_RES_0402LF-90.9,1%,1/16W,CHIA   I449 @SCM_LIB.SCM(SCH_1):PAGE13

SPI_BMC_TPM_CS2_N_R @SCM_LIB.SCM(SCH_1):SPI_BMC_TPM_CS2_N_R
   J10    5      5 SCONN11_9192031111LF-SCONN11_9A   I113 @SCM_LIB.SCM(SCH_1):PAGE46
  R100    1      A Q_RES_0402LF-33.2,1%,1/16W,CHIA   I147 @SCM_LIB.SCM(SCH_1):PAGE46

SPI_BMC_TPM_CS2_R1_N @SCM_LIB.SCM(SCH_1):SPI_BMC_TPM_CS2_R1_N
  R460    2      B Q_RES_0402LF-33.2,1%,1/16W,CHIA   I312 @SCM_LIB.SCM(SCH_1):PAGE13
    U5 AC10 GPIOZ0||SPI1CS1# AST2600A3GP-AST2600A3-GP,SMLF,A   I363 @SCM_LIB.SCM(SCH_1):PAGE13

SPI_BMC_TPM_CS2_R_N @SCM_LIB.SCM(SCH_1):SPI_BMC_TPM_CS2_R_N
  R238    2      B Q_RES_0402LF-4.7K,1%,1/16W,CHIA   I184 @SCM_LIB.SCM(SCH_1):PAGE13
  R460    1      A Q_RES_0402LF-33.2,1%,1/16W,CHIA   I312 @SCM_LIB.SCM(SCH_1):PAGE13
  R100    2      B Q_RES_0402LF-33.2,1%,1/16W,CHIA   I147 @SCM_LIB.SCM(SCH_1):PAGE46

SPI_BMC_TPM_MISO @SCM_LIB.SCM(SCH_1):SPI_BMC_TPM_MISO
  R469    2      B Q_RES_0402LF-33.2,1%,1/16W,CHIA   I319 @SCM_LIB.SCM(SCH_1):PAGE13
   R98    2      B Q_RES_0402LF-0,5%,1/16W,CHIP,CA   I119 @SCM_LIB.SCM(SCH_1):PAGE46
  R414    2      B Q_RES_0402LF-4.7K,1%,1/16W,EMPB   I140 @SCM_LIB.SCM(SCH_1):PAGE46

SPI_BMC_TPM_MISO_R @SCM_LIB.SCM(SCH_1):SPI_BMC_TPM_MISO_R
   J10    4      4 SCONN11_9192031111LF-SCONN11_9A   I113 @SCM_LIB.SCM(SCH_1):PAGE46
   R98    1      A Q_RES_0402LF-0,5%,1/16W,CHIP,CA   I119 @SCM_LIB.SCM(SCH_1):PAGE46

SPI_BMC_TPM_MISO_R1 @SCM_LIB.SCM(SCH_1):SPI_BMC_TPM_MISO_R1
  R469    1      A Q_RES_0402LF-33.2,1%,1/16W,CHIA   I319 @SCM_LIB.SCM(SCH_1):PAGE13
    U5 AA11 GPIOZ5||SPI1MISO AST2600A3GP-AST2600A3-GP,SMLF,A   I363 @SCM_LIB.SCM(SCH_1):PAGE13

SPI_BMC_TPM_MOSI @SCM_LIB.SCM(SCH_1):SPI_BMC_TPM_MOSI
  R309    2      B Q_RES_0402LF-33.2,1%,1/16W,CHIA   I360 @SCM_LIB.SCM(SCH_1):PAGE13
   R97    2      B Q_RES_0402LF-0,5%,1/16W,CHIP,CA   I115 @SCM_LIB.SCM(SCH_1):PAGE46
    Q7    S      S 2N7002A7-2N7002A-7,SMLF,IC,BAMA   I243 @SCM_LIB.SCM(SCH_1):PAGE27

SPI_BMC_TPM_MOSI_R @SCM_LIB.SCM(SCH_1):SPI_BMC_TPM_MOSI_R
   J10    3      3 SCONN11_9192031111LF-SCONN11_9A   I113 @SCM_LIB.SCM(SCH_1):PAGE46
   R97    1      A Q_RES_0402LF-0,5%,1/16W,CHIP,CA   I115 @SCM_LIB.SCM(SCH_1):PAGE46

SPI_BMC_TPM_MOSI_R1 @SCM_LIB.SCM(SCH_1):SPI_BMC_TPM_MOSI_R1
  R309    1      A Q_RES_0402LF-33.2,1%,1/16W,CHIA   I360 @SCM_LIB.SCM(SCH_1):PAGE13
    U5 AC11 GPIOZ4||SPI1MOSI AST2600A3GP-AST2600A3-GP,SMLF,A   I363 @SCM_LIB.SCM(SCH_1):PAGE13

SPI_PCH_CLK_FLASH_R1 @SCM_LIB.SCM(SCH_1):SPI_PCH_CLK_FLASH_R1
  R481    2      B Q_RES_0402LF-33.2,1%,1/16W,CHIA    I24 @SCM_LIB.SCM(SCH_1):PAGE45
   J40   16    CLK SCONN16_ACASPI006P06-SCONN16_AA    I53 @SCM_LIB.SCM(SCH_1):PAGE45
   U17   16   SCLK MX25L51245GMI10G-MX25L51245GMIA    I54 @SCM_LIB.SCM(SCH_1):PAGE45

SPI_PCH_CS0_FLASH_R1_N @SCM_LIB.SCM(SCH_1):SPI_PCH_CS0_FLASH_R1_N
  R485    2      B Q_RES_0402LF-33.2,1%,1/16W,CHIA    I20 @SCM_LIB.SCM(SCH_1):PAGE45
  R490    2      B Q_RES_0402LF-4.7K,1%,1/16W,CHIA    I34 @SCM_LIB.SCM(SCH_1):PAGE45
  R487    1      A Q_RES_0402LF-4.7K,1%,1/16W,EMPA    I51 @SCM_LIB.SCM(SCH_1):PAGE45
   J40    7   CS_N SCONN16_ACASPI006P06-SCONN16_AA    I53 @SCM_LIB.SCM(SCH_1):PAGE45
   U17    7    CS# MX25L51245GMI10G-MX25L51245GMIA    I54 @SCM_LIB.SCM(SCH_1):PAGE45

SPI_PCH_IO0_FLASH_R1 @SCM_LIB.SCM(SCH_1):SPI_PCH_IO0_FLASH_R1
  R482    2      B Q_RES_0402LF-33.2,1%,1/16W,CHIA    I22 @SCM_LIB.SCM(SCH_1):PAGE45
   J40   15     DI SCONN16_ACASPI006P06-SCONN16_AA    I53 @SCM_LIB.SCM(SCH_1):PAGE45
   U17   15 SI_SIO0 MX25L51245GMI10G-MX25L51245GMIA    I54 @SCM_LIB.SCM(SCH_1):PAGE45

SPI_PCH_IO1_FLASH_R1 @SCM_LIB.SCM(SCH_1):SPI_PCH_IO1_FLASH_R1
  R484    2      B Q_RES_0402LF-33.2,1%,1/16W,CHIA    I21 @SCM_LIB.SCM(SCH_1):PAGE45
   J40    8     DO SCONN16_ACASPI006P06-SCONN16_AA    I53 @SCM_LIB.SCM(SCH_1):PAGE45
   U17    8 SO_SIO1 MX25L51245GMI10G-MX25L51245GMIA    I54 @SCM_LIB.SCM(SCH_1):PAGE45

SPI_PCH_IO2_FLASH_R1 @SCM_LIB.SCM(SCH_1):SPI_PCH_IO2_FLASH_R1
  R483    2      B Q_RES_0402LF-33.2,1%,1/16W,CHIA    I23 @SCM_LIB.SCM(SCH_1):PAGE45
  R488    2      B Q_RES_0402LF-4.7K,1%,1/16W,CHIA    I33 @SCM_LIB.SCM(SCH_1):PAGE45
   J40    9   WP_N SCONN16_ACASPI006P06-SCONN16_AA    I53 @SCM_LIB.SCM(SCH_1):PAGE45
   U17    9 WP#_SIO2 MX25L51245GMI10G-MX25L51245GMIA    I54 @SCM_LIB.SCM(SCH_1):PAGE45

SPI_PCH_IO3_FLASH_R1 @SCM_LIB.SCM(SCH_1):SPI_PCH_IO3_FLASH_R1
  R486    2      B Q_RES_0402LF-33.2,1%,1/16W,CHIA    I19 @SCM_LIB.SCM(SCH_1):PAGE45
  R492    2      B Q_RES_0402LF-4.7K,1%,1/16W,CHIA    I35 @SCM_LIB.SCM(SCH_1):PAGE45
   J40    1 HOLD_N SCONN16_ACASPI006P06-SCONN16_AA    I53 @SCM_LIB.SCM(SCH_1):PAGE45
   U17    1 NC_SIO3 MX25L51245GMI10G-MX25L51245GMIA    I54 @SCM_LIB.SCM(SCH_1):PAGE45

SPI_PCH_MUXED_CLK @SCM_LIB.SCM(SCH_1):SPI_PCH_MUXED_CLK
   U30    9     YC IDTQS3VH257PAG_SMLF-IDTQS3VH25A   I271 @SCM_LIB.SCM(SCH_1):PAGE44
  R481    1      A Q_RES_0402LF-33.2,1%,1/16W,CHIA    I24 @SCM_LIB.SCM(SCH_1):PAGE45

SPI_PCH_MUXED_CS0_N @SCM_LIB.SCM(SCH_1):SPI_PCH_MUXED_CS0_N
   U21    9     YC IDTQS3VH257PAG_SMLF-IDTQS3VH25A   I296 @SCM_LIB.SCM(SCH_1):PAGE44
  R485    1      A Q_RES_0402LF-33.2,1%,1/16W,CHIA    I20 @SCM_LIB.SCM(SCH_1):PAGE45

SPI_PCH_MUXED_IO0 @SCM_LIB.SCM(SCH_1):SPI_PCH_MUXED_IO0
   U30    4     YA IDTQS3VH257PAG_SMLF-IDTQS3VH25A   I271 @SCM_LIB.SCM(SCH_1):PAGE44
  R482    1      A Q_RES_0402LF-33.2,1%,1/16W,CHIA    I22 @SCM_LIB.SCM(SCH_1):PAGE45

SPI_PCH_MUXED_IO1 @SCM_LIB.SCM(SCH_1):SPI_PCH_MUXED_IO1
   U21    7     YB IDTQS3VH257PAG_SMLF-IDTQS3VH25A   I296 @SCM_LIB.SCM(SCH_1):PAGE44
  R484    1      A Q_RES_0402LF-33.2,1%,1/16W,CHIA    I21 @SCM_LIB.SCM(SCH_1):PAGE45

SPI_PCH_MUXED_IO2 @SCM_LIB.SCM(SCH_1):SPI_PCH_MUXED_IO2
   U21    4     YA IDTQS3VH257PAG_SMLF-IDTQS3VH25A   I296 @SCM_LIB.SCM(SCH_1):PAGE44
  R483    1      A Q_RES_0402LF-33.2,1%,1/16W,CHIA    I23 @SCM_LIB.SCM(SCH_1):PAGE45

SPI_PCH_MUXED_IO3 @SCM_LIB.SCM(SCH_1):SPI_PCH_MUXED_IO3
   U30    7     YB IDTQS3VH257PAG_SMLF-IDTQS3VH25A   I271 @SCM_LIB.SCM(SCH_1):PAGE44
  R486    1      A Q_RES_0402LF-33.2,1%,1/16W,CHIA    I19 @SCM_LIB.SCM(SCH_1):PAGE45

SPI_PCH_SECURE_CS0_N @SCM_LIB.SCM(SCH_1):SPI_PCH_SECURE_CS0_N
   U21   11   I_0C IDTQS3VH257PAG_SMLF-IDTQS3VH25A   I296 @SCM_LIB.SCM(SCH_1):PAGE44
  R864    2      B Q_RES_0402LF-33.2,1%,1/16W,CHIA   I342 @SCM_LIB.SCM(SCH_1):PAGE44

SPI_SYS_CS0_N @SCM_LIB.SCM(SCH_1):SPI_SYS_CS0_N
   GF1  B12 QSPI0_CS0_N FCONN168_ME1016810202011_SCM-FA   I553 @SCM_LIB.SCM(SCH_1):PAGE10
  R864    1      A Q_RES_0402LF-33.2,1%,1/16W,CHIA   I342 @SCM_LIB.SCM(SCH_1):PAGE44

SPI_SYS_HOLD_R_IO3 @SCM_LIB.SCM(SCH_1):SPI_SYS_HOLD_R_IO3
   GF1  B16 QSPI0_D3 FCONN168_ME1016810202011_SCM-FA   I553 @SCM_LIB.SCM(SCH_1):PAGE10
  R863    1      A Q_RES_0402LF-22,1%,1/16W,CHIP,A   I365 @SCM_LIB.SCM(SCH_1):PAGE44

SPI_SYS_MUX_CLK @SCM_LIB.SCM(SCH_1):SPI_SYS_MUX_CLK
   U30   11   I_0C IDTQS3VH257PAG_SMLF-IDTQS3VH25A   I271 @SCM_LIB.SCM(SCH_1):PAGE44
  R859    2      B Q_RES_0402LF-33.2,1%,1/16W,CHIA   I339 @SCM_LIB.SCM(SCH_1):PAGE44

SPI_SYS_MUX_HOLD_IO3 @SCM_LIB.SCM(SCH_1):SPI_SYS_MUX_HOLD_IO3
   U30    5   I_0B IDTQS3VH257PAG_SMLF-IDTQS3VH25A   I271 @SCM_LIB.SCM(SCH_1):PAGE44
  R863    2      B Q_RES_0402LF-22,1%,1/16W,CHIP,A   I365 @SCM_LIB.SCM(SCH_1):PAGE44

SPI_SYS_MUX_MISO @SCM_LIB.SCM(SCH_1):SPI_SYS_MUX_MISO
   U21    5   I_0B IDTQS3VH257PAG_SMLF-IDTQS3VH25A   I296 @SCM_LIB.SCM(SCH_1):PAGE44
  R861    2      B Q_RES_0402LF-22,1%,1/16W,CHIP,A   I363 @SCM_LIB.SCM(SCH_1):PAGE44

SPI_SYS_MUX_MOSI @SCM_LIB.SCM(SCH_1):SPI_SYS_MUX_MOSI
   U30    2   I_0A IDTQS3VH257PAG_SMLF-IDTQS3VH25A   I271 @SCM_LIB.SCM(SCH_1):PAGE44
  R860    2      B Q_RES_0402LF-22,1%,1/16W,CHIP,A   I362 @SCM_LIB.SCM(SCH_1):PAGE44

SPI_SYS_MUX_WP_IO2 @SCM_LIB.SCM(SCH_1):SPI_SYS_MUX_WP_IO2
   U21    2   I_0A IDTQS3VH257PAG_SMLF-IDTQS3VH25A   I296 @SCM_LIB.SCM(SCH_1):PAGE44
  R862    2      B Q_RES_0402LF-22,1%,1/16W,CHIP,A   I364 @SCM_LIB.SCM(SCH_1):PAGE44

SPI_SYS_R1_CLK @SCM_LIB.SCM(SCH_1):SPI_SYS_R1_CLK
    J5    1      1 SCONN11_9192031111LF-SCONN11_9A    I56 @SCM_LIB.SCM(SCH_1):PAGE46
  R501    1      A Q_RES_0402LF-33.2,1%,1/16W,CHIA    I58 @SCM_LIB.SCM(SCH_1):PAGE46

SPI_SYS_R1_MISO @SCM_LIB.SCM(SCH_1):SPI_SYS_R1_MISO
    J5    4      4 SCONN11_9192031111LF-SCONN11_9A    I56 @SCM_LIB.SCM(SCH_1):PAGE46
  R499    2      B Q_RES_0402LF-22,1%,1/16W,CHIP,A   I136 @SCM_LIB.SCM(SCH_1):PAGE46

SPI_SYS_R1_MOSI @SCM_LIB.SCM(SCH_1):SPI_SYS_R1_MOSI
    J5    3      3 SCONN11_9192031111LF-SCONN11_9A    I56 @SCM_LIB.SCM(SCH_1):PAGE46
  R498    2      B Q_RES_0402LF-22,1%,1/16W,CHIP,A   I137 @SCM_LIB.SCM(SCH_1):PAGE46

SPI_SYS_R_CLK @SCM_LIB.SCM(SCH_1):SPI_SYS_R_CLK
   GF1  B11 QSPI0_CLK FCONN168_ME1016810202011_SCM-FA   I553 @SCM_LIB.SCM(SCH_1):PAGE10
  R859    1      A Q_RES_0402LF-33.2,1%,1/16W,CHIA   I339 @SCM_LIB.SCM(SCH_1):PAGE44
  R501    2      B Q_RES_0402LF-33.2,1%,1/16W,CHIA    I58 @SCM_LIB.SCM(SCH_1):PAGE46

SPI_SYS_R_MISO @SCM_LIB.SCM(SCH_1):SPI_SYS_R_MISO
   GF1  B14 QSPI0_D1 FCONN168_ME1016810202011_SCM-FA   I553 @SCM_LIB.SCM(SCH_1):PAGE10
  R861    1      A Q_RES_0402LF-22,1%,1/16W,CHIP,A   I363 @SCM_LIB.SCM(SCH_1):PAGE44
  R499    1      A Q_RES_0402LF-22,1%,1/16W,CHIP,A   I136 @SCM_LIB.SCM(SCH_1):PAGE46

SPI_SYS_R_MOSI @SCM_LIB.SCM(SCH_1):SPI_SYS_R_MOSI
   GF1  B13 QSPI0_D0 FCONN168_ME1016810202011_SCM-FA   I553 @SCM_LIB.SCM(SCH_1):PAGE10
  R860    1      A Q_RES_0402LF-22,1%,1/16W,CHIP,A   I362 @SCM_LIB.SCM(SCH_1):PAGE44
  R498    1      A Q_RES_0402LF-22,1%,1/16W,CHIP,A   I137 @SCM_LIB.SCM(SCH_1):PAGE46

SPI_SYS_WP_R_IO2 @SCM_LIB.SCM(SCH_1):SPI_SYS_WP_R_IO2
   GF1  B15 QSPI0_D2 FCONN168_ME1016810202011_SCM-FA   I553 @SCM_LIB.SCM(SCH_1):PAGE10
  R862    1      A Q_RES_0402LF-22,1%,1/16W,CHIP,A   I364 @SCM_LIB.SCM(SCH_1):PAGE44

SPI_TPM_CS_N @SCM_LIB.SCM(SCH_1):SPI_TPM_CS_N
   GF1 OB12 SPI0_CS_N FCONN168_ME1016810202011_SCM-FA   I553 @SCM_LIB.SCM(SCH_1):PAGE10
  R594    1      A Q_RES_0402LF-33.2,1%,1/16W,CHIA   I360 @SCM_LIB.SCM(SCH_1):PAGE44

SPI_TPM_CS_N_R @SCM_LIB.SCM(SCH_1):SPI_TPM_CS_N_R
    J5    5      5 SCONN11_9192031111LF-SCONN11_9A    I56 @SCM_LIB.SCM(SCH_1):PAGE46
  R500    1      A Q_RES_0402LF-0,5%,1/16W,CHIP,CA    I65 @SCM_LIB.SCM(SCH_1):PAGE46

SPI_TPM_CS_R_N @SCM_LIB.SCM(SCH_1):SPI_TPM_CS_R_N
  R594    2      B Q_RES_0402LF-33.2,1%,1/16W,CHIA   I360 @SCM_LIB.SCM(SCH_1):PAGE44
  R500    2      B Q_RES_0402LF-0,5%,1/16W,CHIP,CA    I65 @SCM_LIB.SCM(SCH_1):PAGE46

SW_P1V0_AUX_BST @SCM_LIB.SCM(SCH_1):SW_P1V0_AUX_BST
  PU42    9    BST NB695GDZ-NB695GD-Z,SMLF,IC,AL0A    I15 @SCM_LIB.SCM(SCH_1):PAGE56
 PC264    1      A Q_CAP_0402-0.22UF,16V,10%,X7R,A    I19 @SCM_LIB.SCM(SCH_1):PAGE56

SW_P1V0_AUX_FLT @SCM_LIB.SCM(SCH_1):SW_P1V0_AUX_FLT
  PU42    1    VIN NB695GDZ-NB695GD-Z,SMLF,IC,AL0A    I15 @SCM_LIB.SCM(SCH_1):PAGE56
 PC263    1      A Q_CAP_0402-0.1UF,25V,10%,X7R,CA    I16 @SCM_LIB.SCM(SCH_1):PAGE56
  PL32    2      2 Q_INDUCTOR_SMLF-BLM18SN220TN1DA    I34 @SCM_LIB.SCM(SCH_1):PAGE56
 PC262    1      A Q_CAP_C0805-10UF,25V,10%,X6S,CA    I43 @SCM_LIB.SCM(SCH_1):PAGE56
 PC261    1      A Q_CAP_C0805-10UF,25V,10%,X6S,CA    I44 @SCM_LIB.SCM(SCH_1):PAGE56

SW_P1V0_AUX_SW @SCM_LIB.SCM(SCH_1):SW_P1V0_AUX_SW
  PU42    8     SW NB695GDZ-NB695GD-Z,SMLF,IC,AL0A    I15 @SCM_LIB.SCM(SCH_1):PAGE56
 PC264    2      B Q_CAP_0402-0.22UF,16V,10%,X7R,A    I19 @SCM_LIB.SCM(SCH_1):PAGE56
  PL33    1      1 Q_INDUCTOR_SMLF-1UH,IND,CV-10BA    I37 @SCM_LIB.SCM(SCH_1):PAGE56

SW_P1V2_AUX_BST @SCM_LIB.SCM(SCH_1):SW_P1V2_AUX_BST
  PU41    9    BST NB695GDZ-NB695GD-Z,SMLF,IC,AL0A    I15 @SCM_LIB.SCM(SCH_1):PAGE55
 PC254    1      A Q_CAP_0402-0.22UF,16V,10%,X7R,A    I19 @SCM_LIB.SCM(SCH_1):PAGE55

SW_P1V2_AUX_FLT @SCM_LIB.SCM(SCH_1):SW_P1V2_AUX_FLT
  PU41    1    VIN NB695GDZ-NB695GD-Z,SMLF,IC,AL0A    I15 @SCM_LIB.SCM(SCH_1):PAGE55
 PC253    1      A Q_CAP_0402-0.1UF,25V,10%,X7R,CA    I16 @SCM_LIB.SCM(SCH_1):PAGE55
  PL29    2      2 Q_INDUCTOR_SMLF-BLM18SN220TN1DA    I31 @SCM_LIB.SCM(SCH_1):PAGE55
 PC252    1      A Q_CAP_C0805-10UF,25V,10%,X6S,CA    I42 @SCM_LIB.SCM(SCH_1):PAGE55
 PC251    1      A Q_CAP_C0805-10UF,25V,10%,X6S,CA    I43 @SCM_LIB.SCM(SCH_1):PAGE55

SW_P1V2_AUX_SW @SCM_LIB.SCM(SCH_1):SW_P1V2_AUX_SW
  PU41    8     SW NB695GDZ-NB695GD-Z,SMLF,IC,AL0A    I15 @SCM_LIB.SCM(SCH_1):PAGE55
 PC254    2      B Q_CAP_0402-0.22UF,16V,10%,X7R,A    I19 @SCM_LIB.SCM(SCH_1):PAGE55
  PL31    1      1 Q_INDUCTOR_SMLF-1UH,IND,CV-10BA    I21 @SCM_LIB.SCM(SCH_1):PAGE55

SW_P3V3_AUX_BST @SCM_LIB.SCM(SCH_1):SW_P3V3_AUX_BST
 PC224    1      A Q_CAP_0402-0.22UF,16V,10%,X7R,A    I15 @SCM_LIB.SCM(SCH_1):PAGE52
  R415    2      B Q_RES_0402LF-2.2,1%,1/16W,CHIPA   I146 @SCM_LIB.SCM(SCH_1):PAGE52

SW_P3V3_AUX_BST_R @SCM_LIB.SCM(SCH_1):SW_P3V3_AUX_BST_R
   PU1   10    BST MPQ8626GDZ-MPQ8626GD-Z,SMLF,ICA    I82 @SCM_LIB.SCM(SCH_1):PAGE52
  R415    1      A Q_RES_0402LF-2.2,1%,1/16W,CHIPA   I146 @SCM_LIB.SCM(SCH_1):PAGE52

SW_P3V3_AUX_FLT @SCM_LIB.SCM(SCH_1):SW_P3V3_AUX_FLT
 PC223    1      A Q_CAP_0402-0.1UF,25V,10%,X7R,CA    I11 @SCM_LIB.SCM(SCH_1):PAGE52
  PL19    2      2 Q_INDUCTOR_SMLF-BLM18SN220TN1DA    I32 @SCM_LIB.SCM(SCH_1):PAGE52
 PC219    1      A Q_CAP_C0805-22UF,16V,20%,X6S,CA    I80 @SCM_LIB.SCM(SCH_1):PAGE52
 PC218    1      A Q_CAP_C0805-22UF,16V,20%,X6S,CA    I81 @SCM_LIB.SCM(SCH_1):PAGE52
   PU1    3    VIN MPQ8626GDZ-MPQ8626GD-Z,SMLF,ICA    I82 @SCM_LIB.SCM(SCH_1):PAGE52
  C265    1      A Q_CAP_C0805-22UF,16V,20%,X6S,CA   I102 @SCM_LIB.SCM(SCH_1):PAGE52

SW_P3V3_AUX_SW @SCM_LIB.SCM(SCH_1):SW_P3V3_AUX_SW
 PC224    2      B Q_CAP_0402-0.22UF,16V,10%,X7R,A    I15 @SCM_LIB.SCM(SCH_1):PAGE52
   PU1    2    SW1 MPQ8626GDZ-MPQ8626GD-Z,SMLF,ICA    I82 @SCM_LIB.SCM(SCH_1):PAGE52
   PU1   11    SW2 MPQ8626GDZ-MPQ8626GD-Z,SMLF,ICA    I82 @SCM_LIB.SCM(SCH_1):PAGE52
  PL35    1      1 Q_INDUCTOR_SMLF-3.3UH/6A,IND,CA    I92 @SCM_LIB.SCM(SCH_1):PAGE52

SW_P5V_AUX_BST @SCM_LIB.SCM(SCH_1):SW_P5V_AUX_BST
 PC216    1      A Q_CAP_0402-0.22UF,16V,10%,X7R,A    I23 @SCM_LIB.SCM(SCH_1):PAGE51
  PU38    1    BST MPQ8633AGLEC807Z-MPQ8633AGLE-CA    I42 @SCM_LIB.SCM(SCH_1):PAGE51

SW_P5V_AUX_FLT @SCM_LIB.SCM(SCH_1):SW_P5V_AUX_FLT
   PL4    2      2 Q_INDUCTOR_SMLF-BLM18SN220TN1DA    I39 @SCM_LIB.SCM(SCH_1):PAGE51
  PU38   10   VIN1 MPQ8633AGLEC807Z-MPQ8633AGLE-CA    I42 @SCM_LIB.SCM(SCH_1):PAGE51
  PU38   21   VIN2 MPQ8633AGLEC807Z-MPQ8633AGLE-CA    I42 @SCM_LIB.SCM(SCH_1):PAGE51
 PC210    1      A Q_CAP_0402-0.1UF,25V,10%,X7R,CA    I45 @SCM_LIB.SCM(SCH_1):PAGE51
 PC206    1      A Q_CAP_C0805-22UF,16V,20%,X6S,CA    I47 @SCM_LIB.SCM(SCH_1):PAGE51
 PC207    1      A Q_CAP_C0805-22UF,16V,20%,X6S,CA    I48 @SCM_LIB.SCM(SCH_1):PAGE51

SW_P5V_AUX_SW @SCM_LIB.SCM(SCH_1):SW_P5V_AUX_SW
 PC216    2      B Q_CAP_0402-0.22UF,16V,10%,X7R,A    I23 @SCM_LIB.SCM(SCH_1):PAGE51
  PL34    1      1 Q_INDUCTOR_SMLF-4.7UH,IND,CV-4A    I28 @SCM_LIB.SCM(SCH_1):PAGE51
  PU38   20     SW MPQ8633AGLEC807Z-MPQ8633AGLE-CA    I42 @SCM_LIB.SCM(SCH_1):PAGE51

SYS_BMC_PWRBTN_R1_N @SCM_LIB.SCM(SCH_1):SYS_BMC_PWRBTN_R1_N
    U5  W24 GPIOP1||PWM9||THRUOUT0 AST2600A3GP-AST2600A3-GP,SMLF,A   I350 @SCM_LIB.SCM(SCH_1):PAGE15
  R804    1      A Q_RES_0402LF-0,5%,1/16W,CHIP,CA   I367 @SCM_LIB.SCM(SCH_1):PAGE15
  R462    2      B Q_RES_0402LF-4.7K,1%,1/16W,CHIA   I391 @SCM_LIB.SCM(SCH_1):PAGE15

SYS_BMC_PWRBTN_R_N @SCM_LIB.SCM(SCH_1):SYS_BMC_PWRBTN_R_N
  R804    2      B Q_RES_0402LF-0,5%,1/16W,CHIP,CA   I367 @SCM_LIB.SCM(SCH_1):PAGE15
   U15    1      B 74LVC1G08GW_SM-74LVC1G08GW,IC,A   I393 @SCM_LIB.SCM(SCH_1):PAGE15

SYS_PWRBTN_N @SCM_LIB.SCM(SCH_1):SYS_PWRBTN_N
   GF1  A47 SYS_PWRBTN_N FCONN168_ME1016810202011_SCM-FA   I553 @SCM_LIB.SCM(SCH_1):PAGE10
   R44    2      B Q_RES_0402LF-4.7K,1%,1/16W,EMPA   I175 @SCM_LIB.SCM(SCH_1):PAGE11
   U15    4      Y 74LVC1G08GW_SM-74LVC1G08GW,IC,A   I393 @SCM_LIB.SCM(SCH_1):PAGE15

TDR_DIFF_100_BOT_DN @SCM_LIB.SCM(SCH_1):TDR_DIFF_100_BOT_DN
   X18    4     S2 TP_TDR_4P_FTS_TH-TP_TDR_4P_DIPA    I42 @SCM_LIB.SCM(SCH_1):PAGE60
   X24    1     S1 TP_TDR_4P_FTS_TH-TP_TDR_4P_DIPA    I43 @SCM_LIB.SCM(SCH_1):PAGE60

TDR_DIFF_100_BOT_DP @SCM_LIB.SCM(SCH_1):TDR_DIFF_100_BOT_DP
   X18    1     S1 TP_TDR_4P_FTS_TH-TP_TDR_4P_DIPA    I42 @SCM_LIB.SCM(SCH_1):PAGE60
   X24    4     S2 TP_TDR_4P_FTS_TH-TP_TDR_4P_DIPA    I43 @SCM_LIB.SCM(SCH_1):PAGE60

TDR_DIFF_100_IN1_DN @SCM_LIB.SCM(SCH_1):TDR_DIFF_100_IN1_DN
   X14    4     S2 TP_TDR_4P_FTS_TH-TP_TDR_4P_DIPA    I58 @SCM_LIB.SCM(SCH_1):PAGE60
   X20    1     S1 TP_TDR_4P_FTS_TH-TP_TDR_4P_DIPA    I59 @SCM_LIB.SCM(SCH_1):PAGE60

TDR_DIFF_100_IN1_DP @SCM_LIB.SCM(SCH_1):TDR_DIFF_100_IN1_DP
   X14    1     S1 TP_TDR_4P_FTS_TH-TP_TDR_4P_DIPA    I58 @SCM_LIB.SCM(SCH_1):PAGE60
   X20    4     S2 TP_TDR_4P_FTS_TH-TP_TDR_4P_DIPA    I59 @SCM_LIB.SCM(SCH_1):PAGE60

TDR_DIFF_100_IN4_DN @SCM_LIB.SCM(SCH_1):TDR_DIFF_100_IN4_DN
   X17    4     S2 TP_TDR_4P_FTS_TH-TP_TDR_4P_DIPA    I46 @SCM_LIB.SCM(SCH_1):PAGE60
   X23    1     S1 TP_TDR_4P_FTS_TH-TP_TDR_4P_DIPA    I47 @SCM_LIB.SCM(SCH_1):PAGE60

TDR_DIFF_100_IN4_DP @SCM_LIB.SCM(SCH_1):TDR_DIFF_100_IN4_DP
   X17    1     S1 TP_TDR_4P_FTS_TH-TP_TDR_4P_DIPA    I46 @SCM_LIB.SCM(SCH_1):PAGE60
   X23    4     S2 TP_TDR_4P_FTS_TH-TP_TDR_4P_DIPA    I47 @SCM_LIB.SCM(SCH_1):PAGE60

TDR_DIFF_100_TOP_DN @SCM_LIB.SCM(SCH_1):TDR_DIFF_100_TOP_DN
   X19    1     S1 TP_TDR_4P_FTS_TH-TP_TDR_4P_DIPA    I38 @SCM_LIB.SCM(SCH_1):PAGE60
   X13    4     S2 TP_TDR_4P_FTS_TH-TP_TDR_4P_DIPA    I39 @SCM_LIB.SCM(SCH_1):PAGE60

TDR_DIFF_100_TOP_DP @SCM_LIB.SCM(SCH_1):TDR_DIFF_100_TOP_DP
   X19    4     S2 TP_TDR_4P_FTS_TH-TP_TDR_4P_DIPA    I38 @SCM_LIB.SCM(SCH_1):PAGE60
   X13    1     S1 TP_TDR_4P_FTS_TH-TP_TDR_4P_DIPA    I39 @SCM_LIB.SCM(SCH_1):PAGE60

TDR_DIFF_85_BOT_DN @SCM_LIB.SCM(SCH_1):TDR_DIFF_85_BOT_DN
   X12    1     S1 TP_TDR_4P_FTS_TH-TP_TDR_4P_DIPA    I18 @SCM_LIB.SCM(SCH_1):PAGE60
    X6    4     S2 TP_TDR_4P_FTS_TH-TP_TDR_4P_DIPA    I19 @SCM_LIB.SCM(SCH_1):PAGE60

TDR_DIFF_85_BOT_DP @SCM_LIB.SCM(SCH_1):TDR_DIFF_85_BOT_DP
   X12    4     S2 TP_TDR_4P_FTS_TH-TP_TDR_4P_DIPA    I18 @SCM_LIB.SCM(SCH_1):PAGE60
    X6    1     S1 TP_TDR_4P_FTS_TH-TP_TDR_4P_DIPA    I19 @SCM_LIB.SCM(SCH_1):PAGE60

TDR_DIFF_85_IN1_DN @SCM_LIB.SCM(SCH_1):TDR_DIFF_85_IN1_DN
    X8    1     S1 TP_TDR_4P_FTS_TH-TP_TDR_4P_DIPA    I34 @SCM_LIB.SCM(SCH_1):PAGE60
    X2    4     S2 TP_TDR_4P_FTS_TH-TP_TDR_4P_DIPA    I35 @SCM_LIB.SCM(SCH_1):PAGE60

TDR_DIFF_85_IN1_DP @SCM_LIB.SCM(SCH_1):TDR_DIFF_85_IN1_DP
    X8    4     S2 TP_TDR_4P_FTS_TH-TP_TDR_4P_DIPA    I34 @SCM_LIB.SCM(SCH_1):PAGE60
    X2    1     S1 TP_TDR_4P_FTS_TH-TP_TDR_4P_DIPA    I35 @SCM_LIB.SCM(SCH_1):PAGE60

TDR_DIFF_85_IN4_DN @SCM_LIB.SCM(SCH_1):TDR_DIFF_85_IN4_DN
   X11    1     S1 TP_TDR_4P_FTS_TH-TP_TDR_4P_DIPA    I22 @SCM_LIB.SCM(SCH_1):PAGE60
    X5    4     S2 TP_TDR_4P_FTS_TH-TP_TDR_4P_DIPA    I23 @SCM_LIB.SCM(SCH_1):PAGE60

TDR_DIFF_85_IN4_DP @SCM_LIB.SCM(SCH_1):TDR_DIFF_85_IN4_DP
   X11    4     S2 TP_TDR_4P_FTS_TH-TP_TDR_4P_DIPA    I22 @SCM_LIB.SCM(SCH_1):PAGE60
    X5    1     S1 TP_TDR_4P_FTS_TH-TP_TDR_4P_DIPA    I23 @SCM_LIB.SCM(SCH_1):PAGE60

TDR_DIFF_85_TOP_DN @SCM_LIB.SCM(SCH_1):TDR_DIFF_85_TOP_DN
    X1    4     S2 TP_TDR_4P_FTS_TH-TP_TDR_4P_DIPA    I13 @SCM_LIB.SCM(SCH_1):PAGE60
    X7    1     S1 TP_TDR_4P_FTS_TH-TP_TDR_4P_DIPA    I14 @SCM_LIB.SCM(SCH_1):PAGE60

TDR_DIFF_85_TOP_DP @SCM_LIB.SCM(SCH_1):TDR_DIFF_85_TOP_DP
    X1    1     S1 TP_TDR_4P_FTS_TH-TP_TDR_4P_DIPA    I13 @SCM_LIB.SCM(SCH_1):PAGE60
    X7    4     S2 TP_TDR_4P_FTS_TH-TP_TDR_4P_DIPA    I14 @SCM_LIB.SCM(SCH_1):PAGE60

TDR_SE_50_OHM_BOT @SCM_LIB.SCM(SCH_1):TDR_SE_50_OHM_BOT
   DB6    2    IO1 TDR_3P_TH2-EMPTY,N_A     I3 @SCM_LIB.SCM(SCH_1):PAGE60
   DB6    3    IO2 TDR_3P_TH2-EMPTY,N_A     I3 @SCM_LIB.SCM(SCH_1):PAGE60

TDR_SE_50_OHM_IN1 @SCM_LIB.SCM(SCH_1):TDR_SE_50_OHM_IN1
   DB2    2    IO1 TDR_3P_TH2-EMPTY,N_A    I11 @SCM_LIB.SCM(SCH_1):PAGE60
   DB2    3    IO2 TDR_3P_TH2-EMPTY,N_A    I11 @SCM_LIB.SCM(SCH_1):PAGE60

TDR_SE_50_OHM_IN2 @SCM_LIB.SCM(SCH_1):TDR_SE_50_OHM_IN2
   DB3    2    IO1 TDR_3P_TH2-EMPTY,N_A     I9 @SCM_LIB.SCM(SCH_1):PAGE60
   DB3    3    IO2 TDR_3P_TH2-EMPTY,N_A     I9 @SCM_LIB.SCM(SCH_1):PAGE60

TDR_SE_50_OHM_IN3 @SCM_LIB.SCM(SCH_1):TDR_SE_50_OHM_IN3
   DB4    2    IO1 TDR_3P_TH2-EMPTY,N_A     I7 @SCM_LIB.SCM(SCH_1):PAGE60
   DB4    3    IO2 TDR_3P_TH2-EMPTY,N_A     I7 @SCM_LIB.SCM(SCH_1):PAGE60

TDR_SE_50_OHM_IN4 @SCM_LIB.SCM(SCH_1):TDR_SE_50_OHM_IN4
   DB5    2    IO1 TDR_3P_TH2-EMPTY,N_A     I5 @SCM_LIB.SCM(SCH_1):PAGE60
   DB5    3    IO2 TDR_3P_TH2-EMPTY,N_A     I5 @SCM_LIB.SCM(SCH_1):PAGE60

TDR_SE_50_OHM_TOP @SCM_LIB.SCM(SCH_1):TDR_SE_50_OHM_TOP
   DB1    2    IO1 TDR_3P_TH2-EMPTY,N_A     I1 @SCM_LIB.SCM(SCH_1):PAGE60
   DB1    3    IO2 TDR_3P_TH2-EMPTY,N_A     I1 @SCM_LIB.SCM(SCH_1):PAGE60

TMC75_A0 @SCM_LIB.SCM(SCH_1):TMC75_A0
  R417    1      A Q_RES_0402LF-1K,1%,1/16W,EMPTYA    I39 @SCM_LIB.SCM(SCH_1):PAGE26
  R416    2      B Q_RES_0402LF-4.7K,1%,1/16W,CHIA    I41 @SCM_LIB.SCM(SCH_1):PAGE26
   J14    3      3 CONN8_TSW10407FD-CONN8_TSW-104A    I71 @SCM_LIB.SCM(SCH_1):PAGE26

TMC75_A1 @SCM_LIB.SCM(SCH_1):TMC75_A1
   R53    1      A Q_RES_0402LF-1K,1%,1/16W,EMPTYA    I66 @SCM_LIB.SCM(SCH_1):PAGE26
   R52    2      B Q_RES_0402LF-4.7K,1%,1/16W,CHIA    I67 @SCM_LIB.SCM(SCH_1):PAGE26
   J14    5      5 CONN8_TSW10407FD-CONN8_TSW-104A    I71 @SCM_LIB.SCM(SCH_1):PAGE26

TMC75_A2 @SCM_LIB.SCM(SCH_1):TMC75_A2
  R419    1      A Q_RES_0402LF-1K,1%,1/16W,CHIP,A    I37 @SCM_LIB.SCM(SCH_1):PAGE26
  R418    2      B Q_RES_0402LF-4.7K,1%,1/16W,EMPA    I40 @SCM_LIB.SCM(SCH_1):PAGE26
   J14    7      7 CONN8_TSW10407FD-CONN8_TSW-104A    I71 @SCM_LIB.SCM(SCH_1):PAGE26

TP4 @SCM_LIB.SCM(SCH_1):TP4
   U35    5    IO4 DT1240E04LP7-DT1240E-04LP-7,SMA   I155 @SCM_LIB.SCM(SCH_1):PAGE23

TP_BIOS_MUX0_PIN12 @SCM_LIB.SCM(SCH_1):TP_BIOS_MUX0_PIN12
   U30   12     YD IDTQS3VH257PAG_SMLF-IDTQS3VH25A   I271 @SCM_LIB.SCM(SCH_1):PAGE44

TP_BIOS_MUX0_PIN13 @SCM_LIB.SCM(SCH_1):TP_BIOS_MUX0_PIN13
   U30   13   I_1D IDTQS3VH257PAG_SMLF-IDTQS3VH25A   I271 @SCM_LIB.SCM(SCH_1):PAGE44

TP_BIOS_MUX0_PIN14 @SCM_LIB.SCM(SCH_1):TP_BIOS_MUX0_PIN14
   U30   14   I_0D IDTQS3VH257PAG_SMLF-IDTQS3VH25A   I271 @SCM_LIB.SCM(SCH_1):PAGE44

TP_BIOS_MUX1_PIN12 @SCM_LIB.SCM(SCH_1):TP_BIOS_MUX1_PIN12
   U21   12     YD IDTQS3VH257PAG_SMLF-IDTQS3VH25A   I296 @SCM_LIB.SCM(SCH_1):PAGE44

TP_BIOS_MUX1_PIN13 @SCM_LIB.SCM(SCH_1):TP_BIOS_MUX1_PIN13
   U21   13   I_1D IDTQS3VH257PAG_SMLF-IDTQS3VH25A   I296 @SCM_LIB.SCM(SCH_1):PAGE44

TP_BIOS_MUX1_PIN14 @SCM_LIB.SCM(SCH_1):TP_BIOS_MUX1_PIN14
   U21   14   I_0D IDTQS3VH257PAG_SMLF-IDTQS3VH25A   I296 @SCM_LIB.SCM(SCH_1):PAGE44

TP_BMC_SPICS0_N @SCM_LIB.SCM(SCH_1):TP_BMC_SPICS0_N
    U5 AD13 SPI1CS0# AST2600A3GP-AST2600A3-GP,SMLF,A   I363 @SCM_LIB.SCM(SCH_1):PAGE13

TP_BMC_SPICS2_N @SCM_LIB.SCM(SCH_1):TP_BMC_SPICS2_N
    U5 AC13 FWSPICS2# AST2600A3GP-AST2600A3-GP,SMLF,A   I363 @SCM_LIB.SCM(SCH_1):PAGE13

TP_ESD_VGA_P4 @SCM_LIB.SCM(SCH_1):TP_ESD_VGA_P4
   U35    6    NC1 DT1240E04LP7-DT1240E-04LP-7,SMA   I155 @SCM_LIB.SCM(SCH_1):PAGE23

TP_GF1_B44 @SCM_LIB.SCM(SCH_1):TP_GF1_B44
   GF1  B44 QSPI1_CS0_N FCONN168_ME1016810202011_SCM-FA   I553 @SCM_LIB.SCM(SCH_1):PAGE10

TP_GF_A45 @SCM_LIB.SCM(SCH_1):TP_GF_A45
   GF1  A45 HPM_STBY_EN FCONN168_ME1016810202011_SCM-FA   I553 @SCM_LIB.SCM(SCH_1):PAGE10

TP_GF_A62 @SCM_LIB.SCM(SCH_1):TP_GF_A62
   GF1  A62 PCIE_HPM_RXP_1 FCONN168_ME1016810202011_SCM-FA   I553 @SCM_LIB.SCM(SCH_1):PAGE10

TP_GF_A63 @SCM_LIB.SCM(SCH_1):TP_GF_A63
   GF1  A63 PCIE_HPM_RXN_1 FCONN168_ME1016810202011_SCM-FA   I553 @SCM_LIB.SCM(SCH_1):PAGE10

TP_GF_B62 @SCM_LIB.SCM(SCH_1):TP_GF_B62
   GF1  B62 PCIE_HPM_TXP_1 FCONN168_ME1016810202011_SCM-FA   I553 @SCM_LIB.SCM(SCH_1):PAGE10

TP_GF_B63 @SCM_LIB.SCM(SCH_1):TP_GF_B63
   GF1  B63 PCIE_HPM_TXN_1 FCONN168_ME1016810202011_SCM-FA   I553 @SCM_LIB.SCM(SCH_1):PAGE10

TP_ID_BUF @SCM_LIB.SCM(SCH_1):TP_ID_BUF
   U32    1     NC 74LVC1G17GW-74LVC1G17GW,SMLF,IA    I49 @SCM_LIB.SCM(SCH_1):PAGE50

TP_J40_11 @SCM_LIB.SCM(SCH_1):TP_J40_11
   J40   11    NC4 SCONN16_ACASPI006P06-SCONN16_AA    I53 @SCM_LIB.SCM(SCH_1):PAGE45
   U17   11   DNU3 MX25L51245GMI10G-MX25L51245GMIA    I54 @SCM_LIB.SCM(SCH_1):PAGE45

TP_J40_12 @SCM_LIB.SCM(SCH_1):TP_J40_12
   J40   12    NC6 SCONN16_ACASPI006P06-SCONN16_AA    I53 @SCM_LIB.SCM(SCH_1):PAGE45
   U17   12   DNU4 MX25L51245GMI10G-MX25L51245GMIA    I54 @SCM_LIB.SCM(SCH_1):PAGE45

TP_J40_13 @SCM_LIB.SCM(SCH_1):TP_J40_13
   J40   13    NC7 SCONN16_ACASPI006P06-SCONN16_AA    I53 @SCM_LIB.SCM(SCH_1):PAGE45
   U17   13    NC2 MX25L51245GMI10G-MX25L51245GMIA    I54 @SCM_LIB.SCM(SCH_1):PAGE45

TP_J40_14 @SCM_LIB.SCM(SCH_1):TP_J40_14
   J40   14    NC8 SCONN16_ACASPI006P06-SCONN16_AA    I53 @SCM_LIB.SCM(SCH_1):PAGE45
   U17   14    NC3 MX25L51245GMI10G-MX25L51245GMIA    I54 @SCM_LIB.SCM(SCH_1):PAGE45

TP_J40_4 @SCM_LIB.SCM(SCH_1):TP_J40_4
   J40    4    NC1 SCONN16_ACASPI006P06-SCONN16_AA    I53 @SCM_LIB.SCM(SCH_1):PAGE45
   U17    4    NC1 MX25L51245GMI10G-MX25L51245GMIA    I54 @SCM_LIB.SCM(SCH_1):PAGE45

TP_J40_5 @SCM_LIB.SCM(SCH_1):TP_J40_5
   J40    5    NC2 SCONN16_ACASPI006P06-SCONN16_AA    I53 @SCM_LIB.SCM(SCH_1):PAGE45
   U17    5   DNU1 MX25L51245GMI10G-MX25L51245GMIA    I54 @SCM_LIB.SCM(SCH_1):PAGE45

TP_J40_6 @SCM_LIB.SCM(SCH_1):TP_J40_6
   J40    6    NC3 SCONN16_ACASPI006P06-SCONN16_AA    I53 @SCM_LIB.SCM(SCH_1):PAGE45
   U17    6   DNU2 MX25L51245GMI10G-MX25L51245GMIA    I54 @SCM_LIB.SCM(SCH_1):PAGE45

TP_PLD_19D @SCM_LIB.SCM(SCH_1):TP_PLD_19D
   U25  E11  PT19D LCMXO3LF2100C5BG256C-LCMXO3LF-A     I1 @SCM_LIB.SCM(SCH_1):PAGE34

TP_PLD_C13 @SCM_LIB.SCM(SCH_1):TP_PLD_C13
   U25   P5   PB5B LCMXO3LF2100C5BG256C-LCMXO3LF-A     I1 @SCM_LIB.SCM(SCH_1):PAGE36

TP_PLD_CONN_P5 @SCM_LIB.SCM(SCH_1):TP_PLD_CONN_P5
    J7    5      5 CONN8_210HP1080BR1-CONN8_210-HA   I132 @SCM_LIB.SCM(SCH_1):PAGE32

TP_PLD_L3 @SCM_LIB.SCM(SCH_1):TP_PLD_L3
   U25  F12   PR4C LCMXO3LF2100C5BG256C-LCMXO3LF-A     I1 @SCM_LIB.SCM(SCH_1):PAGE35

TP_PWR_BUF @SCM_LIB.SCM(SCH_1):TP_PWR_BUF
   U31    1     NC 74LVC1G07GW-74LVC1G07GW,SMLF,IA   I151 @SCM_LIB.SCM(SCH_1):PAGE50

TP_U14_FLAG_N @SCM_LIB.SCM(SCH_1):TP_U14_FLAG_N
   U14    3   FLG# AP22811AW57-AP22811AW5-7,SMLF,A    I79 @SCM_LIB.SCM(SCH_1):PAGE52

T_GND @SCM_LIB.SCM(SCH_1):T_GND
   DB1    1    GND TDR_3P_TH2-EMPTY,N_A     I1 @SCM_LIB.SCM(SCH_1):PAGE60
   DB6    1    GND TDR_3P_TH2-EMPTY,N_A     I3 @SCM_LIB.SCM(SCH_1):PAGE60
   DB5    1    GND TDR_3P_TH2-EMPTY,N_A     I5 @SCM_LIB.SCM(SCH_1):PAGE60
   DB4    1    GND TDR_3P_TH2-EMPTY,N_A     I7 @SCM_LIB.SCM(SCH_1):PAGE60
   DB3    1    GND TDR_3P_TH2-EMPTY,N_A     I9 @SCM_LIB.SCM(SCH_1):PAGE60
   DB2    1    GND TDR_3P_TH2-EMPTY,N_A    I11 @SCM_LIB.SCM(SCH_1):PAGE60

U39_ADJ @SCM_LIB.SCM(SCH_1):U39_ADJ
   U39    4    ADJ RT9059GQW-RT9059GQW,SMLF,IC,ALA    I60 @SCM_LIB.SCM(SCH_1):PAGE53
  R830    1      A Q_RES_0402LF-12K,1%,1/16W,CHIPA    I61 @SCM_LIB.SCM(SCH_1):PAGE53
  R829    2      B Q_RES_0402LF-25.5K,1%,1/16W,CHA    I62 @SCM_LIB.SCM(SCH_1):PAGE53

U41_ADJ @SCM_LIB.SCM(SCH_1):U41_ADJ
   U41    4    ADJ RT9059GQW-RT9059GQW,SMLF,IC,ALA    I96 @SCM_LIB.SCM(SCH_1):PAGE54
  R832    1      A Q_RES_0402LF-12K,1%,1/16W,CHIPA    I97 @SCM_LIB.SCM(SCH_1):PAGE54
  R831    2      B Q_RES_0402LF-15K,1%,1/16W,CHIPA    I98 @SCM_LIB.SCM(SCH_1):PAGE54

U43_CT @SCM_LIB.SCM(SCH_1):U43_CT
  R710    2      B Q_RES_0402LF-100K,1%,1/16W,CHIA    I55 @SCM_LIB.SCM(SCH_1):PAGE22
  C264    1      A Q_CAP_0402-0.1UF,25V,10%,X7R,CA    I59 @SCM_LIB.SCM(SCH_1):PAGE22
   U43    4     CT TPS3808G18DBVR-TPS3808G01DBVR,A    I90 @SCM_LIB.SCM(SCH_1):PAGE22

U56_ADJ_1 @SCM_LIB.SCM(SCH_1):U56_ADJ_1
   U56    4 ADJ||NC AP2205W57-AP2205-W5-7,SMLF,IC,A    I56 @SCM_LIB.SCM(SCH_1):PAGE51
  R677    1      A Q_RES_0402LF-10K,1%,1/16W,CHIPA    I57 @SCM_LIB.SCM(SCH_1):PAGE51
  R631    2      B Q_RES_0402LF-16.9K,1%,1/16W,CHA    I62 @SCM_LIB.SCM(SCH_1):PAGE51

UART_6_BMC_RXD @SCM_LIB.SCM(SCH_1):UART_6_BMC_RXD
  R762    1      A Q_RES_0402LF-33.2,1%,1/16W,CHIA   I474 @SCM_LIB.SCM(SCH_1):PAGE12
  R901    1      A Q_RES_0402LF-0,5%,1/16W,CHIP,CA    I71 @SCM_LIB.SCM(SCH_1):PAGE31

UART_6_BMC_RXD_R @SCM_LIB.SCM(SCH_1):UART_6_BMC_RXD_R
   U50    3     B0 NC7SB3157_SMLF-NC7SB3157P6X,NCA    I23 @SCM_LIB.SCM(SCH_1):PAGE31
  R538    2      B Q_RES_0402LF-100K,1%,1/16W,CHIA    I25 @SCM_LIB.SCM(SCH_1):PAGE31
  R901    2      B Q_RES_0402LF-0,5%,1/16W,CHIP,CA    I71 @SCM_LIB.SCM(SCH_1):PAGE31

UART_6_BMC_R_RXD @SCM_LIB.SCM(SCH_1):UART_6_BMC_R_RXD
    U5  B22 GPIOG1||RXD6||SD2CMD||SALT10 AST2600A3GP-AST2600A3-GP,SMLF,A   I436 @SCM_LIB.SCM(SCH_1):PAGE12
  R762    2      B Q_RES_0402LF-33.2,1%,1/16W,CHIA   I474 @SCM_LIB.SCM(SCH_1):PAGE12

UART_6_BMC_R_TXD @SCM_LIB.SCM(SCH_1):UART_6_BMC_R_TXD
    U5  E21 GPIOG0||TXD6||SD2CLK||SALT9 AST2600A3GP-AST2600A3-GP,SMLF,A   I436 @SCM_LIB.SCM(SCH_1):PAGE12
  R761    2      B Q_RES_0402LF-33.2,1%,1/16W,CHIA   I473 @SCM_LIB.SCM(SCH_1):PAGE12

UART_6_BMC_TXD @SCM_LIB.SCM(SCH_1):UART_6_BMC_TXD
  R761    1      A Q_RES_0402LF-33.2,1%,1/16W,CHIA   I473 @SCM_LIB.SCM(SCH_1):PAGE12
  R903    1      A Q_RES_0402LF-0,5%,1/16W,CHIP,CA    I73 @SCM_LIB.SCM(SCH_1):PAGE31

UART_6_BMC_TXD_R @SCM_LIB.SCM(SCH_1):UART_6_BMC_TXD_R
   U51    3     B0 NC7SB3157_SMLF-NC7SB3157P6X,NCA    I24 @SCM_LIB.SCM(SCH_1):PAGE31
  R903    2      B Q_RES_0402LF-0,5%,1/16W,CHIP,CA    I73 @SCM_LIB.SCM(SCH_1):PAGE31

UART_BIC_DBG_RX @SCM_LIB.SCM(SCH_1):UART_BIC_DBG_RX
    U3    1     B0 FSA3357K8X-FSA3357K8X,SMLF,IC,A   I251 @SCM_LIB.SCM(SCH_1):PAGE30
  R902    1      A Q_RES_0402LF-0,5%,1/16W,CHIP,CA    I72 @SCM_LIB.SCM(SCH_1):PAGE31

UART_BIC_DBG_RX_R @SCM_LIB.SCM(SCH_1):UART_BIC_DBG_RX_R
   U51    1     B1 NC7SB3157_SMLF-NC7SB3157P6X,NCA    I24 @SCM_LIB.SCM(SCH_1):PAGE31
  R902    2      B Q_RES_0402LF-0,5%,1/16W,CHIP,CA    I72 @SCM_LIB.SCM(SCH_1):PAGE31

UART_BIC_DBG_TX @SCM_LIB.SCM(SCH_1):UART_BIC_DBG_TX
    U2    1     B0 FSA3357K8X-FSA3357K8X,SMLF,IC,A   I250 @SCM_LIB.SCM(SCH_1):PAGE30
  R900    1      A Q_RES_0402LF-0,5%,1/16W,CHIP,CA    I70 @SCM_LIB.SCM(SCH_1):PAGE31

UART_BIC_DBG_TX_R @SCM_LIB.SCM(SCH_1):UART_BIC_DBG_TX_R
   U50    1     B1 NC7SB3157_SMLF-NC7SB3157P6X,NCA    I23 @SCM_LIB.SCM(SCH_1):PAGE31
  R900    2      B Q_RES_0402LF-0,5%,1/16W,CHIP,CA    I70 @SCM_LIB.SCM(SCH_1):PAGE31

UART_BIC_GF_RXD @SCM_LIB.SCM(SCH_1):UART_BIC_GF_RXD
   GF1  OB6 UART1_SCM_RX FCONN168_ME1016810202011_SCM-FA   I553 @SCM_LIB.SCM(SCH_1):PAGE10
   U50    4      A NC7SB3157_SMLF-NC7SB3157P6X,NCA    I23 @SCM_LIB.SCM(SCH_1):PAGE31
  R396    2      B Q_RES_0402LF-100K,1%,1/16W,CHIA    I80 @SCM_LIB.SCM(SCH_1):PAGE31

UART_BIC_GF_TXD @SCM_LIB.SCM(SCH_1):UART_BIC_GF_TXD
   GF1  OB5 UART1_SCM_TX FCONN168_ME1016810202011_SCM-FA   I553 @SCM_LIB.SCM(SCH_1):PAGE10
   U51    4      A NC7SB3157_SMLF-NC7SB3157P6X,NCA    I24 @SCM_LIB.SCM(SCH_1):PAGE31

UART_BMC_1_RXD @SCM_LIB.SCM(SCH_1):UART_BMC_1_RXD
  R427    2      B Q_RES_0402LF-33.2,1%,1/16W,CHIA   I198 @SCM_LIB.SCM(SCH_1):PAGE13
    U5  D13 GPIOM7||RXD1 AST2600A3GP-AST2600A3-GP,SMLF,A   I363 @SCM_LIB.SCM(SCH_1):PAGE13

UART_BMC_1_RXD_R @SCM_LIB.SCM(SCH_1):UART_BMC_1_RXD_R
  R427    1      A Q_RES_0402LF-33.2,1%,1/16W,CHIA   I198 @SCM_LIB.SCM(SCH_1):PAGE13
    U3    3     B2 FSA3357K8X-FSA3357K8X,SMLF,IC,A   I251 @SCM_LIB.SCM(SCH_1):PAGE30

UART_BMC_1_TXD @SCM_LIB.SCM(SCH_1):UART_BMC_1_TXD
  R157    2      B Q_RES_0402LF-33.2,1%,1/16W,CHIA    I18 @SCM_LIB.SCM(SCH_1):PAGE13
    U5  C13 GPIOM6||TXD1 AST2600A3GP-AST2600A3-GP,SMLF,A   I363 @SCM_LIB.SCM(SCH_1):PAGE13

UART_BMC_1_TXD_R @SCM_LIB.SCM(SCH_1):UART_BMC_1_TXD_R
  R157    1      A Q_RES_0402LF-33.2,1%,1/16W,CHIA    I18 @SCM_LIB.SCM(SCH_1):PAGE13
    U2    3     B2 FSA3357K8X-FSA3357K8X,SMLF,IC,A   I250 @SCM_LIB.SCM(SCH_1):PAGE30

UART_BMC_5_RXD @SCM_LIB.SCM(SCH_1):UART_BMC_5_RXD
  R759    1      A Q_RES_0402LF-33.2,1%,1/16W,CHIA   I208 @SCM_LIB.SCM(SCH_1):PAGE13
    U5   D8   RXD5 AST2600A3GP-AST2600A3-GP,SMLF,A   I363 @SCM_LIB.SCM(SCH_1):PAGE13

UART_BMC_5_RXD_BUF @SCM_LIB.SCM(SCH_1):UART_BMC_5_RXD_BUF
    J6    3      3 SCONN3_21291035BR2-SCONN3_212-A   I184 @SCM_LIB.SCM(SCH_1):PAGE30
  R741    2      B Q_RES_0402LF-4.7K,1%,1/16W,CHIA   I197 @SCM_LIB.SCM(SCH_1):PAGE30
   U24    3     2A 74LVC2G07DW7-74LVC2G07DW-7,SMLA   I246 @SCM_LIB.SCM(SCH_1):PAGE30

UART_BMC_5_RXD_BUF1 @SCM_LIB.SCM(SCH_1):UART_BMC_5_RXD_BUF1
  R104    2      B Q_RES_0402LF-33.2,1%,1/16W,CHIA   I147 @SCM_LIB.SCM(SCH_1):PAGE30
   R72    2      B Q_RES_0402LF-4.7K,1%,1/16W,CHIA   I231 @SCM_LIB.SCM(SCH_1):PAGE30
  R766    1      A Q_RES_0402LF-33.2,1%,1/16W,CHIA   I237 @SCM_LIB.SCM(SCH_1):PAGE30
   U47    3     2A 74LVC2G07DW7-74LVC2G07DW-7,SMLA   I247 @SCM_LIB.SCM(SCH_1):PAGE30

UART_BMC_5_RXD_BUF1_R @SCM_LIB.SCM(SCH_1):UART_BMC_5_RXD_BUF1_R
  R757    1      A Q_RES_0402LF-33.2,1%,1/16W,CHIA   I226 @SCM_LIB.SCM(SCH_1):PAGE30
   U47    4     2Y 74LVC2G07DW7-74LVC2G07DW-7,SMLA   I247 @SCM_LIB.SCM(SCH_1):PAGE30

UART_BMC_5_RXD_BUF1_SW @SCM_LIB.SCM(SCH_1):UART_BMC_5_RXD_BUF1_SW
  R766    2      B Q_RES_0402LF-33.2,1%,1/16W,CHIA   I237 @SCM_LIB.SCM(SCH_1):PAGE30
    U3    2     B1 FSA3357K8X-FSA3357K8X,SMLF,IC,A   I251 @SCM_LIB.SCM(SCH_1):PAGE30

UART_BMC_5_RXD_BUF_R @SCM_LIB.SCM(SCH_1):UART_BMC_5_RXD_BUF_R
  R104    1      A Q_RES_0402LF-33.2,1%,1/16W,CHIA   I147 @SCM_LIB.SCM(SCH_1):PAGE30
   U24    4     2Y 74LVC2G07DW7-74LVC2G07DW-7,SMLA   I246 @SCM_LIB.SCM(SCH_1):PAGE30

UART_BMC_5_RXD_R @SCM_LIB.SCM(SCH_1):UART_BMC_5_RXD_R
  R759    2      B Q_RES_0402LF-33.2,1%,1/16W,CHIA   I208 @SCM_LIB.SCM(SCH_1):PAGE13
  R758    2      B Q_RES_0402LF-4.7K,1%,1/16W,CHIA   I221 @SCM_LIB.SCM(SCH_1):PAGE30
  R757    2      B Q_RES_0402LF-33.2,1%,1/16W,CHIA   I226 @SCM_LIB.SCM(SCH_1):PAGE30

UART_BMC_5_TXD @SCM_LIB.SCM(SCH_1):UART_BMC_5_TXD
  R170    1      A Q_RES_0402LF-33.2,1%,1/16W,CHIA    I67 @SCM_LIB.SCM(SCH_1):PAGE13
    U5   C8   TXD5 AST2600A3GP-AST2600A3-GP,SMLF,A   I363 @SCM_LIB.SCM(SCH_1):PAGE13

UART_BMC_5_TXD_BUF @SCM_LIB.SCM(SCH_1):UART_BMC_5_TXD_BUF
  R102    1      A Q_RES_0402LF-33.2,1%,1/16W,CHIA   I148 @SCM_LIB.SCM(SCH_1):PAGE30
   U24    6     1Y 74LVC2G07DW7-74LVC2G07DW-7,SMLA   I246 @SCM_LIB.SCM(SCH_1):PAGE30

UART_BMC_5_TXD_BUF1 @SCM_LIB.SCM(SCH_1):UART_BMC_5_TXD_BUF1
  R715    1      A Q_RES_0402LF-33.2,1%,1/16W,CHIA   I225 @SCM_LIB.SCM(SCH_1):PAGE30
   U47    6     1Y 74LVC2G07DW7-74LVC2G07DW-7,SMLA   I247 @SCM_LIB.SCM(SCH_1):PAGE30

UART_BMC_5_TXD_BUF1_R @SCM_LIB.SCM(SCH_1):UART_BMC_5_TXD_BUF1_R
   R67    2      B Q_RES_0402LF-4.7K,1%,1/16W,CHIA   I146 @SCM_LIB.SCM(SCH_1):PAGE30
  R715    2      B Q_RES_0402LF-33.2,1%,1/16W,CHIA   I225 @SCM_LIB.SCM(SCH_1):PAGE30
   U24    1     1A 74LVC2G07DW7-74LVC2G07DW-7,SMLA   I246 @SCM_LIB.SCM(SCH_1):PAGE30
    U2    2     B1 FSA3357K8X-FSA3357K8X,SMLF,IC,A   I250 @SCM_LIB.SCM(SCH_1):PAGE30

UART_BMC_5_TXD_BUF_R @SCM_LIB.SCM(SCH_1):UART_BMC_5_TXD_BUF_R
  R102    2      B Q_RES_0402LF-33.2,1%,1/16W,CHIA   I148 @SCM_LIB.SCM(SCH_1):PAGE30
    J6    1      1 SCONN3_21291035BR2-SCONN3_212-A   I184 @SCM_LIB.SCM(SCH_1):PAGE30
  R765    2      B Q_RES_0402LF-4.7K,1%,1/16W,CHIA   I239 @SCM_LIB.SCM(SCH_1):PAGE30

UART_BMC_5_TXD_R @SCM_LIB.SCM(SCH_1):UART_BMC_5_TXD_R
  R170    2      B Q_RES_0402LF-33.2,1%,1/16W,CHIA    I67 @SCM_LIB.SCM(SCH_1):PAGE13
   U11    2      A BAT54C-BAT54C,SMLF,IC,BCBAT54CA   I185 @SCM_LIB.SCM(SCH_1):PAGE27
  R754    2      B Q_RES_0402LF-4.7K,1%,1/16W,EMPA   I213 @SCM_LIB.SCM(SCH_1):PAGE27
  R770    2      B Q_RES_0402LF-4.7K,1%,1/16W,EMPA   I217 @SCM_LIB.SCM(SCH_1):PAGE27
   U47    1     1A 74LVC2G07DW7-74LVC2G07DW-7,SMLA   I247 @SCM_LIB.SCM(SCH_1):PAGE30

UART_SYS_DBG_RX @SCM_LIB.SCM(SCH_1):UART_SYS_DBG_RX
   GF1  OB9 UART0_SCM_RX FCONN168_ME1016810202011_SCM-FA   I553 @SCM_LIB.SCM(SCH_1):PAGE10
  R618    1      A Q_RES_0402LF-0,5%,1/16W,CHIP,CA    I76 @SCM_LIB.SCM(SCH_1):PAGE31

UART_SYS_DBG_RX_R @SCM_LIB.SCM(SCH_1):UART_SYS_DBG_RX_R
   U20    3     B0 NC7SB3157_SMLF-NC7SB3157P6X,NCA    I38 @SCM_LIB.SCM(SCH_1):PAGE31
  R618    2      B Q_RES_0402LF-0,5%,1/16W,CHIP,CA    I76 @SCM_LIB.SCM(SCH_1):PAGE31

UART_SYS_DBG_TX @SCM_LIB.SCM(SCH_1):UART_SYS_DBG_TX
   GF1  OB8 UART0_SCM_TX FCONN168_ME1016810202011_SCM-FA   I553 @SCM_LIB.SCM(SCH_1):PAGE10
  R544    1      A Q_RES_0402LF-0,5%,1/16W,CHIP,CA    I74 @SCM_LIB.SCM(SCH_1):PAGE31

UART_SYS_DBG_TX_R @SCM_LIB.SCM(SCH_1):UART_SYS_DBG_TX_R
    U7    3     B0 NC7SB3157_SMLF-NC7SB3157P6X,NCA    I27 @SCM_LIB.SCM(SCH_1):PAGE31
  R544    2      B Q_RES_0402LF-0,5%,1/16W,CHIP,CA    I74 @SCM_LIB.SCM(SCH_1):PAGE31

USB2_01_F_DN @SCM_LIB.SCM(SCH_1):USB2_01_F_DN
  R385    2      B Q_RES_0402LF-0,5%,1/16W,CHIP,CA    I96 @SCM_LIB.SCM(SCH_1):PAGE29
   U38    3    IO2 PRTR5V0U2X-PRTR5V0U2X,SMLF,IC,A    I99 @SCM_LIB.SCM(SCH_1):PAGE29
   L23    3      3 Q_INDUCTOR4P_12-67/320MA,320MAA   I102 @SCM_LIB.SCM(SCH_1):PAGE29
    J2    2     D- CONN9_GSB3111315HR-CONN9_GSB31A   I221 @SCM_LIB.SCM(SCH_1):PAGE29

USB2_01_F_DP @SCM_LIB.SCM(SCH_1):USB2_01_F_DP
   U38    2    IO1 PRTR5V0U2X-PRTR5V0U2X,SMLF,IC,A    I99 @SCM_LIB.SCM(SCH_1):PAGE29
  R386    2      B Q_RES_0402LF-0,5%,1/16W,CHIP,CA   I101 @SCM_LIB.SCM(SCH_1):PAGE29
   L23    2      2 Q_INDUCTOR4P_12-67/320MA,320MAA   I102 @SCM_LIB.SCM(SCH_1):PAGE29
    J2    3     D+ CONN9_GSB3111315HR-CONN9_GSB31A   I221 @SCM_LIB.SCM(SCH_1):PAGE29

USB3_01_FB_RXN @SCM_LIB.SCM(SCH_1):USB3_01_FB_RXN
  R668    2      B Q_RES_0402LF-0,5%,1/16W,CHIP,CA   I111 @SCM_LIB.SCM(SCH_1):PAGE29
   L22    3      3 Q_INDUCTOR4P_12-67/320MA,320MAA   I113 @SCM_LIB.SCM(SCH_1):PAGE29
   U27    5    IO4 DT1240E04LP7-DT1240E-04LP-7,SMA   I211 @SCM_LIB.SCM(SCH_1):PAGE29
   U27    6    NC1 DT1240E04LP7-DT1240E-04LP-7,SMA   I211 @SCM_LIB.SCM(SCH_1):PAGE29
    J2    5  SSRX- CONN9_GSB3111315HR-CONN9_GSB31A   I221 @SCM_LIB.SCM(SCH_1):PAGE29

USB3_01_FB_RXP @SCM_LIB.SCM(SCH_1):USB3_01_FB_RXP
  R675    2      B Q_RES_0402LF-0,5%,1/16W,CHIP,CA   I109 @SCM_LIB.SCM(SCH_1):PAGE29
   L22    2      2 Q_INDUCTOR4P_12-67/320MA,320MAA   I113 @SCM_LIB.SCM(SCH_1):PAGE29
   U27    4    IO3 DT1240E04LP7-DT1240E-04LP-7,SMA   I211 @SCM_LIB.SCM(SCH_1):PAGE29
   U27    7    NC2 DT1240E04LP7-DT1240E-04LP-7,SMA   I211 @SCM_LIB.SCM(SCH_1):PAGE29
    J2    6  SSRX+ CONN9_GSB3111315HR-CONN9_GSB31A   I221 @SCM_LIB.SCM(SCH_1):PAGE29

USB3_01_FB_TXN @SCM_LIB.SCM(SCH_1):USB3_01_FB_TXN
   L21    3      3 Q_INDUCTOR4P_12-67/320MA,320MAA   I123 @SCM_LIB.SCM(SCH_1):PAGE29
  R666    2      B Q_RES_0402LF-0,5%,1/16W,CHIP,CA   I124 @SCM_LIB.SCM(SCH_1):PAGE29
   U27    2    IO2 DT1240E04LP7-DT1240E-04LP-7,SMA   I211 @SCM_LIB.SCM(SCH_1):PAGE29
   U27    9    NC3 DT1240E04LP7-DT1240E-04LP-7,SMA   I211 @SCM_LIB.SCM(SCH_1):PAGE29
    J2    8  SSTX- CONN9_GSB3111315HR-CONN9_GSB31A   I221 @SCM_LIB.SCM(SCH_1):PAGE29

USB3_01_FB_TXP @SCM_LIB.SCM(SCH_1):USB3_01_FB_TXP
  R673    2      B Q_RES_0402LF-0,5%,1/16W,CHIP,CA   I122 @SCM_LIB.SCM(SCH_1):PAGE29
   L21    2      2 Q_INDUCTOR4P_12-67/320MA,320MAA   I123 @SCM_LIB.SCM(SCH_1):PAGE29
   U27    1    IO1 DT1240E04LP7-DT1240E-04LP-7,SMA   I211 @SCM_LIB.SCM(SCH_1):PAGE29
   U27   10    NC4 DT1240E04LP7-DT1240E-04LP-7,SMA   I211 @SCM_LIB.SCM(SCH_1):PAGE29
    J2    9  SSTX+ CONN9_GSB3111315HR-CONN9_GSB31A   I221 @SCM_LIB.SCM(SCH_1):PAGE29

USB3_01_MUX_FB_RXN @SCM_LIB.SCM(SCH_1):USB3_01_MUX_FB_RXN
  R668    1      A Q_RES_0402LF-0,5%,1/16W,CHIP,CA   I111 @SCM_LIB.SCM(SCH_1):PAGE29
   L22    4      4 Q_INDUCTOR4P_12-67/320MA,320MAA   I113 @SCM_LIB.SCM(SCH_1):PAGE29
   U22    8   A1_N PI3PCIE3212ZBEX-PI3PCIE3212ZBEA   I206 @SCM_LIB.SCM(SCH_1):PAGE29

USB3_01_MUX_FB_RXP @SCM_LIB.SCM(SCH_1):USB3_01_MUX_FB_RXP
  R675    1      A Q_RES_0402LF-0,5%,1/16W,CHIP,CA   I109 @SCM_LIB.SCM(SCH_1):PAGE29
   L22    1      1 Q_INDUCTOR4P_12-67/320MA,320MAA   I113 @SCM_LIB.SCM(SCH_1):PAGE29
   U22    7   A1_P PI3PCIE3212ZBEX-PI3PCIE3212ZBEA   I206 @SCM_LIB.SCM(SCH_1):PAGE29

USB3_01_MUX_FB_TXN @SCM_LIB.SCM(SCH_1):USB3_01_MUX_FB_TXN
   L21    4      4 Q_INDUCTOR4P_12-67/320MA,320MAA   I123 @SCM_LIB.SCM(SCH_1):PAGE29
  R666    1      A Q_RES_0402LF-0,5%,1/16W,CHIP,CA   I124 @SCM_LIB.SCM(SCH_1):PAGE29
   U22    4   A0_N PI3PCIE3212ZBEX-PI3PCIE3212ZBEA   I206 @SCM_LIB.SCM(SCH_1):PAGE29

USB3_01_MUX_FB_TXP @SCM_LIB.SCM(SCH_1):USB3_01_MUX_FB_TXP
  R673    1      A Q_RES_0402LF-0,5%,1/16W,CHIP,CA   I122 @SCM_LIB.SCM(SCH_1):PAGE29
   L21    1      1 Q_INDUCTOR4P_12-67/320MA,320MAA   I123 @SCM_LIB.SCM(SCH_1):PAGE29
   U22    3   A0_P PI3PCIE3212ZBEX-PI3PCIE3212ZBEA   I206 @SCM_LIB.SCM(SCH_1):PAGE29

USB3_01_TXN_C @SCM_LIB.SCM(SCH_1):USB3_01_TXN_C
  C239    2      B Q_CAP_0402-0.1UF,25V,10%,EMPTYA   I143 @SCM_LIB.SCM(SCH_1):PAGE29
  R672    1      A Q_RES_0402LF-0,5%,1/16W,CHIP,CA   I144 @SCM_LIB.SCM(SCH_1):PAGE29
   U22   18   B0_N PI3PCIE3212ZBEX-PI3PCIE3212ZBEA   I206 @SCM_LIB.SCM(SCH_1):PAGE29

USB3_01_TXP_C @SCM_LIB.SCM(SCH_1):USB3_01_TXP_C
  R671    1      A Q_RES_0402LF-0,5%,1/16W,CHIP,CA   I141 @SCM_LIB.SCM(SCH_1):PAGE29
  C238    2      B Q_CAP_0402-0.1UF,25V,10%,EMPTYA   I142 @SCM_LIB.SCM(SCH_1):PAGE29
   U22   19   B0_P PI3PCIE3212ZBEX-PI3PCIE3212ZBEA   I206 @SCM_LIB.SCM(SCH_1):PAGE29

USB3_FPNL_RXN @SCM_LIB.SCM(SCH_1):USB3_FPNL_RXN
   GF1  A60 PCIE_HPM_RXN_0 FCONN168_ME1016810202011_SCM-FA   I553 @SCM_LIB.SCM(SCH_1):PAGE10
   U22   16   B1_N PI3PCIE3212ZBEX-PI3PCIE3212ZBEA   I206 @SCM_LIB.SCM(SCH_1):PAGE29

USB3_FPNL_RXP @SCM_LIB.SCM(SCH_1):USB3_FPNL_RXP
   GF1  A59 PCIE_HPM_RXP_0 FCONN168_ME1016810202011_SCM-FA   I553 @SCM_LIB.SCM(SCH_1):PAGE10
   U22   17   B1_P PI3PCIE3212ZBEX-PI3PCIE3212ZBEA   I206 @SCM_LIB.SCM(SCH_1):PAGE29

USB3_FPNL_TXN @SCM_LIB.SCM(SCH_1):USB3_FPNL_TXN
   GF1  B60 PCIE_HPM_TXN_0 FCONN168_ME1016810202011_SCM-FA   I553 @SCM_LIB.SCM(SCH_1):PAGE10
  C239    1      A Q_CAP_0402-0.1UF,25V,10%,EMPTYA   I143 @SCM_LIB.SCM(SCH_1):PAGE29
  R672    2      B Q_RES_0402LF-0,5%,1/16W,CHIP,CA   I144 @SCM_LIB.SCM(SCH_1):PAGE29

USB3_FPNL_TXP @SCM_LIB.SCM(SCH_1):USB3_FPNL_TXP
   GF1  B59 PCIE_HPM_TXP_0 FCONN168_ME1016810202011_SCM-FA   I553 @SCM_LIB.SCM(SCH_1):PAGE10
  R671    2      B Q_RES_0402LF-0,5%,1/16W,CHIP,CA   I141 @SCM_LIB.SCM(SCH_1):PAGE29
  C238    1      A Q_CAP_0402-0.1UF,25V,10%,EMPTYA   I142 @SCM_LIB.SCM(SCH_1):PAGE29

USB3_MUX_PD @SCM_LIB.SCM(SCH_1):USB3_MUX_PD
  R712    2      B Q_RES_0402LF-10K,1%,1/16W,EMPTA   I153 @SCM_LIB.SCM(SCH_1):PAGE29
  R694    1      A Q_RES_0402LF-100,1%,1/16W,CHIPA   I155 @SCM_LIB.SCM(SCH_1):PAGE29
   U22    2     PD PI3PCIE3212ZBEX-PI3PCIE3212ZBEA   I206 @SCM_LIB.SCM(SCH_1):PAGE29

USB_FPNL_DN @SCM_LIB.SCM(SCH_1):USB_FPNL_DN
   GF1  B57  RSVD1 FCONN168_ME1016810202011_SCM-FA   I553 @SCM_LIB.SCM(SCH_1):PAGE10
  R385    1      A Q_RES_0402LF-0,5%,1/16W,CHIP,CA    I96 @SCM_LIB.SCM(SCH_1):PAGE29
   L23    4      4 Q_INDUCTOR4P_12-67/320MA,320MAA   I102 @SCM_LIB.SCM(SCH_1):PAGE29

USB_FPNL_DP @SCM_LIB.SCM(SCH_1):USB_FPNL_DP
   GF1  B56  RSVD0 FCONN168_ME1016810202011_SCM-FA   I553 @SCM_LIB.SCM(SCH_1):PAGE10
  R386    1      A Q_RES_0402LF-0,5%,1/16W,CHIP,CA   I101 @SCM_LIB.SCM(SCH_1):PAGE29
   L23    1      1 Q_INDUCTOR4P_12-67/320MA,320MAA   I102 @SCM_LIB.SCM(SCH_1):PAGE29

USB_HOST_BMC_A_DN @SCM_LIB.SCM(SCH_1):USB_HOST_BMC_A_DN
   GF1  B54 USB1_DN FCONN168_ME1016810202011_SCM-FA   I553 @SCM_LIB.SCM(SCH_1):PAGE10
  R218    2      B Q_RES_0402LF-0,5%,1/16W,CHIP,CA    I93 @SCM_LIB.SCM(SCH_1):PAGE15
  R441    1      A Q_RES_0402LF-49.9,1%,1/16W,EMPA   I353 @SCM_LIB.SCM(SCH_1):PAGE15

USB_HOST_BMC_A_DP @SCM_LIB.SCM(SCH_1):USB_HOST_BMC_A_DP
   GF1  B53 USB1_DP FCONN168_ME1016810202011_SCM-FA   I553 @SCM_LIB.SCM(SCH_1):PAGE10
  R217    2      B Q_RES_0402LF-0,5%,1/16W,CHIP,CA    I92 @SCM_LIB.SCM(SCH_1):PAGE15
  R440    1      A Q_RES_0402LF-49.9,1%,1/16W,EMPA   I354 @SCM_LIB.SCM(SCH_1):PAGE15

USB_HOST_BMC_A_R_DN @SCM_LIB.SCM(SCH_1):USB_HOST_BMC_A_R_DN
  R218    1      A Q_RES_0402LF-0,5%,1/16W,CHIP,CA    I93 @SCM_LIB.SCM(SCH_1):PAGE15
    U5   B4 USB2A_DN AST2600A3GP-AST2600A3-GP,SMLF,A   I350 @SCM_LIB.SCM(SCH_1):PAGE15

USB_HOST_BMC_A_R_DP @SCM_LIB.SCM(SCH_1):USB_HOST_BMC_A_R_DP
  R217    1      A Q_RES_0402LF-0,5%,1/16W,CHIP,CA    I92 @SCM_LIB.SCM(SCH_1):PAGE15
    U5   A4 USB2A_DP AST2600A3GP-AST2600A3-GP,SMLF,A   I350 @SCM_LIB.SCM(SCH_1):PAGE15

USB_HOST_BMC_B_DN @SCM_LIB.SCM(SCH_1):USB_HOST_BMC_B_DN
   GF1  B51 USB2_DN FCONN168_ME1016810202011_SCM-FA   I553 @SCM_LIB.SCM(SCH_1):PAGE10
  R528    2      B Q_RES_0402LF-0,5%,1/16W,CHIP,CA   I168 @SCM_LIB.SCM(SCH_1):PAGE15

USB_HOST_BMC_B_DP @SCM_LIB.SCM(SCH_1):USB_HOST_BMC_B_DP
   GF1  B50 USB2_DP FCONN168_ME1016810202011_SCM-FA   I553 @SCM_LIB.SCM(SCH_1):PAGE10
  R527    2      B Q_RES_0402LF-0,5%,1/16W,CHIP,CA   I169 @SCM_LIB.SCM(SCH_1):PAGE15

USB_HOST_BMC_B_R_DN @SCM_LIB.SCM(SCH_1):USB_HOST_BMC_B_R_DN
  R528    1      A Q_RES_0402LF-0,5%,1/16W,CHIP,CA   I168 @SCM_LIB.SCM(SCH_1):PAGE15
    U5   B6 USB2B_DN AST2600A3GP-AST2600A3-GP,SMLF,A   I350 @SCM_LIB.SCM(SCH_1):PAGE15

USB_HOST_BMC_B_R_DP @SCM_LIB.SCM(SCH_1):USB_HOST_BMC_B_R_DP
  R527    1      A Q_RES_0402LF-0,5%,1/16W,CHIP,CA   I169 @SCM_LIB.SCM(SCH_1):PAGE15
    U5   A6 USB2B_DP AST2600A3GP-AST2600A3-GP,SMLF,A   I350 @SCM_LIB.SCM(SCH_1):PAGE15

USB_OC0_EN @SCM_LIB.SCM(SCH_1):USB_OC0_EN
  R376    2      B Q_RES_0402LF-4.7K,1%,1/16W,CHIA    I62 @SCM_LIB.SCM(SCH_1):PAGE28
  R377    1      A Q_RES_0402LF-10K,1%,1/16W,EMPTA    I63 @SCM_LIB.SCM(SCH_1):PAGE28
   U10    3     EN NCP380HSNAJAAT1G-NCP380HSNAJAAA   I179 @SCM_LIB.SCM(SCH_1):PAGE28

USB_OC0_ILIM @SCM_LIB.SCM(SCH_1):USB_OC0_ILIM
  R378    1      A Q_RES_0402LF-20K,1%,1/16W,CHIPA    I54 @SCM_LIB.SCM(SCH_1):PAGE28
   U10    5   ILIM NCP380HSNAJAAT1G-NCP380HSNAJAAA   I179 @SCM_LIB.SCM(SCH_1):PAGE28

USB_OC0_REAR_N @SCM_LIB.SCM(SCH_1):USB_OC0_REAR_N
  R383    2      B Q_RES_0402LF-10K,1%,1/16W,CHIPA    I42 @SCM_LIB.SCM(SCH_1):PAGE28
   U10    4 FLAG_N NCP380HSNAJAAT1G-NCP380HSNAJAAA   I179 @SCM_LIB.SCM(SCH_1):PAGE28
  R384    1      A Q_RES_0402LF-100,1%,1/16W,CHIPA   I185 @SCM_LIB.SCM(SCH_1):PAGE28

USB_OC0_REAR_R_N @SCM_LIB.SCM(SCH_1):USB_OC0_REAR_R_N
    U5 AB25 GPIOQ1||TACH1 AST2600A3GP-AST2600A3-GP,SMLF,A   I350 @SCM_LIB.SCM(SCH_1):PAGE15
   U25  L16  PR11A LCMXO3LF2100C5BG256C-LCMXO3LF-A     I1 @SCM_LIB.SCM(SCH_1):PAGE35
  R384    2      B Q_RES_0402LF-100,1%,1/16W,CHIPA   I185 @SCM_LIB.SCM(SCH_1):PAGE28

VCCIO0 @SCM_LIB.SCM(SCH_1):VCCIO0
   U25   D5 VCCIO0_D5 LCMXO3LF2100C5BG256C-LCMXO3LF-A     I1 @SCM_LIB.SCM(SCH_1):PAGE34
   U25  D12 VCCIO0_D12 LCMXO3LF2100C5BG256C-LCMXO3LF-A     I1 @SCM_LIB.SCM(SCH_1):PAGE34
   U25   G8 VCCIO0_G8 LCMXO3LF2100C5BG256C-LCMXO3LF-A     I1 @SCM_LIB.SCM(SCH_1):PAGE34
   U25   G9 VCCIO0_G9 LCMXO3LF2100C5BG256C-LCMXO3LF-A     I1 @SCM_LIB.SCM(SCH_1):PAGE34
  C242    1      A Q_CAP_0402-0.1UF,25V,10%,X7R,CA     I1 @SCM_LIB.SCM(SCH_1):PAGE41
  C166    1      A Q_CAP_C0402-1UF,25V,10%,X6S,CHA     I8 @SCM_LIB.SCM(SCH_1):PAGE41
  R305    2      B Q_RES_0402LF-0,5%,1/16W,CHIP,CA    I71 @SCM_LIB.SCM(SCH_1):PAGE41
  C247    1      A Q_CAP_0402-0.1UF,25V,10%,X7R,CA    I77 @SCM_LIB.SCM(SCH_1):PAGE41
  C189    1      A Q_CAP_0402-0.1UF,25V,10%,X7R,CA    I78 @SCM_LIB.SCM(SCH_1):PAGE41
  C261    1      A Q_CAP_0402-0.1UF,25V,10%,X7R,CA    I79 @SCM_LIB.SCM(SCH_1):PAGE41
  C283    1      A Q_CAP_C0402-0.01UF,50V,10%,EMPA   I126 @SCM_LIB.SCM(SCH_1):PAGE41

VCCIO1 @SCM_LIB.SCM(SCH_1):VCCIO1
   U25  E13 VCCIO1_E13 LCMXO3LF2100C5BG256C-LCMXO3LF-A     I1 @SCM_LIB.SCM(SCH_1):PAGE35
   U25  H10 VCCIO1_H10 LCMXO3LF2100C5BG256C-LCMXO3LF-A     I1 @SCM_LIB.SCM(SCH_1):PAGE35
   U25  J10 VCCIO1_J10 LCMXO3LF2100C5BG256C-LCMXO3LF-A     I1 @SCM_LIB.SCM(SCH_1):PAGE35
   U25  M13 VCCIO1_M13 LCMXO3LF2100C5BG256C-LCMXO3LF-A     I1 @SCM_LIB.SCM(SCH_1):PAGE35
  R525    2      B Q_RES_0402LF-0,5%,1/16W,CHIP,CA    I72 @SCM_LIB.SCM(SCH_1):PAGE41
  C167    1      A Q_CAP_0402-0.1UF,25V,10%,X7R,CA    I80 @SCM_LIB.SCM(SCH_1):PAGE41
  C243    1      A Q_CAP_0402-0.1UF,25V,10%,X7R,CA    I81 @SCM_LIB.SCM(SCH_1):PAGE41
  C254    1      A Q_CAP_0402-0.1UF,25V,10%,X7R,CA    I82 @SCM_LIB.SCM(SCH_1):PAGE41
  C141    1      A Q_CAP_0402-0.1UF,25V,10%,X7R,CA    I83 @SCM_LIB.SCM(SCH_1):PAGE41
  C164    1      A Q_CAP_C0402-1UF,25V,10%,X6S,CHA    I92 @SCM_LIB.SCM(SCH_1):PAGE41
  C281    1      A Q_CAP_C0402-0.01UF,50V,10%,EMPA   I125 @SCM_LIB.SCM(SCH_1):PAGE41

VCCIO2 @SCM_LIB.SCM(SCH_1):VCCIO2
   U25   K8 VCCIO2_K8 LCMXO3LF2100C5BG256C-LCMXO3LF-A     I1 @SCM_LIB.SCM(SCH_1):PAGE36
   U25   K9 VCCIO2_K9 LCMXO3LF2100C5BG256C-LCMXO3LF-A     I1 @SCM_LIB.SCM(SCH_1):PAGE36
   U25   N5 VCCIO2_N5 LCMXO3LF2100C5BG256C-LCMXO3LF-A     I1 @SCM_LIB.SCM(SCH_1):PAGE36
   U25  N12 VCCIO2_N12 LCMXO3LF2100C5BG256C-LCMXO3LF-A     I1 @SCM_LIB.SCM(SCH_1):PAGE36
  R304    2      B Q_RES_0402LF-0,5%,1/16W,CHIP,CA    I73 @SCM_LIB.SCM(SCH_1):PAGE41
  C187    1      A Q_CAP_0402-0.1UF,25V,10%,X7R,CA    I84 @SCM_LIB.SCM(SCH_1):PAGE41
  C245    1      A Q_CAP_0402-0.1UF,25V,10%,X7R,CA    I85 @SCM_LIB.SCM(SCH_1):PAGE41
  C188    1      A Q_CAP_0402-0.1UF,25V,10%,X7R,CA    I86 @SCM_LIB.SCM(SCH_1):PAGE41
  C260    1      A Q_CAP_0402-0.1UF,25V,10%,X7R,CA    I87 @SCM_LIB.SCM(SCH_1):PAGE41
  C165    1      A Q_CAP_C0402-1UF,25V,10%,X6S,CHA    I93 @SCM_LIB.SCM(SCH_1):PAGE41
  C285    1      A Q_CAP_C0402-0.01UF,50V,10%,EMPA   I124 @SCM_LIB.SCM(SCH_1):PAGE41
  R288    1      A Q_RES_0402LF-10K,1%,1/16W,CHIPA    I50 @SCM_LIB.SCM(SCH_1):PAGE36
  R297    2      B Q_RES_0402LF-10K,1%,1/16W,CHIPA   I137 @SCM_LIB.SCM(SCH_1):PAGE34

VCCIO3 @SCM_LIB.SCM(SCH_1):VCCIO3
   U25   M4 VCCIO3 LCMXO3LF2100C5BG256C-LCMXO3LF-A     I1 @SCM_LIB.SCM(SCH_1):PAGE37
  R308    2      B Q_RES_0402LF-0,5%,1/16W,CHIP,CA    I74 @SCM_LIB.SCM(SCH_1):PAGE41
  C152    1      A Q_CAP_0402-0.1UF,25V,10%,X7R,CA    I88 @SCM_LIB.SCM(SCH_1):PAGE41
  C216    1      A Q_CAP_C0402-1UF,25V,10%,X6S,CHA    I94 @SCM_LIB.SCM(SCH_1):PAGE41

VCCIO4 @SCM_LIB.SCM(SCH_1):VCCIO4
   U25   H7 VCCIO4_H7 LCMXO3LF2100C5BG256C-LCMXO3LF-A     I1 @SCM_LIB.SCM(SCH_1):PAGE38
   U25   J7 VCCIO4_J7 LCMXO3LF2100C5BG256C-LCMXO3LF-A     I1 @SCM_LIB.SCM(SCH_1):PAGE38
  R307    2      B Q_RES_0402LF-0,5%,1/16W,CHIP,CA    I76 @SCM_LIB.SCM(SCH_1):PAGE41
  C220    1      A Q_CAP_0402-0.1UF,25V,10%,X7R,CA    I90 @SCM_LIB.SCM(SCH_1):PAGE41
  C162    1      A Q_CAP_0402-0.1UF,25V,10%,X7R,CA    I91 @SCM_LIB.SCM(SCH_1):PAGE41
  C195    1      A Q_CAP_C0402-1UF,25V,10%,X6S,CHA    I96 @SCM_LIB.SCM(SCH_1):PAGE41

VCCIO5 @SCM_LIB.SCM(SCH_1):VCCIO5
   U25   E4 VCCIO5 LCMXO3LF2100C5BG256C-LCMXO3LF-A     I1 @SCM_LIB.SCM(SCH_1):PAGE39
  R301    2      B Q_RES_0402LF-0,5%,1/16W,CHIP,CA    I75 @SCM_LIB.SCM(SCH_1):PAGE41
  C160    1      A Q_CAP_0402-0.1UF,25V,10%,X7R,CA    I89 @SCM_LIB.SCM(SCH_1):PAGE41
  C218    1      A Q_CAP_C0402-1UF,25V,10%,X6S,CHA    I95 @SCM_LIB.SCM(SCH_1):PAGE41

VOL_SEN_ALERT_R @SCM_LIB.SCM(SCH_1):VOL_SEN_ALERT_R
    U5  K23 GPIOB1||SALT2 AST2600A3GP-AST2600A3-GP,SMLF,A   I363 @SCM_LIB.SCM(SCH_1):PAGE13
  R267    2      B Q_RES_0402LF-4.7K,1%,1/16W,EMPA    I85 @SCM_LIB.SCM(SCH_1):PAGE27
   U25  C15   PR1C LCMXO3LF2100C5BG256C-LCMXO3LF-A     I1 @SCM_LIB.SCM(SCH_1):PAGE35

V_BMC_DDC_LS_GATE @SCM_LIB.SCM(SCH_1):V_BMC_DDC_LS_GATE
    Q2    5     G2 MOSFET_NCH_DUAL-2N7002KDW,SMLFA     I2 @SCM_LIB.SCM(SCH_1):PAGE23
   R86    2      B Q_RES_0402LF-0,5%,1/16W,CHIP,CA    I51 @SCM_LIB.SCM(SCH_1):PAGE23
    Q2    2     G1 MOSFET_NCH_DUAL-2N7002KDW,SMLFA    I56 @SCM_LIB.SCM(SCH_1):PAGE23

V_BMC_DDC_SCL @SCM_LIB.SCM(SCH_1):V_BMC_DDC_SCL
    U5   B8 DDCCLK AST2600A3GP-AST2600A3-GP,SMLF,A   I350 @SCM_LIB.SCM(SCH_1):PAGE15
    Q2    4     S2 MOSFET_NCH_DUAL-2N7002KDW,SMLFA     I2 @SCM_LIB.SCM(SCH_1):PAGE23
   R32    2      B Q_RES_0402LF-4.7K,1%,1/16W,CHIA    I50 @SCM_LIB.SCM(SCH_1):PAGE23

V_BMC_DDC_SDA @SCM_LIB.SCM(SCH_1):V_BMC_DDC_SDA
    U5   A8 DDCDAT AST2600A3GP-AST2600A3-GP,SMLF,A   I350 @SCM_LIB.SCM(SCH_1):PAGE15
   R31    2      B Q_RES_0402LF-4.7K,1%,1/16W,CHIA    I27 @SCM_LIB.SCM(SCH_1):PAGE23
    Q2    1     S1 MOSFET_NCH_DUAL-2N7002KDW,SMLFA    I56 @SCM_LIB.SCM(SCH_1):PAGE23

V_BMC_LS_DDC_SCL @SCM_LIB.SCM(SCH_1):V_BMC_LS_DDC_SCL
    Q2    3     D2 MOSFET_NCH_DUAL-2N7002KDW,SMLFA     I2 @SCM_LIB.SCM(SCH_1):PAGE23
   R92    2      B Q_RES_0402LF-2.2K,5%,1/16W,CHIA    I64 @SCM_LIB.SCM(SCH_1):PAGE23
   R28    1      A Q_RES_0402LF-33.2,1%,1/16W,CHIA    I99 @SCM_LIB.SCM(SCH_1):PAGE23

V_BMC_LS_DDC_SCL_R @SCM_LIB.SCM(SCH_1):V_BMC_LS_DDC_SCL_R
   R16    1      A Q_RES_0402LF-2.21K,1%,1/16W,EMA    I75 @SCM_LIB.SCM(SCH_1):PAGE23
  C214    1      A Q_CAP_0402-100PF,50V,5%,EMPTY,A    I84 @SCM_LIB.SCM(SCH_1):PAGE23
   R28    2      B Q_RES_0402LF-33.2,1%,1/16W,CHIA    I99 @SCM_LIB.SCM(SCH_1):PAGE23
   U34    1    IO1 DT1240E04LP7-DT1240E-04LP-7,SMA   I156 @SCM_LIB.SCM(SCH_1):PAGE23
   U34   10    NC4 DT1240E04LP7-DT1240E-04LP-7,SMA   I156 @SCM_LIB.SCM(SCH_1):PAGE23
    J8   12     12 SCONN13_502280130CV01-SCONN13_A   I165 @SCM_LIB.SCM(SCH_1):PAGE23

V_BMC_LS_DDC_SDA @SCM_LIB.SCM(SCH_1):V_BMC_LS_DDC_SDA
   R29    1      A Q_RES_0402LF-33.2,1%,1/16W,CHIA    I34 @SCM_LIB.SCM(SCH_1):PAGE23
    Q2    6     D1 MOSFET_NCH_DUAL-2N7002KDW,SMLFA    I56 @SCM_LIB.SCM(SCH_1):PAGE23
   R91    2      B Q_RES_0402LF-2.2K,5%,1/16W,CHIA    I62 @SCM_LIB.SCM(SCH_1):PAGE23

V_BMC_LS_DDC_SDA_R @SCM_LIB.SCM(SCH_1):V_BMC_LS_DDC_SDA_R
   R29    2      B Q_RES_0402LF-33.2,1%,1/16W,CHIA    I34 @SCM_LIB.SCM(SCH_1):PAGE23
   R17    1      A Q_RES_0402LF-2.21K,1%,1/16W,EMA    I68 @SCM_LIB.SCM(SCH_1):PAGE23
  C213    1      A Q_CAP_0402-100PF,50V,5%,EMPTY,A    I83 @SCM_LIB.SCM(SCH_1):PAGE23
   U34    2    IO2 DT1240E04LP7-DT1240E-04LP-7,SMA   I156 @SCM_LIB.SCM(SCH_1):PAGE23
   U34    9    NC3 DT1240E04LP7-DT1240E-04LP-7,SMA   I156 @SCM_LIB.SCM(SCH_1):PAGE23
    J8   11     11 SCONN13_502280130CV01-SCONN13_A   I165 @SCM_LIB.SCM(SCH_1):PAGE23

V_DACB @SCM_LIB.SCM(SCH_1):V_DACB
   R24    2      B Q_RES_0402LF-10,1%,1/16W,CHIP,A   I134 @SCM_LIB.SCM(SCH_1):PAGE15
  C207    1      A Q_CAP_0402-15PF,50V,5%,C0G,CH0A    I29 @SCM_LIB.SCM(SCH_1):PAGE23
   L28    1      1 Q_INDUCTOR_SMLF-BLM18BB470/500A   I166 @SCM_LIB.SCM(SCH_1):PAGE23

V_DACB_IO @SCM_LIB.SCM(SCH_1):V_DACB_IO
   R87    1      A Q_RES_0402LF-150,1%,1/16W,CHIPA    I57 @SCM_LIB.SCM(SCH_1):PAGE23
   U35    1    IO1 DT1240E04LP7-DT1240E-04LP-7,SMA   I155 @SCM_LIB.SCM(SCH_1):PAGE23
   U35   10    NC4 DT1240E04LP7-DT1240E-04LP-7,SMA   I155 @SCM_LIB.SCM(SCH_1):PAGE23
    J8    5      5 SCONN13_502280130CV01-SCONN13_A   I165 @SCM_LIB.SCM(SCH_1):PAGE23
   L28    2      2 Q_INDUCTOR_SMLF-BLM18BB470/500A   I166 @SCM_LIB.SCM(SCH_1):PAGE23
  C210    1      A Q_CAP_0402-22PF,50V,5%,NPO,TMPA   I170 @SCM_LIB.SCM(SCH_1):PAGE23

V_DACB_R @SCM_LIB.SCM(SCH_1):V_DACB_R
   R24    1      A Q_RES_0402LF-10,1%,1/16W,CHIP,A   I134 @SCM_LIB.SCM(SCH_1):PAGE15
   R22    1      A Q_RES_0402LF-150,1%,1/16W,CHIPA   I151 @SCM_LIB.SCM(SCH_1):PAGE15
    U5 AD21   DACB AST2600A3GP-AST2600A3-GP,SMLF,A   I350 @SCM_LIB.SCM(SCH_1):PAGE15

V_DACG @SCM_LIB.SCM(SCH_1):V_DACG
   R21    2      B Q_RES_0402LF-10,1%,1/16W,CHIP,A   I133 @SCM_LIB.SCM(SCH_1):PAGE15
  C206    1      A Q_CAP_0402-15PF,50V,5%,C0G,CH0A    I26 @SCM_LIB.SCM(SCH_1):PAGE23
   L29    1      1 Q_INDUCTOR_SMLF-BLM18BB470/500A   I167 @SCM_LIB.SCM(SCH_1):PAGE23

V_DACG_IO @SCM_LIB.SCM(SCH_1):V_DACG_IO
  C209    1      A Q_CAP_0402-18PF,50V,5%,C0G,CH0A    I54 @SCM_LIB.SCM(SCH_1):PAGE23
   R88    1      A Q_RES_0402LF-150,1%,1/16W,CHIPA    I59 @SCM_LIB.SCM(SCH_1):PAGE23
   U35    2    IO2 DT1240E04LP7-DT1240E-04LP-7,SMA   I155 @SCM_LIB.SCM(SCH_1):PAGE23
   U35    9    NC3 DT1240E04LP7-DT1240E-04LP-7,SMA   I155 @SCM_LIB.SCM(SCH_1):PAGE23
    J8    3      3 SCONN13_502280130CV01-SCONN13_A   I165 @SCM_LIB.SCM(SCH_1):PAGE23
   L29    2      2 Q_INDUCTOR_SMLF-BLM18BB470/500A   I167 @SCM_LIB.SCM(SCH_1):PAGE23

V_DACG_R @SCM_LIB.SCM(SCH_1):V_DACG_R
   R21    1      A Q_RES_0402LF-10,1%,1/16W,CHIP,A   I133 @SCM_LIB.SCM(SCH_1):PAGE15
   R23    1      A Q_RES_0402LF-150,1%,1/16W,CHIPA   I150 @SCM_LIB.SCM(SCH_1):PAGE15
    U5 AE21   DACG AST2600A3GP-AST2600A3-GP,SMLF,A   I350 @SCM_LIB.SCM(SCH_1):PAGE15

V_DACR @SCM_LIB.SCM(SCH_1):V_DACR
   R26    2      B Q_RES_0402LF-10,1%,1/16W,CHIP,A   I142 @SCM_LIB.SCM(SCH_1):PAGE15
  C205    1      A Q_CAP_0402-15PF,50V,5%,C0G,CH0A    I25 @SCM_LIB.SCM(SCH_1):PAGE23
   L30    1      1 Q_INDUCTOR_SMLF-BLM18BB470/500A   I168 @SCM_LIB.SCM(SCH_1):PAGE23

V_DACR_IO @SCM_LIB.SCM(SCH_1):V_DACR_IO
   R89    1      A Q_RES_0402LF-150,1%,1/16W,CHIPA    I65 @SCM_LIB.SCM(SCH_1):PAGE23
   U35    4    IO3 DT1240E04LP7-DT1240E-04LP-7,SMA   I155 @SCM_LIB.SCM(SCH_1):PAGE23
   U35    7    NC2 DT1240E04LP7-DT1240E-04LP-7,SMA   I155 @SCM_LIB.SCM(SCH_1):PAGE23
    J8    1      1 SCONN13_502280130CV01-SCONN13_A   I165 @SCM_LIB.SCM(SCH_1):PAGE23
   L30    2      2 Q_INDUCTOR_SMLF-BLM18BB470/500A   I168 @SCM_LIB.SCM(SCH_1):PAGE23
  C208    1      A Q_CAP_0402-22PF,50V,5%,NPO,TMPA   I169 @SCM_LIB.SCM(SCH_1):PAGE23

V_DACR_R @SCM_LIB.SCM(SCH_1):V_DACR_R
   R26    1      A Q_RES_0402LF-10,1%,1/16W,CHIP,A   I142 @SCM_LIB.SCM(SCH_1):PAGE15
   R25    1      A Q_RES_0402LF-150,1%,1/16W,CHIPA   I149 @SCM_LIB.SCM(SCH_1):PAGE15
    U5 AF21   DACR AST2600A3GP-AST2600A3-GP,SMLF,A   I350 @SCM_LIB.SCM(SCH_1):PAGE15

V_VGAHS @SCM_LIB.SCM(SCH_1):V_VGAHS
   R19    2      B Q_RES_0402LF-0,5%,1/16W,CHIP,CA   I141 @SCM_LIB.SCM(SCH_1):PAGE15
   U33    2      2 74HC1G126GW-74HC1G126GW,SMLF,IA    I32 @SCM_LIB.SCM(SCH_1):PAGE23

V_VGAHS_BUF @SCM_LIB.SCM(SCH_1):V_VGAHS_BUF
   R85    2      B Q_RES_0402LF-0,5%,1/16W,CHIP,CA    I60 @SCM_LIB.SCM(SCH_1):PAGE23
  C211    1      A Q_CAP_0402-10PF,50V,1%,NPO,TMPA    I67 @SCM_LIB.SCM(SCH_1):PAGE23
   U34    4    IO3 DT1240E04LP7-DT1240E-04LP-7,SMA   I156 @SCM_LIB.SCM(SCH_1):PAGE23
   U34    7    NC2 DT1240E04LP7-DT1240E-04LP-7,SMA   I156 @SCM_LIB.SCM(SCH_1):PAGE23
    J8    9      9 SCONN13_502280130CV01-SCONN13_A   I165 @SCM_LIB.SCM(SCH_1):PAGE23

V_VGAHS_BUF_R @SCM_LIB.SCM(SCH_1):V_VGAHS_BUF_R
   U33    4      4 74HC1G126GW-74HC1G126GW,SMLF,IA    I32 @SCM_LIB.SCM(SCH_1):PAGE23
   R85    1      A Q_RES_0402LF-0,5%,1/16W,CHIP,CA    I60 @SCM_LIB.SCM(SCH_1):PAGE23

V_VGAHS_R @SCM_LIB.SCM(SCH_1):V_VGAHS_R
   R19    1      A Q_RES_0402LF-0,5%,1/16W,CHIP,CA   I141 @SCM_LIB.SCM(SCH_1):PAGE15
    U5  B14 GPIOL6||VGAHS AST2600A3GP-AST2600A3-GP,SMLF,A   I350 @SCM_LIB.SCM(SCH_1):PAGE15

V_VGAVS @SCM_LIB.SCM(SCH_1):V_VGAVS
   R20    2      B Q_RES_0402LF-0,5%,1/16W,CHIP,CA   I140 @SCM_LIB.SCM(SCH_1):PAGE15
   U26    2      2 74HC1G126GW-74HC1G126GW,SMLF,IA    I33 @SCM_LIB.SCM(SCH_1):PAGE23

V_VGAVS_BUF @SCM_LIB.SCM(SCH_1):V_VGAVS_BUF
   R84    2      B Q_RES_0402LF-0,5%,1/16W,CHIP,CA    I61 @SCM_LIB.SCM(SCH_1):PAGE23
  C212    1      A Q_CAP_0402-10PF,50V,1%,NPO,TMPA    I77 @SCM_LIB.SCM(SCH_1):PAGE23
   U34    5    IO4 DT1240E04LP7-DT1240E-04LP-7,SMA   I156 @SCM_LIB.SCM(SCH_1):PAGE23
   U34    6    NC1 DT1240E04LP7-DT1240E-04LP-7,SMA   I156 @SCM_LIB.SCM(SCH_1):PAGE23
    J8    7      7 SCONN13_502280130CV01-SCONN13_A   I165 @SCM_LIB.SCM(SCH_1):PAGE23

V_VGAVS_BUF_R @SCM_LIB.SCM(SCH_1):V_VGAVS_BUF_R
   U26    4      4 74HC1G126GW-74HC1G126GW,SMLF,IA    I33 @SCM_LIB.SCM(SCH_1):PAGE23
   R84    1      A Q_RES_0402LF-0,5%,1/16W,CHIP,CA    I61 @SCM_LIB.SCM(SCH_1):PAGE23

V_VGAVS_R @SCM_LIB.SCM(SCH_1):V_VGAVS_R
   R20    1      A Q_RES_0402LF-0,5%,1/16W,CHIP,CA   I140 @SCM_LIB.SCM(SCH_1):PAGE15
    U5  C14 GPIOL7||VGAVS AST2600A3GP-AST2600A3-GP,SMLF,A   I350 @SCM_LIB.SCM(SCH_1):PAGE15

END GLOBAL SIGNAL CROSS REFERENCE
GLOBAL PART CROSS REFERENCE - 25-Aug-2023 AT 17:03:33

  C1 Q_CAP_C0603-4.7UF,25V,10%,X6S,A
     1 P1V2_AUX @SCM_LIB.SCM(SCH_1):P1V2_AUX     I4 @SCM_LIB.SCM(SCH_1):PAGE20
     2    GND @SCM_LIB.SCM(SCH_1):GND     I4 @SCM_LIB.SCM(SCH_1):PAGE20

  C2 Q_CAP_C0402-1UF,25V,10%,X6S,CHA
     1 P1V2_AUX @SCM_LIB.SCM(SCH_1):P1V2_AUX     I5 @SCM_LIB.SCM(SCH_1):PAGE20
     2    GND @SCM_LIB.SCM(SCH_1):GND     I5 @SCM_LIB.SCM(SCH_1):PAGE20

  C3 Q_CAP_C0402-1UF,25V,10%,X6S,CHA
     1 P1V2_AUX @SCM_LIB.SCM(SCH_1):P1V2_AUX     I6 @SCM_LIB.SCM(SCH_1):PAGE20
     2    GND @SCM_LIB.SCM(SCH_1):GND     I6 @SCM_LIB.SCM(SCH_1):PAGE20

  C4 Q_CAP_C0402-1UF,25V,10%,X6S,CHA
     1 P1V2_AUX @SCM_LIB.SCM(SCH_1):P1V2_AUX     I7 @SCM_LIB.SCM(SCH_1):PAGE20
     2    GND @SCM_LIB.SCM(SCH_1):GND     I7 @SCM_LIB.SCM(SCH_1):PAGE20

  C5 Q_CAP_C0402-1UF,25V,10%,X6S,CHA
     1 P1V2_AUX @SCM_LIB.SCM(SCH_1):P1V2_AUX    I23 @SCM_LIB.SCM(SCH_1):PAGE20
     2    GND @SCM_LIB.SCM(SCH_1):GND    I23 @SCM_LIB.SCM(SCH_1):PAGE20

  C6 Q_CAP_0402-0.1UF,25V,10%,X7R,CA
     1 P2V5_AUX @SCM_LIB.SCM(SCH_1):P2V5_AUX    I19 @SCM_LIB.SCM(SCH_1):PAGE20
     2    GND @SCM_LIB.SCM(SCH_1):GND    I19 @SCM_LIB.SCM(SCH_1):PAGE20

  C7 Q_CAP_0402-0.1UF,25V,10%,X7R,CA
     1 P1V2_AUX @SCM_LIB.SCM(SCH_1):P1V2_AUX    I24 @SCM_LIB.SCM(SCH_1):PAGE20
     2    GND @SCM_LIB.SCM(SCH_1):GND    I24 @SCM_LIB.SCM(SCH_1):PAGE20

  C8 Q_CAP_0402-0.1UF,25V,10%,X7R,CA
     1 P2V5_AUX @SCM_LIB.SCM(SCH_1):P2V5_AUX    I21 @SCM_LIB.SCM(SCH_1):PAGE20
     2    GND @SCM_LIB.SCM(SCH_1):GND    I21 @SCM_LIB.SCM(SCH_1):PAGE20

  C9 Q_CAP_0402-100PF,50V,5%,NPO,CHA
     1 P1V2_AUX @SCM_LIB.SCM(SCH_1):P1V2_AUX    I25 @SCM_LIB.SCM(SCH_1):PAGE20
     2    GND @SCM_LIB.SCM(SCH_1):GND    I25 @SCM_LIB.SCM(SCH_1):PAGE20

 C10 Q_CAP_0402-0.1UF,25V,10%,X7R,CA
     1 P0V6_DDR_VREF_AUX @SCM_LIB.SCM(SCH_1):P0V6_DDR_VREF_AUX    I85 @SCM_LIB.SCM(SCH_1):PAGE20
     2    GND @SCM_LIB.SCM(SCH_1):GND    I85 @SCM_LIB.SCM(SCH_1):PAGE20

 C11 Q_CAP_0402-0.1UF,25V,10%,X7R,CA
     1 P3V3_AUX @SCM_LIB.SCM(SCH_1):P3V3_AUX    I31 @SCM_LIB.SCM(SCH_1):PAGE31
     2    GND @SCM_LIB.SCM(SCH_1):GND    I31 @SCM_LIB.SCM(SCH_1):PAGE31

 C12 Q_CAP_0402-0.22UF,16V,10%,X7R,A
     1 M_BMC_DDR4_MCLK_C @SCM_LIB.SCM(SCH_1):M_BMC_DDR4_MCLK_C   I106 @SCM_LIB.SCM(SCH_1):PAGE20
     2    GND @SCM_LIB.SCM(SCH_1):GND   I106 @SCM_LIB.SCM(SCH_1):PAGE20

 C13 Q_CAP_0402-0.1UF,25V,10%,X7R,CA
     1 P1V2_AUX @SCM_LIB.SCM(SCH_1):P1V2_AUX   I186 @SCM_LIB.SCM(SCH_1):PAGE20
     2    GND @SCM_LIB.SCM(SCH_1):GND   I186 @SCM_LIB.SCM(SCH_1):PAGE20

 C14 Q_CAP_0402-0.1UF,25V,10%,X7R,CA
     1 P1V2_AUX @SCM_LIB.SCM(SCH_1):P1V2_AUX   I187 @SCM_LIB.SCM(SCH_1):PAGE20
     2    GND @SCM_LIB.SCM(SCH_1):GND   I187 @SCM_LIB.SCM(SCH_1):PAGE20

 C15 Q_CAP_C0402-10UF,6.3V,20%,X6S,A
     1 P1V2_AUX @SCM_LIB.SCM(SCH_1):P1V2_AUX   I134 @SCM_LIB.SCM(SCH_1):PAGE20
     2    GND @SCM_LIB.SCM(SCH_1):GND   I134 @SCM_LIB.SCM(SCH_1):PAGE20

 C16 Q_CAP_C0402-10UF,6.3V,20%,X6S,A
     1 P1V2_AUX @SCM_LIB.SCM(SCH_1):P1V2_AUX   I113 @SCM_LIB.SCM(SCH_1):PAGE20
     2    GND @SCM_LIB.SCM(SCH_1):GND   I113 @SCM_LIB.SCM(SCH_1):PAGE20

 C17 Q_CAP_0402-0.1UF,25V,10%,X7R,CA
     1 P1V2_AUX @SCM_LIB.SCM(SCH_1):P1V2_AUX   I190 @SCM_LIB.SCM(SCH_1):PAGE20
     2    GND @SCM_LIB.SCM(SCH_1):GND   I190 @SCM_LIB.SCM(SCH_1):PAGE20

 C18 Q_CAP_0402-0.1UF,25V,10%,X7R,CA
     1 P1V2_AUX @SCM_LIB.SCM(SCH_1):P1V2_AUX   I192 @SCM_LIB.SCM(SCH_1):PAGE20
     2    GND @SCM_LIB.SCM(SCH_1):GND   I192 @SCM_LIB.SCM(SCH_1):PAGE20

 C19 Q_CAP_0402-0.1UF,25V,10%,X7R,CA
     1 P3V3_AUX @SCM_LIB.SCM(SCH_1):P3V3_AUX   I261 @SCM_LIB.SCM(SCH_1):PAGE30
     2    GND @SCM_LIB.SCM(SCH_1):GND   I261 @SCM_LIB.SCM(SCH_1):PAGE30

 C20 Q_CAP_0402-0.1UF,25V,10%,X7R,CA
     1 P3V3_AUX @SCM_LIB.SCM(SCH_1):P3V3_AUX   I254 @SCM_LIB.SCM(SCH_1):PAGE30
     2    GND @SCM_LIB.SCM(SCH_1):GND   I254 @SCM_LIB.SCM(SCH_1):PAGE30

 C21 Q_CAP_C0402-0.01UF,50V,10%,EMPA
     1 P0V6_DDR_VREF_AUX @SCM_LIB.SCM(SCH_1):P0V6_DDR_VREF_AUX    I24 @SCM_LIB.SCM(SCH_1):PAGE12
     2    GND @SCM_LIB.SCM(SCH_1):GND    I24 @SCM_LIB.SCM(SCH_1):PAGE12

 C22 Q_CAP_0402-0.1UF,25V,10%,X7R,CA
     1 P0V6_DDR_VREF_AUX @SCM_LIB.SCM(SCH_1):P0V6_DDR_VREF_AUX   I448 @SCM_LIB.SCM(SCH_1):PAGE12
     2    GND @SCM_LIB.SCM(SCH_1):GND   I448 @SCM_LIB.SCM(SCH_1):PAGE12

 C23 Q_CAP_0402-0.1UF,25V,10%,X7R,CA
     1 P0V6_DDR_VREF_AUX @SCM_LIB.SCM(SCH_1):P0V6_DDR_VREF_AUX    I28 @SCM_LIB.SCM(SCH_1):PAGE12
     2    GND @SCM_LIB.SCM(SCH_1):GND    I28 @SCM_LIB.SCM(SCH_1):PAGE12

 C24 Q_CAP_0402-0.1UF,25V,10%,X7R,CA
     1 P2E_PCH_TX_DP @SCM_LIB.SCM(SCH_1):P2E_PCH_TX_DP   I152 @SCM_LIB.SCM(SCH_1):PAGE12
     2 P2E_PCH_TX_C_DP @SCM_LIB.SCM(SCH_1):P2E_PCH_TX_C_DP   I152 @SCM_LIB.SCM(SCH_1):PAGE12

 C25 Q_CAP_0402-0.1UF,25V,10%,X7R,CA
     1 P2E_PCH_TX_DN @SCM_LIB.SCM(SCH_1):P2E_PCH_TX_DN   I153 @SCM_LIB.SCM(SCH_1):PAGE12
     2 P2E_PCH_TX_C_DN @SCM_LIB.SCM(SCH_1):P2E_PCH_TX_C_DN   I153 @SCM_LIB.SCM(SCH_1):PAGE12

 C26 Q_CAP_0402-0.1UF,25V,10%,X7R,CA
     1 P3V3_AUX @SCM_LIB.SCM(SCH_1):P3V3_AUX   I398 @SCM_LIB.SCM(SCH_1):PAGE15
     2    GND @SCM_LIB.SCM(SCH_1):GND   I398 @SCM_LIB.SCM(SCH_1):PAGE15

 C27 Q_CAP_0402-0.1UF,25V,10%,X7R,CA
     1 LED_D22_R @SCM_LIB.SCM(SCH_1):LED_D22_R   I212 @SCM_LIB.SCM(SCH_1):PAGE50
     2    GND @SCM_LIB.SCM(SCH_1):GND   I212 @SCM_LIB.SCM(SCH_1):PAGE50

 C28 Q_CAP_C0402-1UF,25V,10%,EMPTY,A
     1 REAR_AC_PWR_BTN_N @SCM_LIB.SCM(SCH_1):REAR_AC_PWR_BTN_N   I236 @SCM_LIB.SCM(SCH_1):PAGE50
     2    GND @SCM_LIB.SCM(SCH_1):GND   I236 @SCM_LIB.SCM(SCH_1):PAGE50

 C29 Q_CAP_0402-0.1UF,25V,10%,EMPTYA
     1 P3V3_AUX @SCM_LIB.SCM(SCH_1):P3V3_AUX   I232 @SCM_LIB.SCM(SCH_1):PAGE50
     2    GND @SCM_LIB.SCM(SCH_1):GND   I232 @SCM_LIB.SCM(SCH_1):PAGE50

 C30 Q_CAP_C0402-1UF,25V,10%,X6S,CHA
     1 P3V3_P2V5_P1V8_RVDD @SCM_LIB.SCM(SCH_1):P3V3_P2V5_P1V8_RVDD    I29 @SCM_LIB.SCM(SCH_1):PAGE13
     2    GND @SCM_LIB.SCM(SCH_1):GND    I29 @SCM_LIB.SCM(SCH_1):PAGE13

 C31 Q_CAP_0402-0.1UF,25V,10%,X7R,CA
     1 P3V3_P2V5_P1V8_RVDD @SCM_LIB.SCM(SCH_1):P3V3_P2V5_P1V8_RVDD    I30 @SCM_LIB.SCM(SCH_1):PAGE13
     2    GND @SCM_LIB.SCM(SCH_1):GND    I30 @SCM_LIB.SCM(SCH_1):PAGE13

 C32 Q_CAP_C0402-1UF,25V,10%,X6S,CHA
     1 P3V3_P2V5_P1V8_RVDD @SCM_LIB.SCM(SCH_1):P3V3_P2V5_P1V8_RVDD    I31 @SCM_LIB.SCM(SCH_1):PAGE13
     2    GND @SCM_LIB.SCM(SCH_1):GND    I31 @SCM_LIB.SCM(SCH_1):PAGE13

 C33 Q_CAP_0402-0.1UF,25V,10%,X7R,CA
     1 P3V3_P2V5_P1V8_RVDD @SCM_LIB.SCM(SCH_1):P3V3_P2V5_P1V8_RVDD    I32 @SCM_LIB.SCM(SCH_1):PAGE13
     2    GND @SCM_LIB.SCM(SCH_1):GND    I32 @SCM_LIB.SCM(SCH_1):PAGE13

 C34 Q_CAP_0402-0.1UF,25V,10%,X7R,CA
     1 P3V3_AUX @SCM_LIB.SCM(SCH_1):P3V3_AUX    I42 @SCM_LIB.SCM(SCH_1):PAGE22
     2    GND @SCM_LIB.SCM(SCH_1):GND    I42 @SCM_LIB.SCM(SCH_1):PAGE22

 C35 Q_CAP_C0402-1UF,25V,10%,X6S,CHA
     1 P3V3_P1V8_SD1VDD @SCM_LIB.SCM(SCH_1):P3V3_P1V8_SD1VDD    I14 @SCM_LIB.SCM(SCH_1):PAGE15
     2    GND @SCM_LIB.SCM(SCH_1):GND    I14 @SCM_LIB.SCM(SCH_1):PAGE15

 C36 Q_CAP_0402-0.1UF,25V,10%,X7R,CA
     1 P3V3_P1V8_SD1VDD @SCM_LIB.SCM(SCH_1):P3V3_P1V8_SD1VDD    I16 @SCM_LIB.SCM(SCH_1):PAGE15
     2    GND @SCM_LIB.SCM(SCH_1):GND    I16 @SCM_LIB.SCM(SCH_1):PAGE15

 C37 Q_CAP_0402-0.1UF,25V,10%,X7R,CA
     1 P3V3_RGM @SCM_LIB.SCM(SCH_1):P3V3_RGM    I24 @SCM_LIB.SCM(SCH_1):PAGE15
     2    GND @SCM_LIB.SCM(SCH_1):GND    I24 @SCM_LIB.SCM(SCH_1):PAGE15

 C38 Q_CAP_C0402-1UF,25V,10%,X6S,CHA
     1 P3V3_P1V8_SD2VDD @SCM_LIB.SCM(SCH_1):P3V3_P1V8_SD2VDD    I36 @SCM_LIB.SCM(SCH_1):PAGE15
     2    GND @SCM_LIB.SCM(SCH_1):GND    I36 @SCM_LIB.SCM(SCH_1):PAGE15

 C39 Q_CAP_0402-0.1UF,25V,10%,X7R,CA
     1 P3V3_P1V8_SD2VDD @SCM_LIB.SCM(SCH_1):P3V3_P1V8_SD2VDD    I37 @SCM_LIB.SCM(SCH_1):PAGE15
     2    GND @SCM_LIB.SCM(SCH_1):GND    I37 @SCM_LIB.SCM(SCH_1):PAGE15

 C40 Q_CAP_C0603-4.7UF,25V,10%,X6S,A
     1 P1V8_BMC_USB2AV18 @SCM_LIB.SCM(SCH_1):P1V8_BMC_USB2AV18   I368 @SCM_LIB.SCM(SCH_1):PAGE15
     2    GND @SCM_LIB.SCM(SCH_1):GND   I368 @SCM_LIB.SCM(SCH_1):PAGE15

 C41 Q_CAP_0402-0.1UF,25V,10%,X7R,CA
     1 P1V8_BMC_USB2AV18 @SCM_LIB.SCM(SCH_1):P1V8_BMC_USB2AV18    I68 @SCM_LIB.SCM(SCH_1):PAGE15
     2    GND @SCM_LIB.SCM(SCH_1):GND    I68 @SCM_LIB.SCM(SCH_1):PAGE15

 C42 Q_CAP_C0603-22UF,6.3V,20%,X6S,A
     1 PVCCIO_PECI_BMC @SCM_LIB.SCM(SCH_1):PVCCIO_PECI_BMC   I117 @SCM_LIB.SCM(SCH_1):PAGE15
     2    GND @SCM_LIB.SCM(SCH_1):GND   I117 @SCM_LIB.SCM(SCH_1):PAGE15

 C43 Q_CAP_C0402-1UF,25V,10%,X6S,CHA
     1 PVCCIO_PECI_BMC @SCM_LIB.SCM(SCH_1):PVCCIO_PECI_BMC   I119 @SCM_LIB.SCM(SCH_1):PAGE15
     2    GND @SCM_LIB.SCM(SCH_1):GND   I119 @SCM_LIB.SCM(SCH_1):PAGE15

 C44 Q_CAP_C0603-4.7UF,25V,10%,X6S,A
     1 P3V3_BMC_USB2AV33 @SCM_LIB.SCM(SCH_1):P3V3_BMC_USB2AV33   I369 @SCM_LIB.SCM(SCH_1):PAGE15
     2    GND @SCM_LIB.SCM(SCH_1):GND   I369 @SCM_LIB.SCM(SCH_1):PAGE15

 C45 Q_CAP_0402-0.1UF,25V,10%,X7R,CA
     1 P3V3_BMC_USB2AV33 @SCM_LIB.SCM(SCH_1):P3V3_BMC_USB2AV33    I89 @SCM_LIB.SCM(SCH_1):PAGE15
     2    GND @SCM_LIB.SCM(SCH_1):GND    I89 @SCM_LIB.SCM(SCH_1):PAGE15

 C46 Q_CAP_C0402-1UF,25V,10%,X6S,CHA
     1 P1V8_STBY_AVDDPLL @SCM_LIB.SCM(SCH_1):P1V8_STBY_AVDDPLL   I122 @SCM_LIB.SCM(SCH_1):PAGE17
     2    GND @SCM_LIB.SCM(SCH_1):GND   I122 @SCM_LIB.SCM(SCH_1):PAGE17

 C47 Q_CAP_C0402-1UF,25V,10%,X6S,CHA
     1 P1V0_STBY_RC_VCC10A @SCM_LIB.SCM(SCH_1):P1V0_STBY_RC_VCC10A   I128 @SCM_LIB.SCM(SCH_1):PAGE17
     2    GND @SCM_LIB.SCM(SCH_1):GND   I128 @SCM_LIB.SCM(SCH_1):PAGE17

 C48 Q_CAP_C0402-1UF,25V,10%,X6S,CHA
     1 P3V3_STBY_DACAV33 @SCM_LIB.SCM(SCH_1):P3V3_STBY_DACAV33   I148 @SCM_LIB.SCM(SCH_1):PAGE17
     2    GND @SCM_LIB.SCM(SCH_1):GND   I148 @SCM_LIB.SCM(SCH_1):PAGE17

 C49 Q_CAP_0402-0.1UF,25V,10%,X7R,CA
     1 P1V8_STBY_AVDDPLL @SCM_LIB.SCM(SCH_1):P1V8_STBY_AVDDPLL   I118 @SCM_LIB.SCM(SCH_1):PAGE17
     2    GND @SCM_LIB.SCM(SCH_1):GND   I118 @SCM_LIB.SCM(SCH_1):PAGE17

 C50 Q_CAP_0402-0.1UF,25V,10%,X7R,CA
     1 P1V0_STBY_RC_VCC10A @SCM_LIB.SCM(SCH_1):P1V0_STBY_RC_VCC10A   I126 @SCM_LIB.SCM(SCH_1):PAGE17
     2    GND @SCM_LIB.SCM(SCH_1):GND   I126 @SCM_LIB.SCM(SCH_1):PAGE17

 C51 Q_CAP_0402-0.1UF,25V,10%,X7R,CA
     1 P3V3_STBY_DACAV33 @SCM_LIB.SCM(SCH_1):P3V3_STBY_DACAV33   I145 @SCM_LIB.SCM(SCH_1):PAGE17
     2    GND @SCM_LIB.SCM(SCH_1):GND   I145 @SCM_LIB.SCM(SCH_1):PAGE17

 C52 Q_CAP_C0402-1UF,25V,10%,X6S,CHA
     1 P1V0_STBY_PLAVDD @SCM_LIB.SCM(SCH_1):P1V0_STBY_PLAVDD    I31 @SCM_LIB.SCM(SCH_1):PAGE16
     2    GND @SCM_LIB.SCM(SCH_1):GND    I31 @SCM_LIB.SCM(SCH_1):PAGE16

 C53 Q_CAP_C0402-1UF,25V,10%,X6S,CHA
     1 P3V3_P1V8_I2C_I3C @SCM_LIB.SCM(SCH_1):P3V3_P1V8_I2C_I3C   I135 @SCM_LIB.SCM(SCH_1):PAGE17
     2    GND @SCM_LIB.SCM(SCH_1):GND   I135 @SCM_LIB.SCM(SCH_1):PAGE17

 C54 Q_CAP_0402-0.1UF,25V,10%,X7R,CA
     1 P1V0_STBY_PLAVDD @SCM_LIB.SCM(SCH_1):P1V0_STBY_PLAVDD    I32 @SCM_LIB.SCM(SCH_1):PAGE16
     2    GND @SCM_LIB.SCM(SCH_1):GND    I32 @SCM_LIB.SCM(SCH_1):PAGE16

 C55 Q_CAP_C0603-22UF,6.3V,20%,X6S,A
     1 P1V2_AUX @SCM_LIB.SCM(SCH_1):P1V2_AUX    I23 @SCM_LIB.SCM(SCH_1):PAGE16
     2    GND @SCM_LIB.SCM(SCH_1):GND    I23 @SCM_LIB.SCM(SCH_1):PAGE16

 C56 Q_CAP_C0402-1UF,25V,10%,X6S,CHA
     1 P1V0_STBY_PLAVDD @SCM_LIB.SCM(SCH_1):P1V0_STBY_PLAVDD    I33 @SCM_LIB.SCM(SCH_1):PAGE16
     2    GND @SCM_LIB.SCM(SCH_1):GND    I33 @SCM_LIB.SCM(SCH_1):PAGE16

 C57 Q_CAP_0402-0.1UF,25V,10%,X7R,CA
     1 P3V3_P1V8_I2C_I3C @SCM_LIB.SCM(SCH_1):P3V3_P1V8_I2C_I3C   I133 @SCM_LIB.SCM(SCH_1):PAGE17
     2    GND @SCM_LIB.SCM(SCH_1):GND   I133 @SCM_LIB.SCM(SCH_1):PAGE17

 C58 Q_CAP_C0402-1UF,25V,10%,X6S,CHA
     1 P1V2_AUX @SCM_LIB.SCM(SCH_1):P1V2_AUX    I52 @SCM_LIB.SCM(SCH_1):PAGE16
     2    GND @SCM_LIB.SCM(SCH_1):GND    I52 @SCM_LIB.SCM(SCH_1):PAGE16

 C59 Q_CAP_0402-0.1UF,25V,10%,X7R,CA
     1 P1V0_STBY_PLAVDD @SCM_LIB.SCM(SCH_1):P1V0_STBY_PLAVDD    I79 @SCM_LIB.SCM(SCH_1):PAGE16
     2    GND @SCM_LIB.SCM(SCH_1):GND    I79 @SCM_LIB.SCM(SCH_1):PAGE16

 C60 Q_CAP_C0402-1UF,25V,10%,X6S,CHA
     1 P3V3_STBY_PLLAHVDD @SCM_LIB.SCM(SCH_1):P3V3_STBY_PLLAHVDD   I141 @SCM_LIB.SCM(SCH_1):PAGE17
     2    GND @SCM_LIB.SCM(SCH_1):GND   I141 @SCM_LIB.SCM(SCH_1):PAGE17

 C61 Q_CAP_C0402-1UF,25V,10%,X6S,CHA
     1 P1V8_STBY_PE_VCC18A @SCM_LIB.SCM(SCH_1):P1V8_STBY_PE_VCC18A    I55 @SCM_LIB.SCM(SCH_1):PAGE16
     2    GND @SCM_LIB.SCM(SCH_1):GND    I55 @SCM_LIB.SCM(SCH_1):PAGE16

 C62 Q_CAP_C0402-1UF,25V,10%,X6S,CHA
     1 P1V2_AUX @SCM_LIB.SCM(SCH_1):P1V2_AUX    I53 @SCM_LIB.SCM(SCH_1):PAGE16
     2    GND @SCM_LIB.SCM(SCH_1):GND    I53 @SCM_LIB.SCM(SCH_1):PAGE16

 C63 Q_CAP_0402-2200PF,50V,10%,X7R,A
     1 P1V2_STBY_MVDD_CK @SCM_LIB.SCM(SCH_1):P1V2_STBY_MVDD_CK    I46 @SCM_LIB.SCM(SCH_1):PAGE16
     2    GND @SCM_LIB.SCM(SCH_1):GND    I46 @SCM_LIB.SCM(SCH_1):PAGE16

 C64 Q_CAP_C0402-1UF,25V,10%,X6S,CHA
     1 P1V0_STBY_PLAVDD @SCM_LIB.SCM(SCH_1):P1V0_STBY_PLAVDD    I81 @SCM_LIB.SCM(SCH_1):PAGE16
     2    GND @SCM_LIB.SCM(SCH_1):GND    I81 @SCM_LIB.SCM(SCH_1):PAGE16

 C65 Q_CAP_0402-0.1UF,25V,10%,X7R,CA
     1 P3V3_STBY_PLLAHVDD @SCM_LIB.SCM(SCH_1):P3V3_STBY_PLLAHVDD   I139 @SCM_LIB.SCM(SCH_1):PAGE17
     2    GND @SCM_LIB.SCM(SCH_1):GND   I139 @SCM_LIB.SCM(SCH_1):PAGE17

 C66 Q_CAP_0402-0.1UF,25V,10%,X7R,CA
     1 P1V2_AUX @SCM_LIB.SCM(SCH_1):P1V2_AUX    I54 @SCM_LIB.SCM(SCH_1):PAGE16
     2    GND @SCM_LIB.SCM(SCH_1):GND    I54 @SCM_LIB.SCM(SCH_1):PAGE16

 C67 Q_CAP_C0402-1UF,25V,10%,X6S,CHA
     1 P1V2_STBY_MVDD_CK @SCM_LIB.SCM(SCH_1):P1V2_STBY_MVDD_CK    I48 @SCM_LIB.SCM(SCH_1):PAGE16
     2    GND @SCM_LIB.SCM(SCH_1):GND    I48 @SCM_LIB.SCM(SCH_1):PAGE16

 C68 Q_CAP_0402-0.1UF,25V,10%,X7R,CA
     1 P1V0_STBY_PLAVDD @SCM_LIB.SCM(SCH_1):P1V0_STBY_PLAVDD    I82 @SCM_LIB.SCM(SCH_1):PAGE16
     2    GND @SCM_LIB.SCM(SCH_1):GND    I82 @SCM_LIB.SCM(SCH_1):PAGE16

 C69 Q_CAP_0402-0.1UF,25V,10%,X7R,CA
     1 P1V8_STBY_PE_VCC18A @SCM_LIB.SCM(SCH_1):P1V8_STBY_PE_VCC18A    I59 @SCM_LIB.SCM(SCH_1):PAGE16
     2    GND @SCM_LIB.SCM(SCH_1):GND    I59 @SCM_LIB.SCM(SCH_1):PAGE16

 C70 Q_CAP_0402-0.1UF,25V,10%,X7R,CA
     1 P1V2_AUX @SCM_LIB.SCM(SCH_1):P1V2_AUX    I57 @SCM_LIB.SCM(SCH_1):PAGE16
     2    GND @SCM_LIB.SCM(SCH_1):GND    I57 @SCM_LIB.SCM(SCH_1):PAGE16

 C71 Q_CAP_0402-0.1UF,25V,10%,X7R,CA
     1 P1V2_STBY_MVDD_CK @SCM_LIB.SCM(SCH_1):P1V2_STBY_MVDD_CK    I49 @SCM_LIB.SCM(SCH_1):PAGE16
     2    GND @SCM_LIB.SCM(SCH_1):GND    I49 @SCM_LIB.SCM(SCH_1):PAGE16

 C72 Q_CAP_0402-0.1UF,25V,10%,X7R,CA
     1 P1V2_AUX @SCM_LIB.SCM(SCH_1):P1V2_AUX    I58 @SCM_LIB.SCM(SCH_1):PAGE16
     2    GND @SCM_LIB.SCM(SCH_1):GND    I58 @SCM_LIB.SCM(SCH_1):PAGE16

 C73 Q_CAP_0402-0.1UF,25V,10%,X7R,CA
     1 P1V2_STBY_MVDD_CK @SCM_LIB.SCM(SCH_1):P1V2_STBY_MVDD_CK    I51 @SCM_LIB.SCM(SCH_1):PAGE16
     2    GND @SCM_LIB.SCM(SCH_1):GND    I51 @SCM_LIB.SCM(SCH_1):PAGE16

 C74 Q_CAP_0402-0.1UF,25V,10%,X7R,CA
     1 P1V2_AUX @SCM_LIB.SCM(SCH_1):P1V2_AUX    I66 @SCM_LIB.SCM(SCH_1):PAGE16
     2    GND @SCM_LIB.SCM(SCH_1):GND    I66 @SCM_LIB.SCM(SCH_1):PAGE16

 C75 Q_CAP_C0402-1UF,25V,10%,X6S,CHA
     1 A_BMC_ADCAV33 @SCM_LIB.SCM(SCH_1):A_BMC_ADCAV33    I93 @SCM_LIB.SCM(SCH_1):PAGE16
     2    GND @SCM_LIB.SCM(SCH_1):GND    I93 @SCM_LIB.SCM(SCH_1):PAGE16

 C76 Q_CAP_0402-0.1UF,25V,10%,X7R,CA
     1 P1V2_AUX @SCM_LIB.SCM(SCH_1):P1V2_AUX   I183 @SCM_LIB.SCM(SCH_1):PAGE16
     2    GND @SCM_LIB.SCM(SCH_1):GND   I183 @SCM_LIB.SCM(SCH_1):PAGE16

 C77 Q_CAP_0402-0.1UF,25V,10%,X7R,CA
     1 A_BMC_ADCAV33 @SCM_LIB.SCM(SCH_1):A_BMC_ADCAV33   I100 @SCM_LIB.SCM(SCH_1):PAGE16
     2    GND @SCM_LIB.SCM(SCH_1):GND   I100 @SCM_LIB.SCM(SCH_1):PAGE16

 C78 Q_CAP_C0402-1UF,25V,10%,X6S,CHA
     1 P1V0_STBY_PE_VCC10A @SCM_LIB.SCM(SCH_1):P1V0_STBY_PE_VCC10A   I160 @SCM_LIB.SCM(SCH_1):PAGE17
     2    GND @SCM_LIB.SCM(SCH_1):GND   I160 @SCM_LIB.SCM(SCH_1):PAGE17

 C79 Q_CAP_0402-0.1UF,25V,10%,X7R,CA
     1 P1V0_STBY_PE_VCC10A @SCM_LIB.SCM(SCH_1):P1V0_STBY_PE_VCC10A   I157 @SCM_LIB.SCM(SCH_1):PAGE17
     2    GND @SCM_LIB.SCM(SCH_1):GND   I157 @SCM_LIB.SCM(SCH_1):PAGE17

 C80 Q_CAP_C0402-1UF,25V,10%,X6S,CHA
     1 P1V8_STBY_RC_VCC18A @SCM_LIB.SCM(SCH_1):P1V8_STBY_RC_VCC18A   I153 @SCM_LIB.SCM(SCH_1):PAGE17
     2    GND @SCM_LIB.SCM(SCH_1):GND   I153 @SCM_LIB.SCM(SCH_1):PAGE17

 C81 Q_CAP_0402-0.1UF,25V,10%,X7R,CA
     1 P1V8_STBY_RC_VCC18A @SCM_LIB.SCM(SCH_1):P1V8_STBY_RC_VCC18A   I151 @SCM_LIB.SCM(SCH_1):PAGE17
     2    GND @SCM_LIB.SCM(SCH_1):GND   I151 @SCM_LIB.SCM(SCH_1):PAGE17

 C82 Q_CAP_0402-0.1UF,25V,10%,X7R,CA
     1 P1V2_AUX @SCM_LIB.SCM(SCH_1):P1V2_AUX   I180 @SCM_LIB.SCM(SCH_1):PAGE16
     2    GND @SCM_LIB.SCM(SCH_1):GND   I180 @SCM_LIB.SCM(SCH_1):PAGE16

 C83 Q_CAP_0402-0.1UF,25V,10%,X7R,CA
     1 P3V3_RTC_AUX @SCM_LIB.SCM(SCH_1):P3V3_RTC_AUX   I106 @SCM_LIB.SCM(SCH_1):PAGE16
     2    GND @SCM_LIB.SCM(SCH_1):GND   I106 @SCM_LIB.SCM(SCH_1):PAGE16

 C84 Q_CAP_0402-0.1UF,25V,10%,X7R,CA
     1 P1V2_AUX @SCM_LIB.SCM(SCH_1):P1V2_AUX   I179 @SCM_LIB.SCM(SCH_1):PAGE16
     2    GND @SCM_LIB.SCM(SCH_1):GND   I179 @SCM_LIB.SCM(SCH_1):PAGE16

 C85 Q_CAP_0402-0.1UF,25V,10%,X7R,CA
     1 P3V3_RGM @SCM_LIB.SCM(SCH_1):P3V3_RGM   I120 @SCM_LIB.SCM(SCH_1):PAGE16
     2    GND @SCM_LIB.SCM(SCH_1):GND   I120 @SCM_LIB.SCM(SCH_1):PAGE16

 C86 Q_CAP_0402-0.1UF,25V,10%,X7R,CA
     1 P1V0_AUX @SCM_LIB.SCM(SCH_1):P1V0_AUX   I149 @SCM_LIB.SCM(SCH_1):PAGE16
     2    GND @SCM_LIB.SCM(SCH_1):GND   I149 @SCM_LIB.SCM(SCH_1):PAGE16

 C87 Q_CAP_0402-0.1UF,25V,10%,X7R,CA
     1 P1V8_AUX @SCM_LIB.SCM(SCH_1):P1V8_AUX   I147 @SCM_LIB.SCM(SCH_1):PAGE16
     2    GND @SCM_LIB.SCM(SCH_1):GND   I147 @SCM_LIB.SCM(SCH_1):PAGE16

 C88 Q_CAP_0402-0.1UF,25V,10%,X7R,CA
     1 P3V3_AUX @SCM_LIB.SCM(SCH_1):P3V3_AUX   I123 @SCM_LIB.SCM(SCH_1):PAGE16
     2    GND @SCM_LIB.SCM(SCH_1):GND   I123 @SCM_LIB.SCM(SCH_1):PAGE16

 C89 Q_CAP_0402-0.1UF,25V,10%,X7R,CA
     1 P1V8_AUX @SCM_LIB.SCM(SCH_1):P1V8_AUX   I118 @SCM_LIB.SCM(SCH_1):PAGE16
     2    GND @SCM_LIB.SCM(SCH_1):GND   I118 @SCM_LIB.SCM(SCH_1):PAGE16

 C90 Q_CAP_C0402-1UF,25V,10%,X6S,CHA
     1 P1V0_STBY_DP_VCC10A @SCM_LIB.SCM(SCH_1):P1V0_STBY_DP_VCC10A   I173 @SCM_LIB.SCM(SCH_1):PAGE17
     2    GND @SCM_LIB.SCM(SCH_1):GND   I173 @SCM_LIB.SCM(SCH_1):PAGE17

 C91 Q_CAP_0402-0.1UF,25V,10%,X7R,CA
     1 P1V2_AUX @SCM_LIB.SCM(SCH_1):P1V2_AUX   I151 @SCM_LIB.SCM(SCH_1):PAGE16
     2    GND @SCM_LIB.SCM(SCH_1):GND   I151 @SCM_LIB.SCM(SCH_1):PAGE16

 C92 Q_CAP_0402-0.1UF,25V,10%,X7R,CA
     1 P1V0_AUX @SCM_LIB.SCM(SCH_1):P1V0_AUX   I150 @SCM_LIB.SCM(SCH_1):PAGE16
     2    GND @SCM_LIB.SCM(SCH_1):GND   I150 @SCM_LIB.SCM(SCH_1):PAGE16

 C93 Q_CAP_0402-0.1UF,25V,10%,X7R,CA
     1 P1V8_AUX @SCM_LIB.SCM(SCH_1):P1V8_AUX   I148 @SCM_LIB.SCM(SCH_1):PAGE16
     2    GND @SCM_LIB.SCM(SCH_1):GND   I148 @SCM_LIB.SCM(SCH_1):PAGE16

 C94 Q_CAP_0402-0.1UF,25V,10%,X7R,CA
     1 P3V3_AUX @SCM_LIB.SCM(SCH_1):P3V3_AUX   I124 @SCM_LIB.SCM(SCH_1):PAGE16
     2    GND @SCM_LIB.SCM(SCH_1):GND   I124 @SCM_LIB.SCM(SCH_1):PAGE16

 C95 Q_CAP_0402-0.1UF,25V,10%,X7R,CA
     1 P1V8_AUX @SCM_LIB.SCM(SCH_1):P1V8_AUX   I119 @SCM_LIB.SCM(SCH_1):PAGE16
     2    GND @SCM_LIB.SCM(SCH_1):GND   I119 @SCM_LIB.SCM(SCH_1):PAGE16

 C96 Q_CAP_0402-0.1UF,25V,10%,X7R,CA
     1 PGPPA_BMC_AUX @SCM_LIB.SCM(SCH_1):PGPPA_BMC_AUX   I178 @SCM_LIB.SCM(SCH_1):PAGE17
     2    GND @SCM_LIB.SCM(SCH_1):GND   I178 @SCM_LIB.SCM(SCH_1):PAGE17

 C97 Q_CAP_0402-0.1UF,25V,10%,X7R,CA
     1 P1V0_STBY_DP_VCC10A @SCM_LIB.SCM(SCH_1):P1V0_STBY_DP_VCC10A   I169 @SCM_LIB.SCM(SCH_1):PAGE17
     2    GND @SCM_LIB.SCM(SCH_1):GND   I169 @SCM_LIB.SCM(SCH_1):PAGE17

 C98 Q_CAP_0402-0.1UF,25V,10%,X7R,CA
     1 P1V2_AUX @SCM_LIB.SCM(SCH_1):P1V2_AUX   I163 @SCM_LIB.SCM(SCH_1):PAGE16
     2    GND @SCM_LIB.SCM(SCH_1):GND   I163 @SCM_LIB.SCM(SCH_1):PAGE16

 C99 Q_CAP_0402-0.1UF,25V,10%,X7R,CA
     1 P1V0_AUX @SCM_LIB.SCM(SCH_1):P1V0_AUX   I154 @SCM_LIB.SCM(SCH_1):PAGE16
     2    GND @SCM_LIB.SCM(SCH_1):GND   I154 @SCM_LIB.SCM(SCH_1):PAGE16

C100 Q_CAP_0402-0.1UF,25V,10%,X7R,CA
     1 P1V8_AUX @SCM_LIB.SCM(SCH_1):P1V8_AUX   I152 @SCM_LIB.SCM(SCH_1):PAGE16
     2    GND @SCM_LIB.SCM(SCH_1):GND   I152 @SCM_LIB.SCM(SCH_1):PAGE16

C101 Q_CAP_0402-0.1UF,25V,10%,X7R,CA
     1 P3V3_AUX @SCM_LIB.SCM(SCH_1):P3V3_AUX   I132 @SCM_LIB.SCM(SCH_1):PAGE16
     2    GND @SCM_LIB.SCM(SCH_1):GND   I132 @SCM_LIB.SCM(SCH_1):PAGE16

C102 Q_CAP_0402-0.1UF,25V,10%,X7R,CA
     1 P1V8_AUX @SCM_LIB.SCM(SCH_1):P1V8_AUX   I126 @SCM_LIB.SCM(SCH_1):PAGE16
     2    GND @SCM_LIB.SCM(SCH_1):GND   I126 @SCM_LIB.SCM(SCH_1):PAGE16

C103 Q_CAP_0402-0.1UF,25V,10%,X7R,CA
     1 P1V2_AUX @SCM_LIB.SCM(SCH_1):P1V2_AUX   I164 @SCM_LIB.SCM(SCH_1):PAGE16
     2    GND @SCM_LIB.SCM(SCH_1):GND   I164 @SCM_LIB.SCM(SCH_1):PAGE16

C104 Q_CAP_C0402-1UF,25V,10%,X6S,CHA
     1 P1V0_AUX @SCM_LIB.SCM(SCH_1):P1V0_AUX   I155 @SCM_LIB.SCM(SCH_1):PAGE16
     2    GND @SCM_LIB.SCM(SCH_1):GND   I155 @SCM_LIB.SCM(SCH_1):PAGE16

C105 Q_CAP_0402-0.1UF,25V,10%,X7R,CA
     1 P1V8_AUX @SCM_LIB.SCM(SCH_1):P1V8_AUX   I153 @SCM_LIB.SCM(SCH_1):PAGE16
     2    GND @SCM_LIB.SCM(SCH_1):GND   I153 @SCM_LIB.SCM(SCH_1):PAGE16

C106 Q_CAP_C0402-1UF,25V,10%,X6S,CHA
     1 P1V8_AUX @SCM_LIB.SCM(SCH_1):P1V8_AUX   I127 @SCM_LIB.SCM(SCH_1):PAGE16
     2    GND @SCM_LIB.SCM(SCH_1):GND   I127 @SCM_LIB.SCM(SCH_1):PAGE16

C107 Q_CAP_0402-0.1UF,25V,10%,X7R,CA
     1 P1V2_AUX @SCM_LIB.SCM(SCH_1):P1V2_AUX   I165 @SCM_LIB.SCM(SCH_1):PAGE16
     2    GND @SCM_LIB.SCM(SCH_1):GND   I165 @SCM_LIB.SCM(SCH_1):PAGE16

C108 Q_CAP_C0402-1UF,25V,10%,X6S,CHA
     1 P1V0_AUX @SCM_LIB.SCM(SCH_1):P1V0_AUX   I157 @SCM_LIB.SCM(SCH_1):PAGE16
     2    GND @SCM_LIB.SCM(SCH_1):GND   I157 @SCM_LIB.SCM(SCH_1):PAGE16

C109 Q_CAP_0402-0.1UF,25V,10%,X7R,CA
     1 P1V8_AUX @SCM_LIB.SCM(SCH_1):P1V8_AUX   I156 @SCM_LIB.SCM(SCH_1):PAGE16
     2    GND @SCM_LIB.SCM(SCH_1):GND   I156 @SCM_LIB.SCM(SCH_1):PAGE16

C110 Q_CAP_C0402-1UF,25V,10%,X6S,CHA
     1 P3V3_AUX @SCM_LIB.SCM(SCH_1):P3V3_AUX   I133 @SCM_LIB.SCM(SCH_1):PAGE16
     2    GND @SCM_LIB.SCM(SCH_1):GND   I133 @SCM_LIB.SCM(SCH_1):PAGE16

C111 Q_CAP_C0402-1UF,25V,10%,X6S,CHA
     1 P1V8_AUX @SCM_LIB.SCM(SCH_1):P1V8_AUX   I128 @SCM_LIB.SCM(SCH_1):PAGE16
     2    GND @SCM_LIB.SCM(SCH_1):GND   I128 @SCM_LIB.SCM(SCH_1):PAGE16

C112 Q_CAP_0402-0.1UF,25V,10%,X7R,CA
     1 P1V2_AUX @SCM_LIB.SCM(SCH_1):P1V2_AUX   I166 @SCM_LIB.SCM(SCH_1):PAGE16
     2    GND @SCM_LIB.SCM(SCH_1):GND   I166 @SCM_LIB.SCM(SCH_1):PAGE16

C113 Q_CAP_C0603-22UF,6.3V,20%,X6S,A
     1 P1V0_AUX @SCM_LIB.SCM(SCH_1):P1V0_AUX   I189 @SCM_LIB.SCM(SCH_1):PAGE16
     2    GND @SCM_LIB.SCM(SCH_1):GND   I189 @SCM_LIB.SCM(SCH_1):PAGE16

C114 Q_CAP_C0402-1UF,25V,10%,X6S,CHA
     1 P1V8_AUX @SCM_LIB.SCM(SCH_1):P1V8_AUX   I158 @SCM_LIB.SCM(SCH_1):PAGE16
     2    GND @SCM_LIB.SCM(SCH_1):GND   I158 @SCM_LIB.SCM(SCH_1):PAGE16

C115 Q_CAP_C0402-1UF,25V,10%,X6S,CHA
     1 P3V3_AUX @SCM_LIB.SCM(SCH_1):P3V3_AUX   I135 @SCM_LIB.SCM(SCH_1):PAGE16
     2    GND @SCM_LIB.SCM(SCH_1):GND   I135 @SCM_LIB.SCM(SCH_1):PAGE16

C116 Q_CAP_C0402-1UF,25V,10%,X6S,CHA
     1 P1V8_AUX @SCM_LIB.SCM(SCH_1):P1V8_AUX   I129 @SCM_LIB.SCM(SCH_1):PAGE16
     2    GND @SCM_LIB.SCM(SCH_1):GND   I129 @SCM_LIB.SCM(SCH_1):PAGE16

C117 Q_CAP_C0402-1UF,25V,10%,X6S,CHA
     1 P1V2_AUX @SCM_LIB.SCM(SCH_1):P1V2_AUX   I167 @SCM_LIB.SCM(SCH_1):PAGE16
     2    GND @SCM_LIB.SCM(SCH_1):GND   I167 @SCM_LIB.SCM(SCH_1):PAGE16

C118 Q_CAP_C0603-22UF,6.3V,20%,X6S,A
     1 P1V0_AUX @SCM_LIB.SCM(SCH_1):P1V0_AUX   I162 @SCM_LIB.SCM(SCH_1):PAGE16
     2    GND @SCM_LIB.SCM(SCH_1):GND   I162 @SCM_LIB.SCM(SCH_1):PAGE16

C119 Q_CAP_C0402-1UF,25V,10%,X6S,CHA
     1 P1V8_AUX @SCM_LIB.SCM(SCH_1):P1V8_AUX   I159 @SCM_LIB.SCM(SCH_1):PAGE16
     2    GND @SCM_LIB.SCM(SCH_1):GND   I159 @SCM_LIB.SCM(SCH_1):PAGE16

C120 Q_CAP_C0603-22UF,6.3V,20%,X6S,A
     1 P3V3_AUX @SCM_LIB.SCM(SCH_1):P3V3_AUX   I190 @SCM_LIB.SCM(SCH_1):PAGE16
     2    GND @SCM_LIB.SCM(SCH_1):GND   I190 @SCM_LIB.SCM(SCH_1):PAGE16

C121 Q_CAP_C0603-22UF,6.3V,20%,X6S,A
     1 P1V8_AUX @SCM_LIB.SCM(SCH_1):P1V8_AUX   I131 @SCM_LIB.SCM(SCH_1):PAGE16
     2    GND @SCM_LIB.SCM(SCH_1):GND   I131 @SCM_LIB.SCM(SCH_1):PAGE16

C122 Q_CAP_C0402-1UF,25V,10%,X6S,CHA
     1 P1V2_AUX @SCM_LIB.SCM(SCH_1):P1V2_AUX   I168 @SCM_LIB.SCM(SCH_1):PAGE16
     2    GND @SCM_LIB.SCM(SCH_1):GND   I168 @SCM_LIB.SCM(SCH_1):PAGE16

C123 Q_CAP_C0603-22UF,6.3V,20%,X6S,A
     1 P1V0_AUX @SCM_LIB.SCM(SCH_1):P1V0_AUX   I171 @SCM_LIB.SCM(SCH_1):PAGE16
     2    GND @SCM_LIB.SCM(SCH_1):GND   I171 @SCM_LIB.SCM(SCH_1):PAGE16

C124 Q_CAP_C0603-22UF,6.3V,20%,X6S,A
     1 P1V8_AUX @SCM_LIB.SCM(SCH_1):P1V8_AUX   I169 @SCM_LIB.SCM(SCH_1):PAGE16
     2    GND @SCM_LIB.SCM(SCH_1):GND   I169 @SCM_LIB.SCM(SCH_1):PAGE16

C125 Q_CAP_C0603-22UF,6.3V,20%,X6S,A
     1 P3V3_AUX @SCM_LIB.SCM(SCH_1):P3V3_AUX   I191 @SCM_LIB.SCM(SCH_1):PAGE16
     2    GND @SCM_LIB.SCM(SCH_1):GND   I191 @SCM_LIB.SCM(SCH_1):PAGE16

C126 Q_CAP_C0603-22UF,6.3V,20%,X6S,A
     1 P1V8_AUX @SCM_LIB.SCM(SCH_1):P1V8_AUX   I143 @SCM_LIB.SCM(SCH_1):PAGE16
     2    GND @SCM_LIB.SCM(SCH_1):GND   I143 @SCM_LIB.SCM(SCH_1):PAGE16

C127 Q_CAP_C0402-1UF,25V,10%,X6S,CHA
     1 P1V2_AUX @SCM_LIB.SCM(SCH_1):P1V2_AUX   I173 @SCM_LIB.SCM(SCH_1):PAGE16
     2    GND @SCM_LIB.SCM(SCH_1):GND   I173 @SCM_LIB.SCM(SCH_1):PAGE16

C128 Q_CAP_C0402-1UF,25V,10%,X6S,CHA
     1 P1V8_STBY_DP_VCC18A @SCM_LIB.SCM(SCH_1):P1V8_STBY_DP_VCC18A   I165 @SCM_LIB.SCM(SCH_1):PAGE17
     2    GND @SCM_LIB.SCM(SCH_1):GND   I165 @SCM_LIB.SCM(SCH_1):PAGE17

C129 Q_CAP_C0402-1UF,25V,10%,X6S,CHA
     1 P1V2_AUX @SCM_LIB.SCM(SCH_1):P1V2_AUX   I174 @SCM_LIB.SCM(SCH_1):PAGE16
     2    GND @SCM_LIB.SCM(SCH_1):GND   I174 @SCM_LIB.SCM(SCH_1):PAGE16

C130 Q_CAP_0402-0.1UF,25V,10%,X7R,CA
     1 P1V8_STBY_DP_VCC18A @SCM_LIB.SCM(SCH_1):P1V8_STBY_DP_VCC18A   I163 @SCM_LIB.SCM(SCH_1):PAGE17
     2    GND @SCM_LIB.SCM(SCH_1):GND   I163 @SCM_LIB.SCM(SCH_1):PAGE17

C131 Q_CAP_C0603-22UF,6.3V,20%,X6S,A
     1 P1V2_AUX @SCM_LIB.SCM(SCH_1):P1V2_AUX   I192 @SCM_LIB.SCM(SCH_1):PAGE16
     2    GND @SCM_LIB.SCM(SCH_1):GND   I192 @SCM_LIB.SCM(SCH_1):PAGE16

C132 Q_CAP_C0603-22UF,6.3V,20%,X6S,A
     1 P1V2_AUX @SCM_LIB.SCM(SCH_1):P1V2_AUX   I193 @SCM_LIB.SCM(SCH_1):PAGE16
     2    GND @SCM_LIB.SCM(SCH_1):GND   I193 @SCM_LIB.SCM(SCH_1):PAGE16

C133 Q_CAP_C0402-0.01UF,50V,10%,X7RA
     1    GND @SCM_LIB.SCM(SCH_1):GND   I104 @SCM_LIB.SCM(SCH_1):PAGE17
     2 A_BMC_ADCVREFN1 @SCM_LIB.SCM(SCH_1):A_BMC_ADCVREFN1   I104 @SCM_LIB.SCM(SCH_1):PAGE17

C134 Q_CAP_C0402-0.01UF,50V,10%,X7RA
     1    GND @SCM_LIB.SCM(SCH_1):GND   I106 @SCM_LIB.SCM(SCH_1):PAGE17
     2 A_BMC_ADCVREFN0 @SCM_LIB.SCM(SCH_1):A_BMC_ADCVREFN0   I106 @SCM_LIB.SCM(SCH_1):PAGE17

C135 Q_CAP_C0402-0.01UF,50V,10%,X7RA
     1    GND @SCM_LIB.SCM(SCH_1):GND   I107 @SCM_LIB.SCM(SCH_1):PAGE17
     2 A_BMC_ADCVREFP1 @SCM_LIB.SCM(SCH_1):A_BMC_ADCVREFP1   I107 @SCM_LIB.SCM(SCH_1):PAGE17

C136 Q_CAP_C0402-0.01UF,50V,10%,X7RA
     1    GND @SCM_LIB.SCM(SCH_1):GND   I110 @SCM_LIB.SCM(SCH_1):PAGE17
     2 A_BMC_ADCVREFP0 @SCM_LIB.SCM(SCH_1):A_BMC_ADCVREFP0   I110 @SCM_LIB.SCM(SCH_1):PAGE17

C137 Q_CAP_C0402-0.01UF,50V,10%,X7RA
     1 A_BMC_ADCVREFN1 @SCM_LIB.SCM(SCH_1):A_BMC_ADCVREFN1   I108 @SCM_LIB.SCM(SCH_1):PAGE17
     2 A_BMC_ADCVREFP1 @SCM_LIB.SCM(SCH_1):A_BMC_ADCVREFP1   I108 @SCM_LIB.SCM(SCH_1):PAGE17

C138 Q_CAP_C0402-0.01UF,50V,10%,X7RA
     1 A_BMC_ADCVREFN0 @SCM_LIB.SCM(SCH_1):A_BMC_ADCVREFN0   I109 @SCM_LIB.SCM(SCH_1):PAGE17
     2 A_BMC_ADCVREFP0 @SCM_LIB.SCM(SCH_1):A_BMC_ADCVREFP0   I109 @SCM_LIB.SCM(SCH_1):PAGE17

C139 Q_CAP_0402-0.1UF,25V,10%,X7R,CA
     1 P1V2_P1V0_I3C_VDDL1 @SCM_LIB.SCM(SCH_1):P1V2_P1V0_I3C_VDDL1    I98 @SCM_LIB.SCM(SCH_1):PAGE17
     2    GND @SCM_LIB.SCM(SCH_1):GND    I98 @SCM_LIB.SCM(SCH_1):PAGE17

C140 Q_CAP_0402-0.1UF,25V,10%,X7R,CA
     1 P1V2_P1V0_I3C_VDDL2 @SCM_LIB.SCM(SCH_1):P1V2_P1V0_I3C_VDDL2    I97 @SCM_LIB.SCM(SCH_1):PAGE17
     2    GND @SCM_LIB.SCM(SCH_1):GND    I97 @SCM_LIB.SCM(SCH_1):PAGE17

C141 Q_CAP_0402-0.1UF,25V,10%,X7R,CA
     1 VCCIO1 @SCM_LIB.SCM(SCH_1):VCCIO1    I83 @SCM_LIB.SCM(SCH_1):PAGE41
     2    GND @SCM_LIB.SCM(SCH_1):GND    I83 @SCM_LIB.SCM(SCH_1):PAGE41

C142 Q_CAP_C0805-10UF,25V,10%,X6S,CA
     1 P1V8_AUX @SCM_LIB.SCM(SCH_1):P1V8_AUX   I104 @SCM_LIB.SCM(SCH_1):PAGE54
     2    GND @SCM_LIB.SCM(SCH_1):GND   I104 @SCM_LIB.SCM(SCH_1):PAGE54

C143 Q_CAP_C0402-10UF,6.3V,20%,X6S,A
     1 P3V3_AUX @SCM_LIB.SCM(SCH_1):P3V3_AUX   I108 @SCM_LIB.SCM(SCH_1):PAGE46
     2    GND @SCM_LIB.SCM(SCH_1):GND   I108 @SCM_LIB.SCM(SCH_1):PAGE46

C144 Q_CAP_0402-0.1UF,25V,10%,X7R,CA
     1 P3V3_AUX @SCM_LIB.SCM(SCH_1):P3V3_AUX   I102 @SCM_LIB.SCM(SCH_1):PAGE46
     2    GND @SCM_LIB.SCM(SCH_1):GND   I102 @SCM_LIB.SCM(SCH_1):PAGE46

C145 Q_CAP_C0402-1UF,25V,10%,X6S,CHA
     1 P3V3_AUX @SCM_LIB.SCM(SCH_1):P3V3_AUX    I99 @SCM_LIB.SCM(SCH_1):PAGE41
     2    GND @SCM_LIB.SCM(SCH_1):GND    I99 @SCM_LIB.SCM(SCH_1):PAGE41

C146 Q_CAP_0402-0.1UF,25V,10%,X7R,CA
     1 P3V3_AUX @SCM_LIB.SCM(SCH_1):P3V3_AUX   I292 @SCM_LIB.SCM(SCH_1):PAGE44
     2    GND @SCM_LIB.SCM(SCH_1):GND   I292 @SCM_LIB.SCM(SCH_1):PAGE44

C147 Q_CAP_0402-0.1UF,25V,10%,EMPTYA
     1 P3V3_AUX @SCM_LIB.SCM(SCH_1):P3V3_AUX    I17 @SCM_LIB.SCM(SCH_1):PAGE22
     2    GND @SCM_LIB.SCM(SCH_1):GND    I17 @SCM_LIB.SCM(SCH_1):PAGE22

C148 Q_CAP_0402-0.1UF,25V,10%,X7R,CA
     1 P3V3_AUX @SCM_LIB.SCM(SCH_1):P3V3_AUX   I172 @SCM_LIB.SCM(SCH_1):PAGE29
     2    GND @SCM_LIB.SCM(SCH_1):GND   I172 @SCM_LIB.SCM(SCH_1):PAGE29

C149 Q_CAP_0402-0.1UF,25V,10%,X7R,CA
     1 P3V3_AUX @SCM_LIB.SCM(SCH_1):P3V3_AUX   I161 @SCM_LIB.SCM(SCH_1):PAGE29
     2    GND @SCM_LIB.SCM(SCH_1):GND   I161 @SCM_LIB.SCM(SCH_1):PAGE29

C150 Q_CAP_C0402-0.001UF,50V,10%,EMA
     1 PWRGD_P5V_AUX_R @SCM_LIB.SCM(SCH_1):PWRGD_P5V_AUX_R    I49 @SCM_LIB.SCM(SCH_1):PAGE51
     2    GND @SCM_LIB.SCM(SCH_1):GND    I49 @SCM_LIB.SCM(SCH_1):PAGE51

C151 Q_CAP_C0402-0.001UF,50V,10%,EMA
     1 PWRGD_P3V3_AUX_R @SCM_LIB.SCM(SCH_1):PWRGD_P3V3_AUX_R    I93 @SCM_LIB.SCM(SCH_1):PAGE52
     2    GND @SCM_LIB.SCM(SCH_1):GND    I93 @SCM_LIB.SCM(SCH_1):PAGE52

C152 Q_CAP_0402-0.1UF,25V,10%,X7R,CA
     1 VCCIO3 @SCM_LIB.SCM(SCH_1):VCCIO3    I88 @SCM_LIB.SCM(SCH_1):PAGE41
     2    GND @SCM_LIB.SCM(SCH_1):GND    I88 @SCM_LIB.SCM(SCH_1):PAGE41

C153 Q_CAP_C0402-0.001UF,50V,10%,EMA
     1 PWRGD_P2V5_AUX_R @SCM_LIB.SCM(SCH_1):PWRGD_P2V5_AUX_R    I64 @SCM_LIB.SCM(SCH_1):PAGE53
     2    GND @SCM_LIB.SCM(SCH_1):GND    I64 @SCM_LIB.SCM(SCH_1):PAGE53

C154 Q_CAP_C0402-0.001UF,50V,10%,EMA
     1 PWRGD_P1V8_AUX_R @SCM_LIB.SCM(SCH_1):PWRGD_P1V8_AUX_R   I100 @SCM_LIB.SCM(SCH_1):PAGE54
     2    GND @SCM_LIB.SCM(SCH_1):GND   I100 @SCM_LIB.SCM(SCH_1):PAGE54

C155 Q_CAP_C0402-0.001UF,50V,10%,EMA
     1 PWRGD_P1V2_AUX_R @SCM_LIB.SCM(SCH_1):PWRGD_P1V2_AUX_R    I52 @SCM_LIB.SCM(SCH_1):PAGE55
     2    GND @SCM_LIB.SCM(SCH_1):GND    I52 @SCM_LIB.SCM(SCH_1):PAGE55

C156 Q_CAP_C0402-0.001UF,50V,10%,EMA
     1 PWRGD_P1V0_AUX_R @SCM_LIB.SCM(SCH_1):PWRGD_P1V0_AUX_R    I51 @SCM_LIB.SCM(SCH_1):PAGE56
     2    GND @SCM_LIB.SCM(SCH_1):GND    I51 @SCM_LIB.SCM(SCH_1):PAGE56

C157 Q_CAP_0402-0.1UF,25V,10%,X7R,CA
     1 P3V3_AUX @SCM_LIB.SCM(SCH_1):P3V3_AUX   I181 @SCM_LIB.SCM(SCH_1):PAGE28
     2    GND @SCM_LIB.SCM(SCH_1):GND   I181 @SCM_LIB.SCM(SCH_1):PAGE28

C158 Q_CAP_0402-0.1UF,25V,10%,X7R,CA
     1 P3V3_AUX @SCM_LIB.SCM(SCH_1):P3V3_AUX   I101 @SCM_LIB.SCM(SCH_1):PAGE28
     2    GND @SCM_LIB.SCM(SCH_1):GND   I101 @SCM_LIB.SCM(SCH_1):PAGE28

C159 Q_CAP_0402-0.1UF,25V,10%,X7R,CA
     1 P3V3_AUX @SCM_LIB.SCM(SCH_1):P3V3_AUX    I98 @SCM_LIB.SCM(SCH_1):PAGE28
     2    GND @SCM_LIB.SCM(SCH_1):GND    I98 @SCM_LIB.SCM(SCH_1):PAGE28

C160 Q_CAP_0402-0.1UF,25V,10%,X7R,CA
     1 VCCIO5 @SCM_LIB.SCM(SCH_1):VCCIO5    I89 @SCM_LIB.SCM(SCH_1):PAGE41
     2    GND @SCM_LIB.SCM(SCH_1):GND    I89 @SCM_LIB.SCM(SCH_1):PAGE41

C161 Q_CAP_C0402-1UF,25V,10%,X6S,CHA
     1 RST_BMC_SELF_HW_D @SCM_LIB.SCM(SCH_1):RST_BMC_SELF_HW_D    I23 @SCM_LIB.SCM(SCH_1):PAGE22
     2 RST_BMC_SELF_HW_D_C @SCM_LIB.SCM(SCH_1):RST_BMC_SELF_HW_D_C    I23 @SCM_LIB.SCM(SCH_1):PAGE22

C162 Q_CAP_0402-0.1UF,25V,10%,X7R,CA
     1 VCCIO4 @SCM_LIB.SCM(SCH_1):VCCIO4    I91 @SCM_LIB.SCM(SCH_1):PAGE41
     2    GND @SCM_LIB.SCM(SCH_1):GND    I91 @SCM_LIB.SCM(SCH_1):PAGE41

C163 Q_CAP_C0603-10UF,16V,20%,X6S,CA
     1 PVCCA_AUX_PLD @SCM_LIB.SCM(SCH_1):PVCCA_AUX_PLD   I122 @SCM_LIB.SCM(SCH_1):PAGE41
     2    GND @SCM_LIB.SCM(SCH_1):GND   I122 @SCM_LIB.SCM(SCH_1):PAGE41

C164 Q_CAP_C0402-1UF,25V,10%,X6S,CHA
     1 VCCIO1 @SCM_LIB.SCM(SCH_1):VCCIO1    I92 @SCM_LIB.SCM(SCH_1):PAGE41
     2    GND @SCM_LIB.SCM(SCH_1):GND    I92 @SCM_LIB.SCM(SCH_1):PAGE41

C165 Q_CAP_C0402-1UF,25V,10%,X6S,CHA
     1 VCCIO2 @SCM_LIB.SCM(SCH_1):VCCIO2    I93 @SCM_LIB.SCM(SCH_1):PAGE41
     2    GND @SCM_LIB.SCM(SCH_1):GND    I93 @SCM_LIB.SCM(SCH_1):PAGE41

C166 Q_CAP_C0402-1UF,25V,10%,X6S,CHA
     1 VCCIO0 @SCM_LIB.SCM(SCH_1):VCCIO0     I8 @SCM_LIB.SCM(SCH_1):PAGE41
     2    GND @SCM_LIB.SCM(SCH_1):GND     I8 @SCM_LIB.SCM(SCH_1):PAGE41

C167 Q_CAP_0402-0.1UF,25V,10%,X7R,CA
     1 VCCIO1 @SCM_LIB.SCM(SCH_1):VCCIO1    I80 @SCM_LIB.SCM(SCH_1):PAGE41
     2    GND @SCM_LIB.SCM(SCH_1):GND    I80 @SCM_LIB.SCM(SCH_1):PAGE41

C168 Q_CAP_0402-0.1UF,25V,10%,X7R,CA
     1 P0V6_DDR_VREF_AUX @SCM_LIB.SCM(SCH_1):P0V6_DDR_VREF_AUX    I32 @SCM_LIB.SCM(SCH_1):PAGE20
     2    GND @SCM_LIB.SCM(SCH_1):GND    I32 @SCM_LIB.SCM(SCH_1):PAGE20

C169 Q_CAP_C0402-0.01UF,50V,10%,EMPA
     1 P1V2_AUX @SCM_LIB.SCM(SCH_1):P1V2_AUX    I34 @SCM_LIB.SCM(SCH_1):PAGE20
     2 P0V6_DDR_VREF_AUX @SCM_LIB.SCM(SCH_1):P0V6_DDR_VREF_AUX    I34 @SCM_LIB.SCM(SCH_1):PAGE20

C170 Q_CAP_C0402-0.01UF,50V,10%,X7RA
     1 P0V6_DDR_VREF_AUX @SCM_LIB.SCM(SCH_1):P0V6_DDR_VREF_AUX    I33 @SCM_LIB.SCM(SCH_1):PAGE20
     2    GND @SCM_LIB.SCM(SCH_1):GND    I33 @SCM_LIB.SCM(SCH_1):PAGE20

C171 Q_CAP_C0805-22UF,10V,20%,X6S,CA
     1 P5V_AUX @SCM_LIB.SCM(SCH_1):P5V_AUX    I38 @SCM_LIB.SCM(SCH_1):PAGE28
     2    GND @SCM_LIB.SCM(SCH_1):GND    I38 @SCM_LIB.SCM(SCH_1):PAGE28

C172 Q_CAP_0402-470PF,50V,10%,X7R,TA
     1 P5V_AUX @SCM_LIB.SCM(SCH_1):P5V_AUX    I35 @SCM_LIB.SCM(SCH_1):PAGE28
     2    GND @SCM_LIB.SCM(SCH_1):GND    I35 @SCM_LIB.SCM(SCH_1):PAGE28

C173 Q_CAP_0402-2200PF,50V,10%,X7R,A
     1 RST_BMC_SELF_HW_D_C @SCM_LIB.SCM(SCH_1):RST_BMC_SELF_HW_D_C   I107 @SCM_LIB.SCM(SCH_1):PAGE22
     2    GND @SCM_LIB.SCM(SCH_1):GND   I107 @SCM_LIB.SCM(SCH_1):PAGE22

C174 Q_CAP_0402-0.1UF,25V,10%,EMPTYA
     1 P3V_BAT_R @SCM_LIB.SCM(SCH_1):P3V_BAT_R   I503 @SCM_LIB.SCM(SCH_1):PAGE10
     2    GND @SCM_LIB.SCM(SCH_1):GND   I503 @SCM_LIB.SCM(SCH_1):PAGE10

C175 Q_CAP_0402-0.1UF,25V,10%,X7R,CA
     1 P3V3_AUX @SCM_LIB.SCM(SCH_1):P3V3_AUX   I151 @SCM_LIB.SCM(SCH_1):PAGE30
     2    GND @SCM_LIB.SCM(SCH_1):GND   I151 @SCM_LIB.SCM(SCH_1):PAGE30

C176 Q_CAP_C0402-1UF,25V,10%,X6S,CHA
     1 PVCCA_AUX_PLD @SCM_LIB.SCM(SCH_1):PVCCA_AUX_PLD   I108 @SCM_LIB.SCM(SCH_1):PAGE41
     2    GND @SCM_LIB.SCM(SCH_1):GND   I108 @SCM_LIB.SCM(SCH_1):PAGE41

C177 Q_CAP_C1206-47UF,6.3V,20%,X6S,A
     1 P5V_USB_REAR @SCM_LIB.SCM(SCH_1):P5V_USB_REAR   I219 @SCM_LIB.SCM(SCH_1):PAGE29
     2    GND @SCM_LIB.SCM(SCH_1):GND   I219 @SCM_LIB.SCM(SCH_1):PAGE29

C178 Q_CAP_0402-470PF,50V,10%,X7R,TA
     1 P5V_USB_REAR @SCM_LIB.SCM(SCH_1):P5V_USB_REAR   I194 @SCM_LIB.SCM(SCH_1):PAGE29
     2    GND @SCM_LIB.SCM(SCH_1):GND   I194 @SCM_LIB.SCM(SCH_1):PAGE29

C179 Q_CAP_0402-470PF,50V,10%,X7R,TA
     1 P5V_USB_REAR @SCM_LIB.SCM(SCH_1):P5V_USB_REAR   I193 @SCM_LIB.SCM(SCH_1):PAGE29
     2    GND @SCM_LIB.SCM(SCH_1):GND   I193 @SCM_LIB.SCM(SCH_1):PAGE29

C180 Q_CAP_0402-0.1UF,25V,10%,X7R,CA
     1 P3V3_LDO @SCM_LIB.SCM(SCH_1):P3V3_LDO   I440 @SCM_LIB.SCM(SCH_1):PAGE13
     2    GND @SCM_LIB.SCM(SCH_1):GND   I440 @SCM_LIB.SCM(SCH_1):PAGE13

C181 Q_CAP_0402-0.1UF,25V,10%,X7R,CA
     1 REAR_AC_PWR_BTN @SCM_LIB.SCM(SCH_1):REAR_AC_PWR_BTN   I246 @SCM_LIB.SCM(SCH_1):PAGE50
     2    GND @SCM_LIB.SCM(SCH_1):GND   I246 @SCM_LIB.SCM(SCH_1):PAGE50

C187 Q_CAP_0402-0.1UF,25V,10%,X7R,CA
     1 VCCIO2 @SCM_LIB.SCM(SCH_1):VCCIO2    I84 @SCM_LIB.SCM(SCH_1):PAGE41
     2    GND @SCM_LIB.SCM(SCH_1):GND    I84 @SCM_LIB.SCM(SCH_1):PAGE41

C188 Q_CAP_0402-0.1UF,25V,10%,X7R,CA
     1 VCCIO2 @SCM_LIB.SCM(SCH_1):VCCIO2    I86 @SCM_LIB.SCM(SCH_1):PAGE41
     2    GND @SCM_LIB.SCM(SCH_1):GND    I86 @SCM_LIB.SCM(SCH_1):PAGE41

C189 Q_CAP_0402-0.1UF,25V,10%,X7R,CA
     1 VCCIO0 @SCM_LIB.SCM(SCH_1):VCCIO0    I78 @SCM_LIB.SCM(SCH_1):PAGE41
     2    GND @SCM_LIB.SCM(SCH_1):GND    I78 @SCM_LIB.SCM(SCH_1):PAGE41

C190 Q_CAP_0402-0.1UF,25V,10%,X7R,CA
     1 PVCCA_AUX_PLD @SCM_LIB.SCM(SCH_1):PVCCA_AUX_PLD   I116 @SCM_LIB.SCM(SCH_1):PAGE41
     2    GND @SCM_LIB.SCM(SCH_1):GND   I116 @SCM_LIB.SCM(SCH_1):PAGE41

C191 Q_CAP_0402-0.1UF,25V,10%,X7R,CA
     1 P3V3_AUX @SCM_LIB.SCM(SCH_1):P3V3_AUX    I54 @SCM_LIB.SCM(SCH_1):PAGE26
     2    GND @SCM_LIB.SCM(SCH_1):GND    I54 @SCM_LIB.SCM(SCH_1):PAGE26

C192 Q_CAP_0402-0.1UF,25V,10%,X7R,CA
     1 P3V3_AUX @SCM_LIB.SCM(SCH_1):P3V3_AUX    I17 @SCM_LIB.SCM(SCH_1):PAGE26
     2    GND @SCM_LIB.SCM(SCH_1):GND    I17 @SCM_LIB.SCM(SCH_1):PAGE26

C193 Q_CAP_0402-0.1UF,25V,10%,X7R,CA
     1 PVCCA_AUX_PLD @SCM_LIB.SCM(SCH_1):PVCCA_AUX_PLD   I109 @SCM_LIB.SCM(SCH_1):PAGE41
     2    GND @SCM_LIB.SCM(SCH_1):GND   I109 @SCM_LIB.SCM(SCH_1):PAGE41

C194 Q_CAP_C0603-10UF,16V,20%,X6S,CA
     1 P3V3_AUX @SCM_LIB.SCM(SCH_1):P3V3_AUX   I101 @SCM_LIB.SCM(SCH_1):PAGE41
     2    GND @SCM_LIB.SCM(SCH_1):GND   I101 @SCM_LIB.SCM(SCH_1):PAGE41

C195 Q_CAP_C0402-1UF,25V,10%,X6S,CHA
     1 VCCIO4 @SCM_LIB.SCM(SCH_1):VCCIO4    I96 @SCM_LIB.SCM(SCH_1):PAGE41
     2    GND @SCM_LIB.SCM(SCH_1):GND    I96 @SCM_LIB.SCM(SCH_1):PAGE41

C196 Q_CAP_C0402-1UF,25V,10%,X6S,CHA
     1 P3V3_RTC_AUX @SCM_LIB.SCM(SCH_1):P3V3_RTC_AUX   I165 @SCM_LIB.SCM(SCH_1):PAGE50
     2    GND @SCM_LIB.SCM(SCH_1):GND   I165 @SCM_LIB.SCM(SCH_1):PAGE50

C197 Q_CAP_0402-0.1UF,25V,10%,X7R,CA
     1 HDD_LED_P5V_AUX @SCM_LIB.SCM(SCH_1):HDD_LED_P5V_AUX    I45 @SCM_LIB.SCM(SCH_1):PAGE49
     2    GND @SCM_LIB.SCM(SCH_1):GND    I45 @SCM_LIB.SCM(SCH_1):PAGE49

C198 Q_CAP_C0402-1UF,25V,10%,X6S,CHA
     1 REAR_PWR_BTN_N @SCM_LIB.SCM(SCH_1):REAR_PWR_BTN_N    I44 @SCM_LIB.SCM(SCH_1):PAGE50
     2    GND @SCM_LIB.SCM(SCH_1):GND    I44 @SCM_LIB.SCM(SCH_1):PAGE50

C199 Q_CAP_C0402-1UF,25V,10%,X6S,CHA
     1 REAR_ID_RST_BTN_N @SCM_LIB.SCM(SCH_1):REAR_ID_RST_BTN_N    I55 @SCM_LIB.SCM(SCH_1):PAGE50
     2    GND @SCM_LIB.SCM(SCH_1):GND    I55 @SCM_LIB.SCM(SCH_1):PAGE50

C200 Q_CAP_0402-0.1UF,25V,10%,X7R,CA
     1 P3V3_AUX @SCM_LIB.SCM(SCH_1):P3V3_AUX    I43 @SCM_LIB.SCM(SCH_1):PAGE50
     2    GND @SCM_LIB.SCM(SCH_1):GND    I43 @SCM_LIB.SCM(SCH_1):PAGE50

C201 Q_CAP_0402-0.1UF,25V,10%,X7R,CA
     1 P3V3_AUX @SCM_LIB.SCM(SCH_1):P3V3_AUX    I51 @SCM_LIB.SCM(SCH_1):PAGE50
     2    GND @SCM_LIB.SCM(SCH_1):GND    I51 @SCM_LIB.SCM(SCH_1):PAGE50

C202 Q_CAP_0402-0.1UF,25V,10%,X7R,CA
     1 P5V_AUX @SCM_LIB.SCM(SCH_1):P5V_AUX    I11 @SCM_LIB.SCM(SCH_1):PAGE23
     2    GND @SCM_LIB.SCM(SCH_1):GND    I11 @SCM_LIB.SCM(SCH_1):PAGE23

C203 Q_CAP_0402-0.1UF,25V,10%,X7R,CA
     1 P5V_AUX @SCM_LIB.SCM(SCH_1):P5V_AUX    I12 @SCM_LIB.SCM(SCH_1):PAGE23
     2    GND @SCM_LIB.SCM(SCH_1):GND    I12 @SCM_LIB.SCM(SCH_1):PAGE23

C204 Q_CAP_0603-1UF,16V,10%,EMPTY,TA
     1 CRT_VCC5 @SCM_LIB.SCM(SCH_1):CRT_VCC5    I45 @SCM_LIB.SCM(SCH_1):PAGE23
     2    GND @SCM_LIB.SCM(SCH_1):GND    I45 @SCM_LIB.SCM(SCH_1):PAGE23

C205 Q_CAP_0402-15PF,50V,5%,C0G,CH0A
     1 V_DACR @SCM_LIB.SCM(SCH_1):V_DACR    I25 @SCM_LIB.SCM(SCH_1):PAGE23
     2    GND @SCM_LIB.SCM(SCH_1):GND    I25 @SCM_LIB.SCM(SCH_1):PAGE23

C206 Q_CAP_0402-15PF,50V,5%,C0G,CH0A
     1 V_DACG @SCM_LIB.SCM(SCH_1):V_DACG    I26 @SCM_LIB.SCM(SCH_1):PAGE23
     2    GND @SCM_LIB.SCM(SCH_1):GND    I26 @SCM_LIB.SCM(SCH_1):PAGE23

C207 Q_CAP_0402-15PF,50V,5%,C0G,CH0A
     1 V_DACB @SCM_LIB.SCM(SCH_1):V_DACB    I29 @SCM_LIB.SCM(SCH_1):PAGE23
     2    GND @SCM_LIB.SCM(SCH_1):GND    I29 @SCM_LIB.SCM(SCH_1):PAGE23

C208 Q_CAP_0402-22PF,50V,5%,NPO,TMPA
     1 V_DACR_IO @SCM_LIB.SCM(SCH_1):V_DACR_IO   I169 @SCM_LIB.SCM(SCH_1):PAGE23
     2    GND @SCM_LIB.SCM(SCH_1):GND   I169 @SCM_LIB.SCM(SCH_1):PAGE23

C209 Q_CAP_0402-18PF,50V,5%,C0G,CH0A
     1 V_DACG_IO @SCM_LIB.SCM(SCH_1):V_DACG_IO    I54 @SCM_LIB.SCM(SCH_1):PAGE23
     2    GND @SCM_LIB.SCM(SCH_1):GND    I54 @SCM_LIB.SCM(SCH_1):PAGE23

C210 Q_CAP_0402-22PF,50V,5%,NPO,TMPA
     1 V_DACB_IO @SCM_LIB.SCM(SCH_1):V_DACB_IO   I170 @SCM_LIB.SCM(SCH_1):PAGE23
     2    GND @SCM_LIB.SCM(SCH_1):GND   I170 @SCM_LIB.SCM(SCH_1):PAGE23

C211 Q_CAP_0402-10PF,50V,1%,NPO,TMPA
     1 V_VGAHS_BUF @SCM_LIB.SCM(SCH_1):V_VGAHS_BUF    I67 @SCM_LIB.SCM(SCH_1):PAGE23
     2    GND @SCM_LIB.SCM(SCH_1):GND    I67 @SCM_LIB.SCM(SCH_1):PAGE23

C212 Q_CAP_0402-10PF,50V,1%,NPO,TMPA
     1 V_VGAVS_BUF @SCM_LIB.SCM(SCH_1):V_VGAVS_BUF    I77 @SCM_LIB.SCM(SCH_1):PAGE23
     2    GND @SCM_LIB.SCM(SCH_1):GND    I77 @SCM_LIB.SCM(SCH_1):PAGE23

C213 Q_CAP_0402-100PF,50V,5%,EMPTY,A
     1 V_BMC_LS_DDC_SDA_R @SCM_LIB.SCM(SCH_1):V_BMC_LS_DDC_SDA_R    I83 @SCM_LIB.SCM(SCH_1):PAGE23
     2    GND @SCM_LIB.SCM(SCH_1):GND    I83 @SCM_LIB.SCM(SCH_1):PAGE23

C214 Q_CAP_0402-100PF,50V,5%,EMPTY,A
     1 V_BMC_LS_DDC_SCL_R @SCM_LIB.SCM(SCH_1):V_BMC_LS_DDC_SCL_R    I84 @SCM_LIB.SCM(SCH_1):PAGE23
     2    GND @SCM_LIB.SCM(SCH_1):GND    I84 @SCM_LIB.SCM(SCH_1):PAGE23

C215 Q_CAP_C0402-10UF,6.3V,20%,X6S,A
     1  J7_P1 @SCM_LIB.SCM(SCH_1):J7_P1    I22 @SCM_LIB.SCM(SCH_1):PAGE32
     2    GND @SCM_LIB.SCM(SCH_1):GND    I22 @SCM_LIB.SCM(SCH_1):PAGE32

C216 Q_CAP_C0402-1UF,25V,10%,X6S,CHA
     1 VCCIO3 @SCM_LIB.SCM(SCH_1):VCCIO3    I94 @SCM_LIB.SCM(SCH_1):PAGE41
     2    GND @SCM_LIB.SCM(SCH_1):GND    I94 @SCM_LIB.SCM(SCH_1):PAGE41

C217 Q_CAP_0402-0.1UF,25V,10%,X7R,CA
     1  J7_P1 @SCM_LIB.SCM(SCH_1):J7_P1    I21 @SCM_LIB.SCM(SCH_1):PAGE32
     2    GND @SCM_LIB.SCM(SCH_1):GND    I21 @SCM_LIB.SCM(SCH_1):PAGE32

C218 Q_CAP_C0402-1UF,25V,10%,X6S,CHA
     1 VCCIO5 @SCM_LIB.SCM(SCH_1):VCCIO5    I95 @SCM_LIB.SCM(SCH_1):PAGE41
     2    GND @SCM_LIB.SCM(SCH_1):GND    I95 @SCM_LIB.SCM(SCH_1):PAGE41

C219 Q_CAP_0402-0.1UF,25V,10%,X7R,CA
     1 P3V3_AUX @SCM_LIB.SCM(SCH_1):P3V3_AUX   I150 @SCM_LIB.SCM(SCH_1):PAGE29
     2    GND @SCM_LIB.SCM(SCH_1):GND   I150 @SCM_LIB.SCM(SCH_1):PAGE29

C220 Q_CAP_0402-0.1UF,25V,10%,X7R,CA
     1 VCCIO4 @SCM_LIB.SCM(SCH_1):VCCIO4    I90 @SCM_LIB.SCM(SCH_1):PAGE41
     2    GND @SCM_LIB.SCM(SCH_1):GND    I90 @SCM_LIB.SCM(SCH_1):PAGE41

C221 Q_CAP_0402-0.1UF,25V,10%,X7R,CA
     1 P1V2_AUX @SCM_LIB.SCM(SCH_1):P1V2_AUX   I199 @SCM_LIB.SCM(SCH_1):PAGE20
     2    GND @SCM_LIB.SCM(SCH_1):GND   I199 @SCM_LIB.SCM(SCH_1):PAGE20

C222 Q_CAP_0402-0.1UF,25V,10%,X7R,CA
     1 P1V2_AUX @SCM_LIB.SCM(SCH_1):P1V2_AUX   I198 @SCM_LIB.SCM(SCH_1):PAGE20
     2    GND @SCM_LIB.SCM(SCH_1):GND   I198 @SCM_LIB.SCM(SCH_1):PAGE20

C223 Q_CAP_C0402-4700P,25V,10%,EMPTA
     1 RST_BMC_SRST_BUF_R_N @SCM_LIB.SCM(SCH_1):RST_BMC_SRST_BUF_R_N    I46 @SCM_LIB.SCM(SCH_1):PAGE22
     2    GND @SCM_LIB.SCM(SCH_1):GND    I46 @SCM_LIB.SCM(SCH_1):PAGE22

C224 Q_CAP_C0402-10UF,6.3V,20%,X6S,A
     1 PGPPA_BMC_AUX @SCM_LIB.SCM(SCH_1):PGPPA_BMC_AUX   I180 @SCM_LIB.SCM(SCH_1):PAGE17
     2    GND @SCM_LIB.SCM(SCH_1):GND   I180 @SCM_LIB.SCM(SCH_1):PAGE17

C225 Q_CAP_0402-0.1UF,25V,10%,X7R,CA
     1 P1V2_AUX @SCM_LIB.SCM(SCH_1):P1V2_AUX   I197 @SCM_LIB.SCM(SCH_1):PAGE20
     2    GND @SCM_LIB.SCM(SCH_1):GND   I197 @SCM_LIB.SCM(SCH_1):PAGE20

C226 Q_CAP_C0402-1UF,25V,10%,X6S,CHA
     1 P12V_AUX @SCM_LIB.SCM(SCH_1):P12V_AUX    I60 @SCM_LIB.SCM(SCH_1):PAGE51
     2    GND @SCM_LIB.SCM(SCH_1):GND    I60 @SCM_LIB.SCM(SCH_1):PAGE51

C227 Q_CAP_C0402-2.2UF,10V,10%,X6S,A
     1 P3V3_LDO @SCM_LIB.SCM(SCH_1):P3V3_LDO    I68 @SCM_LIB.SCM(SCH_1):PAGE51
     2    GND @SCM_LIB.SCM(SCH_1):GND    I68 @SCM_LIB.SCM(SCH_1):PAGE51

C228 Q_CAP_0402-0.1UF,25V,10%,EMPTYA
     1 P3V3_AUX @SCM_LIB.SCM(SCH_1):P3V3_AUX    I21 @SCM_LIB.SCM(SCH_1):PAGE21
     2    GND @SCM_LIB.SCM(SCH_1):GND    I21 @SCM_LIB.SCM(SCH_1):PAGE21

C229 Q_CAP_0402-0.22UF,16V,10%,EMPTA
     1 M_BMC_DDR4_MCLK_C @SCM_LIB.SCM(SCH_1):M_BMC_DDR4_MCLK_C   I107 @SCM_LIB.SCM(SCH_1):PAGE20
     2 P1V2_AUX @SCM_LIB.SCM(SCH_1):P1V2_AUX   I107 @SCM_LIB.SCM(SCH_1):PAGE20

C231 Q_CAP_0402-0.1UF,25V,10%,X7R,CA
     1 P3V3_AUX @SCM_LIB.SCM(SCH_1):P3V3_AUX    I45 @SCM_LIB.SCM(SCH_1):PAGE31
     2    GND @SCM_LIB.SCM(SCH_1):GND    I45 @SCM_LIB.SCM(SCH_1):PAGE31

C234 Q_CAP_C0603-22UF,10V,20%,EMPTYA
     1 P3V3_AUX @SCM_LIB.SCM(SCH_1):P3V3_AUX    I81 @SCM_LIB.SCM(SCH_1):PAGE21
     2    GND @SCM_LIB.SCM(SCH_1):GND    I81 @SCM_LIB.SCM(SCH_1):PAGE21

C235 Q_CAP_0402-0.1UF,25V,10%,EMPTYA
     1 P3V3_AUX @SCM_LIB.SCM(SCH_1):P3V3_AUX    I80 @SCM_LIB.SCM(SCH_1):PAGE21
     2    GND @SCM_LIB.SCM(SCH_1):GND    I80 @SCM_LIB.SCM(SCH_1):PAGE21

C236 Q_CAP_0402-0.1UF,25V,10%,X7R,CA
     1 P3V3_AUX @SCM_LIB.SCM(SCH_1):P3V3_AUX   I148 @SCM_LIB.SCM(SCH_1):PAGE29
     2    GND @SCM_LIB.SCM(SCH_1):GND   I148 @SCM_LIB.SCM(SCH_1):PAGE29

C237 Q_CAP_0402-0.1UF,25V,10%,X7R,CA
     1 P3V3_AUX @SCM_LIB.SCM(SCH_1):P3V3_AUX   I146 @SCM_LIB.SCM(SCH_1):PAGE29
     2    GND @SCM_LIB.SCM(SCH_1):GND   I146 @SCM_LIB.SCM(SCH_1):PAGE29

C238 Q_CAP_0402-0.1UF,25V,10%,EMPTYA
     1 USB3_FPNL_TXP @SCM_LIB.SCM(SCH_1):USB3_FPNL_TXP   I142 @SCM_LIB.SCM(SCH_1):PAGE29
     2 USB3_01_TXP_C @SCM_LIB.SCM(SCH_1):USB3_01_TXP_C   I142 @SCM_LIB.SCM(SCH_1):PAGE29

C239 Q_CAP_0402-0.1UF,25V,10%,EMPTYA
     1 USB3_FPNL_TXN @SCM_LIB.SCM(SCH_1):USB3_FPNL_TXN   I143 @SCM_LIB.SCM(SCH_1):PAGE29
     2 USB3_01_TXN_C @SCM_LIB.SCM(SCH_1):USB3_01_TXN_C   I143 @SCM_LIB.SCM(SCH_1):PAGE29

C240 Q_CAP_0402-0.1UF,25V,10%,X7R,CA
     1 P3V3_AUX @SCM_LIB.SCM(SCH_1):P3V3_AUX    I63 @SCM_LIB.SCM(SCH_1):PAGE52
     2    GND @SCM_LIB.SCM(SCH_1):GND    I63 @SCM_LIB.SCM(SCH_1):PAGE52

C241 Q_CAP_0402-0.1UF,25V,10%,X7R,CA
     1 P12V_AUX @SCM_LIB.SCM(SCH_1):P12V_AUX    I52 @SCM_LIB.SCM(SCH_1):PAGE51
     2    GND @SCM_LIB.SCM(SCH_1):GND    I52 @SCM_LIB.SCM(SCH_1):PAGE51

C242 Q_CAP_0402-0.1UF,25V,10%,X7R,CA
     1 VCCIO0 @SCM_LIB.SCM(SCH_1):VCCIO0     I1 @SCM_LIB.SCM(SCH_1):PAGE41
     2    GND @SCM_LIB.SCM(SCH_1):GND     I1 @SCM_LIB.SCM(SCH_1):PAGE41

C243 Q_CAP_0402-0.1UF,25V,10%,X7R,CA
     1 VCCIO1 @SCM_LIB.SCM(SCH_1):VCCIO1    I81 @SCM_LIB.SCM(SCH_1):PAGE41
     2    GND @SCM_LIB.SCM(SCH_1):GND    I81 @SCM_LIB.SCM(SCH_1):PAGE41

C244 Q_CAP_C0402-1UF,25V,10%,X6S,CHA
     1 P3V3_AUX @SCM_LIB.SCM(SCH_1):P3V3_AUX    I42 @SCM_LIB.SCM(SCH_1):PAGE45
     2    GND @SCM_LIB.SCM(SCH_1):GND    I42 @SCM_LIB.SCM(SCH_1):PAGE45

C245 Q_CAP_0402-0.1UF,25V,10%,X7R,CA
     1 VCCIO2 @SCM_LIB.SCM(SCH_1):VCCIO2    I85 @SCM_LIB.SCM(SCH_1):PAGE41
     2    GND @SCM_LIB.SCM(SCH_1):GND    I85 @SCM_LIB.SCM(SCH_1):PAGE41

C246 Q_CAP_C0402-0.01UF,50V,10%,X7RA
     1 P3V3_AUX @SCM_LIB.SCM(SCH_1):P3V3_AUX    I45 @SCM_LIB.SCM(SCH_1):PAGE45
     2    GND @SCM_LIB.SCM(SCH_1):GND    I45 @SCM_LIB.SCM(SCH_1):PAGE45

C247 Q_CAP_0402-0.1UF,25V,10%,X7R,CA
     1 VCCIO0 @SCM_LIB.SCM(SCH_1):VCCIO0    I77 @SCM_LIB.SCM(SCH_1):PAGE41
     2    GND @SCM_LIB.SCM(SCH_1):GND    I77 @SCM_LIB.SCM(SCH_1):PAGE41

C248 Q_CAP_C0402-10UF,6.3V,20%,X6S,A
     1 P3V3_AUX @SCM_LIB.SCM(SCH_1):P3V3_AUX    I69 @SCM_LIB.SCM(SCH_1):PAGE46
     2    GND @SCM_LIB.SCM(SCH_1):GND    I69 @SCM_LIB.SCM(SCH_1):PAGE46

C249 Q_CAP_0402-0.1UF,25V,10%,X7R,CA
     1 P3V3_AUX @SCM_LIB.SCM(SCH_1):P3V3_AUX    I67 @SCM_LIB.SCM(SCH_1):PAGE46
     2    GND @SCM_LIB.SCM(SCH_1):GND    I67 @SCM_LIB.SCM(SCH_1):PAGE46

C250 Q_CAP_0402-0.1UF,25V,10%,X7R,CA
     1 PVCCA_AUX_PLD @SCM_LIB.SCM(SCH_1):PVCCA_AUX_PLD   I115 @SCM_LIB.SCM(SCH_1):PAGE41
     2    GND @SCM_LIB.SCM(SCH_1):GND   I115 @SCM_LIB.SCM(SCH_1):PAGE41

C251 Q_CAP_0402-0.1UF,25V,10%,X7R,CA
     1 P3V3_RGM @SCM_LIB.SCM(SCH_1):P3V3_RGM    I66 @SCM_LIB.SCM(SCH_1):PAGE52
     2    GND @SCM_LIB.SCM(SCH_1):GND    I66 @SCM_LIB.SCM(SCH_1):PAGE52

C252 Q_CAP_C0402-1UF,25V,10%,EMPTY,A
     1 PWRGD_P3V3_RGM_R @SCM_LIB.SCM(SCH_1):PWRGD_P3V3_RGM_R    I73 @SCM_LIB.SCM(SCH_1):PAGE52
     2    GND @SCM_LIB.SCM(SCH_1):GND    I73 @SCM_LIB.SCM(SCH_1):PAGE52

C253 Q_CAP_0402-0.1UF,25V,10%,X7R,CA
     1 P3V3_AUX @SCM_LIB.SCM(SCH_1):P3V3_AUX    I57 @SCM_LIB.SCM(SCH_1):PAGE22
     2    GND @SCM_LIB.SCM(SCH_1):GND    I57 @SCM_LIB.SCM(SCH_1):PAGE22

C254 Q_CAP_0402-0.1UF,25V,10%,X7R,CA
     1 VCCIO1 @SCM_LIB.SCM(SCH_1):VCCIO1    I82 @SCM_LIB.SCM(SCH_1):PAGE41
     2    GND @SCM_LIB.SCM(SCH_1):GND    I82 @SCM_LIB.SCM(SCH_1):PAGE41

C255 Q_CAP_0402-0.1UF,25V,10%,X7R,CA
     1 P3V3_AUX @SCM_LIB.SCM(SCH_1):P3V3_AUX   I278 @SCM_LIB.SCM(SCH_1):PAGE44
     2    GND @SCM_LIB.SCM(SCH_1):GND   I278 @SCM_LIB.SCM(SCH_1):PAGE44

C256 Q_CAP_C0402-1UF,25V,10%,X6S,CHA
     1 PVCCIO_AUX_PLD @SCM_LIB.SCM(SCH_1):PVCCIO_AUX_PLD   I140 @SCM_LIB.SCM(SCH_1):PAGE34
     2    GND @SCM_LIB.SCM(SCH_1):GND   I140 @SCM_LIB.SCM(SCH_1):PAGE34

C257 Q_CAP_0402-0.1UF,25V,10%,X7R,CA
     1 PVCCIO_AUX_PLD @SCM_LIB.SCM(SCH_1):PVCCIO_AUX_PLD   I144 @SCM_LIB.SCM(SCH_1):PAGE34
     2    GND @SCM_LIB.SCM(SCH_1):GND   I144 @SCM_LIB.SCM(SCH_1):PAGE34

C260 Q_CAP_0402-0.1UF,25V,10%,X7R,CA
     1 VCCIO2 @SCM_LIB.SCM(SCH_1):VCCIO2    I87 @SCM_LIB.SCM(SCH_1):PAGE41
     2    GND @SCM_LIB.SCM(SCH_1):GND    I87 @SCM_LIB.SCM(SCH_1):PAGE41

C261 Q_CAP_0402-0.1UF,25V,10%,X7R,CA
     1 VCCIO0 @SCM_LIB.SCM(SCH_1):VCCIO0    I79 @SCM_LIB.SCM(SCH_1):PAGE41
     2    GND @SCM_LIB.SCM(SCH_1):GND    I79 @SCM_LIB.SCM(SCH_1):PAGE41

C262 Q_CAP_0402-0.1UF,25V,10%,X7R,CA
     1 P12V_AUX @SCM_LIB.SCM(SCH_1):P12V_AUX   I101 @SCM_LIB.SCM(SCH_1):PAGE52
     2    GND @SCM_LIB.SCM(SCH_1):GND   I101 @SCM_LIB.SCM(SCH_1):PAGE52

C263 Q_CAP_0402-0.1UF,25V,10%,X7R,CA
     1 PVCCA_AUX_PLD @SCM_LIB.SCM(SCH_1):PVCCA_AUX_PLD   I117 @SCM_LIB.SCM(SCH_1):PAGE41
     2    GND @SCM_LIB.SCM(SCH_1):GND   I117 @SCM_LIB.SCM(SCH_1):PAGE41

C264 Q_CAP_0402-0.1UF,25V,10%,X7R,CA
     1 U43_CT @SCM_LIB.SCM(SCH_1):U43_CT    I59 @SCM_LIB.SCM(SCH_1):PAGE22
     2    GND @SCM_LIB.SCM(SCH_1):GND    I59 @SCM_LIB.SCM(SCH_1):PAGE22

C265 Q_CAP_C0805-22UF,16V,20%,X6S,CA
     1 SW_P3V3_AUX_FLT @SCM_LIB.SCM(SCH_1):SW_P3V3_AUX_FLT   I102 @SCM_LIB.SCM(SCH_1):PAGE52
     2    GND @SCM_LIB.SCM(SCH_1):GND   I102 @SCM_LIB.SCM(SCH_1):PAGE52

C266 Q_CAP_0402-0.1UF,25V,10%,X7R,CA
     1 PVCCA_AUX_PLD @SCM_LIB.SCM(SCH_1):PVCCA_AUX_PLD   I119 @SCM_LIB.SCM(SCH_1):PAGE41
     2    GND @SCM_LIB.SCM(SCH_1):GND   I119 @SCM_LIB.SCM(SCH_1):PAGE41

C267 Q_CAP_0402-1UF,16V,10%,EMPTY,TA
     1 LPC_ESPI_SEL_R1 @SCM_LIB.SCM(SCH_1):LPC_ESPI_SEL_R1   I166 @SCM_LIB.SCM(SCH_1):PAGE27
     2    GND @SCM_LIB.SCM(SCH_1):GND   I166 @SCM_LIB.SCM(SCH_1):PAGE27

C268 Q_CAP_0402-0.1UF,25V,10%,X7R,CA
     1 P3V3_AUX @SCM_LIB.SCM(SCH_1):P3V3_AUX   I229 @SCM_LIB.SCM(SCH_1):PAGE30
     2    GND @SCM_LIB.SCM(SCH_1):GND   I229 @SCM_LIB.SCM(SCH_1):PAGE30

C269 Q_CAP_0402-0.1UF,25V,10%,X7R,CA
     1 PVCCA_AUX_PLD @SCM_LIB.SCM(SCH_1):PVCCA_AUX_PLD   I118 @SCM_LIB.SCM(SCH_1):PAGE41
     2    GND @SCM_LIB.SCM(SCH_1):GND   I118 @SCM_LIB.SCM(SCH_1):PAGE41

C270 Q_CAP_0402-1UF,16V,10%,EMPTY,TA
     1 LPC_ESPI_SEL_N @SCM_LIB.SCM(SCH_1):LPC_ESPI_SEL_N   I239 @SCM_LIB.SCM(SCH_1):PAGE17
     2    GND @SCM_LIB.SCM(SCH_1):GND   I239 @SCM_LIB.SCM(SCH_1):PAGE17

C271 Q_CAP_0402-0.1UF,25V,10%,X7R,CA
     1 P2E_GPU_TX_DN @SCM_LIB.SCM(SCH_1):P2E_GPU_TX_DN   I429 @SCM_LIB.SCM(SCH_1):PAGE12
     2 P2E_GPU_TX_C_DN @SCM_LIB.SCM(SCH_1):P2E_GPU_TX_C_DN   I429 @SCM_LIB.SCM(SCH_1):PAGE12

C272 Q_CAP_0402-0.1UF,25V,10%,X7R,CA
     1 P2E_GPU_TX_DP @SCM_LIB.SCM(SCH_1):P2E_GPU_TX_DP   I428 @SCM_LIB.SCM(SCH_1):PAGE12
     2 P2E_GPU_TX_C_DP @SCM_LIB.SCM(SCH_1):P2E_GPU_TX_C_DP   I428 @SCM_LIB.SCM(SCH_1):PAGE12

C273 Q_CAP_0402-1UF,16V,10%,EMPTY,TA
     1 LPC_ESPI_SEL_R @SCM_LIB.SCM(SCH_1):LPC_ESPI_SEL_R   I234 @SCM_LIB.SCM(SCH_1):PAGE17
     2    GND @SCM_LIB.SCM(SCH_1):GND   I234 @SCM_LIB.SCM(SCH_1):PAGE17

C274 Q_CAP_0402-0.1UF,25V,10%,X7R,CA
     1 P3V3_AUX @SCM_LIB.SCM(SCH_1):P3V3_AUX    I13 @SCM_LIB.SCM(SCH_1):PAGE49
     2    GND @SCM_LIB.SCM(SCH_1):GND    I13 @SCM_LIB.SCM(SCH_1):PAGE49

C275 Q_CAP_0402-100PF,50V,5%,NPO,CHA
     1 P3V_BAT_SENSOR @SCM_LIB.SCM(SCH_1):P3V_BAT_SENSOR   I180 @SCM_LIB.SCM(SCH_1):PAGE15
     2    GND @SCM_LIB.SCM(SCH_1):GND   I180 @SCM_LIB.SCM(SCH_1):PAGE15

C276 Q_CAP_0402-0.1UF,25V,10%,X7R,CA
     1 P3V3_AUX @SCM_LIB.SCM(SCH_1):P3V3_AUX    I75 @SCM_LIB.SCM(SCH_1):PAGE49
     2    GND @SCM_LIB.SCM(SCH_1):GND    I75 @SCM_LIB.SCM(SCH_1):PAGE49

C277 Q_CAP_C0402-1UF,25V,10%,X6S,CHA
     1 ADCVREFEXT1 @SCM_LIB.SCM(SCH_1):ADCVREFEXT1   I253 @SCM_LIB.SCM(SCH_1):PAGE17
     2    GND @SCM_LIB.SCM(SCH_1):GND   I253 @SCM_LIB.SCM(SCH_1):PAGE17

C278 Q_CAP_0402-0.1UF,25V,10%,X7R,CA
     1 P12V_AUX @SCM_LIB.SCM(SCH_1):P12V_AUX    I54 @SCM_LIB.SCM(SCH_1):PAGE55
     2    GND @SCM_LIB.SCM(SCH_1):GND    I54 @SCM_LIB.SCM(SCH_1):PAGE55

C279 Q_CAP_0402-0.1UF,25V,10%,X7R,CA
     1 ADCVREFEXT1 @SCM_LIB.SCM(SCH_1):ADCVREFEXT1   I255 @SCM_LIB.SCM(SCH_1):PAGE17
     2    GND @SCM_LIB.SCM(SCH_1):GND   I255 @SCM_LIB.SCM(SCH_1):PAGE17

C280 Q_CAP_0402-0.1UF,25V,10%,X7R,CA
     1 P12V_AUX @SCM_LIB.SCM(SCH_1):P12V_AUX    I58 @SCM_LIB.SCM(SCH_1):PAGE56
     2    GND @SCM_LIB.SCM(SCH_1):GND    I58 @SCM_LIB.SCM(SCH_1):PAGE56

C281 Q_CAP_C0402-0.01UF,50V,10%,EMPA
     1 VCCIO1 @SCM_LIB.SCM(SCH_1):VCCIO1   I125 @SCM_LIB.SCM(SCH_1):PAGE41
     2    GND @SCM_LIB.SCM(SCH_1):GND   I125 @SCM_LIB.SCM(SCH_1):PAGE41

C282 Q_CAP_C0402-1UF,25V,10%,X6S,CHA
     1 ADCVREFEXT0 @SCM_LIB.SCM(SCH_1):ADCVREFEXT0   I252 @SCM_LIB.SCM(SCH_1):PAGE17
     2    GND @SCM_LIB.SCM(SCH_1):GND   I252 @SCM_LIB.SCM(SCH_1):PAGE17

C283 Q_CAP_C0402-0.01UF,50V,10%,EMPA
     1 VCCIO0 @SCM_LIB.SCM(SCH_1):VCCIO0   I126 @SCM_LIB.SCM(SCH_1):PAGE41
     2    GND @SCM_LIB.SCM(SCH_1):GND   I126 @SCM_LIB.SCM(SCH_1):PAGE41

C284 Q_CAP_0402-0.1UF,25V,10%,X7R,CA
     1 ADCVREFEXT0 @SCM_LIB.SCM(SCH_1):ADCVREFEXT0   I250 @SCM_LIB.SCM(SCH_1):PAGE17
     2    GND @SCM_LIB.SCM(SCH_1):GND   I250 @SCM_LIB.SCM(SCH_1):PAGE17

C285 Q_CAP_C0402-0.01UF,50V,10%,EMPA
     1 VCCIO2 @SCM_LIB.SCM(SCH_1):VCCIO2   I124 @SCM_LIB.SCM(SCH_1):PAGE41
     2    GND @SCM_LIB.SCM(SCH_1):GND   I124 @SCM_LIB.SCM(SCH_1):PAGE41

C286 Q_CAP_C0402-0.01UF,50V,10%,EMPA
     1 PVCCA_AUX_PLD @SCM_LIB.SCM(SCH_1):PVCCA_AUX_PLD   I123 @SCM_LIB.SCM(SCH_1):PAGE41
     2    GND @SCM_LIB.SCM(SCH_1):GND   I123 @SCM_LIB.SCM(SCH_1):PAGE41

C287 Q_CAP_C0402-1UF,25V,10%,X6S,CHA
     1 P5V_AUX @SCM_LIB.SCM(SCH_1):P5V_AUX    I67 @SCM_LIB.SCM(SCH_1):PAGE53
     2    GND @SCM_LIB.SCM(SCH_1):GND    I67 @SCM_LIB.SCM(SCH_1):PAGE53

C288 Q_CAP_C0805-10UF,25V,10%,X6S,CA
     1 P3V3_AUX @SCM_LIB.SCM(SCH_1):P3V3_AUX    I71 @SCM_LIB.SCM(SCH_1):PAGE53
     2    GND @SCM_LIB.SCM(SCH_1):GND    I71 @SCM_LIB.SCM(SCH_1):PAGE53

C289 Q_CAP_C0805-10UF,25V,10%,X6S,CA
     1 P2V5_AUX @SCM_LIB.SCM(SCH_1):P2V5_AUX    I69 @SCM_LIB.SCM(SCH_1):PAGE53
     2    GND @SCM_LIB.SCM(SCH_1):GND    I69 @SCM_LIB.SCM(SCH_1):PAGE53

C290 Q_CAP_0402-0.1UF,25V,10%,X7R,CA
     1 P12V_SENSOR @SCM_LIB.SCM(SCH_1):P12V_SENSOR   I201 @SCM_LIB.SCM(SCH_1):PAGE15
     2    GND @SCM_LIB.SCM(SCH_1):GND   I201 @SCM_LIB.SCM(SCH_1):PAGE15

C291 Q_CAP_0402-0.1UF,25V,10%,X7R,CA
     1 P2V5_AUX @SCM_LIB.SCM(SCH_1):P2V5_AUX    I70 @SCM_LIB.SCM(SCH_1):PAGE53
     2    GND @SCM_LIB.SCM(SCH_1):GND    I70 @SCM_LIB.SCM(SCH_1):PAGE53

C292 Q_CAP_C0402-1UF,25V,10%,X6S,CHA
     1 P5V_AUX @SCM_LIB.SCM(SCH_1):P5V_AUX   I107 @SCM_LIB.SCM(SCH_1):PAGE54
     2    GND @SCM_LIB.SCM(SCH_1):GND   I107 @SCM_LIB.SCM(SCH_1):PAGE54

C293 Q_CAP_C0805-10UF,25V,10%,X6S,CA
     1 P3V3_AUX @SCM_LIB.SCM(SCH_1):P3V3_AUX   I106 @SCM_LIB.SCM(SCH_1):PAGE54
     2    GND @SCM_LIB.SCM(SCH_1):GND   I106 @SCM_LIB.SCM(SCH_1):PAGE54

C294 Q_CAP_0402-0.1UF,25V,10%,X7R,CA
     1 P1V8_AUX @SCM_LIB.SCM(SCH_1):P1V8_AUX   I105 @SCM_LIB.SCM(SCH_1):PAGE54
     2    GND @SCM_LIB.SCM(SCH_1):GND   I105 @SCM_LIB.SCM(SCH_1):PAGE54

C295 Q_CAP_0402-0.1UF,25V,10%,X7R,CA
     1 P5V_SENSOR @SCM_LIB.SCM(SCH_1):P5V_SENSOR   I207 @SCM_LIB.SCM(SCH_1):PAGE15
     2    GND @SCM_LIB.SCM(SCH_1):GND   I207 @SCM_LIB.SCM(SCH_1):PAGE15

C296 Q_CAP_0402-0.1UF,25V,10%,X7R,CA
     1 P3V3_LDO @SCM_LIB.SCM(SCH_1):P3V3_LDO   I119 @SCM_LIB.SCM(SCH_1):PAGE52
     2    GND @SCM_LIB.SCM(SCH_1):GND   I119 @SCM_LIB.SCM(SCH_1):PAGE52

C297 Q_CAP_0402-0.1UF,25V,10%,X7R,CA
     1 P3V3_LDO @SCM_LIB.SCM(SCH_1):P3V3_LDO   I107 @SCM_LIB.SCM(SCH_1):PAGE52
     2    GND @SCM_LIB.SCM(SCH_1):GND   I107 @SCM_LIB.SCM(SCH_1):PAGE52

C298 Q_CAP_0402-0.1UF,25V,10%,X7R,CA
     1 P3V3_LDO @SCM_LIB.SCM(SCH_1):P3V3_LDO   I112 @SCM_LIB.SCM(SCH_1):PAGE54
     2    GND @SCM_LIB.SCM(SCH_1):GND   I112 @SCM_LIB.SCM(SCH_1):PAGE54

C299 Q_CAP_0402-0.1UF,25V,10%,X7R,CA
     1 P3V3_SENSOR @SCM_LIB.SCM(SCH_1):P3V3_SENSOR   I215 @SCM_LIB.SCM(SCH_1):PAGE15
     2    GND @SCM_LIB.SCM(SCH_1):GND   I215 @SCM_LIB.SCM(SCH_1):PAGE15

C300 Q_CAP_0402-0.1UF,25V,10%,X7R,CA
     1 P3V3_AUX @SCM_LIB.SCM(SCH_1):P3V3_AUX   I146 @SCM_LIB.SCM(SCH_1):PAGE28
     2    GND @SCM_LIB.SCM(SCH_1):GND   I146 @SCM_LIB.SCM(SCH_1):PAGE28

C301 Q_CAP_0402-0.1UF,25V,10%,X7R,CA
     1 P3V3_LDO @SCM_LIB.SCM(SCH_1):P3V3_LDO    I61 @SCM_LIB.SCM(SCH_1):PAGE55
     2    GND @SCM_LIB.SCM(SCH_1):GND    I61 @SCM_LIB.SCM(SCH_1):PAGE55

C302 Q_CAP_0402-0.1UF,25V,10%,X7R,CA
     1 P3V3_LDO @SCM_LIB.SCM(SCH_1):P3V3_LDO    I64 @SCM_LIB.SCM(SCH_1):PAGE56
     2    GND @SCM_LIB.SCM(SCH_1):GND    I64 @SCM_LIB.SCM(SCH_1):PAGE56

C303 Q_CAP_0402-0.1UF,25V,10%,X7R,CA
     1 P2V5_SENSOR @SCM_LIB.SCM(SCH_1):P2V5_SENSOR   I235 @SCM_LIB.SCM(SCH_1):PAGE15
     2    GND @SCM_LIB.SCM(SCH_1):GND   I235 @SCM_LIB.SCM(SCH_1):PAGE15

C304 Q_CAP_0402-0.1UF,25V,10%,X7R,CA
     1 P3V3_AUX @SCM_LIB.SCM(SCH_1):P3V3_AUX    I65 @SCM_LIB.SCM(SCH_1):PAGE25
     2    GND @SCM_LIB.SCM(SCH_1):GND    I65 @SCM_LIB.SCM(SCH_1):PAGE25

C305 Q_CAP_C0402-1UF,25V,10%,X6S,CHA
     1 PWRGD_P1V8_AUX_R2 @SCM_LIB.SCM(SCH_1):PWRGD_P1V8_AUX_R2   I125 @SCM_LIB.SCM(SCH_1):PAGE52
     2    GND @SCM_LIB.SCM(SCH_1):GND   I125 @SCM_LIB.SCM(SCH_1):PAGE52

C307 Q_CAP_0402-0.1UF,25V,10%,X7R,CA
     1 P1V8_SENSOR @SCM_LIB.SCM(SCH_1):P1V8_SENSOR   I240 @SCM_LIB.SCM(SCH_1):PAGE15
     2    GND @SCM_LIB.SCM(SCH_1):GND   I240 @SCM_LIB.SCM(SCH_1):PAGE15

C309 Q_CAP_0402-0.1UF,25V,10%,X7R,CA
     1 P1V2_SENSOR @SCM_LIB.SCM(SCH_1):P1V2_SENSOR   I247 @SCM_LIB.SCM(SCH_1):PAGE15
     2    GND @SCM_LIB.SCM(SCH_1):GND   I247 @SCM_LIB.SCM(SCH_1):PAGE15

C310 Q_CAP_C0402-1UF,25V,10%,X6S,CHA
     1 PWRGD_P3V3_RGM_R2 @SCM_LIB.SCM(SCH_1):PWRGD_P3V3_RGM_R2   I130 @SCM_LIB.SCM(SCH_1):PAGE54
     2    GND @SCM_LIB.SCM(SCH_1):GND   I130 @SCM_LIB.SCM(SCH_1):PAGE54

C311 Q_CAP_0402-0.1UF,25V,10%,X7R,CA
     1 P1V0_SENSOR @SCM_LIB.SCM(SCH_1):P1V0_SENSOR   I256 @SCM_LIB.SCM(SCH_1):PAGE15
     2    GND @SCM_LIB.SCM(SCH_1):GND   I256 @SCM_LIB.SCM(SCH_1):PAGE15

C312 Q_CAP_0402-0.1UF,25V,10%,X7R,CA
     1 P3V3_AUX @SCM_LIB.SCM(SCH_1):P3V3_AUX   I146 @SCM_LIB.SCM(SCH_1):PAGE25
     2    GND @SCM_LIB.SCM(SCH_1):GND   I146 @SCM_LIB.SCM(SCH_1):PAGE25

C313 Q_CAP_0402-0.1UF,25V,10%,X7R,CA
     1 P3V3_AUX @SCM_LIB.SCM(SCH_1):P3V3_AUX   I154 @SCM_LIB.SCM(SCH_1):PAGE25
     2    GND @SCM_LIB.SCM(SCH_1):GND   I154 @SCM_LIB.SCM(SCH_1):PAGE25

C314 Q_CAP_0402-0.1UF,25V,10%,X7R,CA
     1 PGPPA_BMC_AUX_SENSOR @SCM_LIB.SCM(SCH_1):PGPPA_BMC_AUX_SENSOR   I259 @SCM_LIB.SCM(SCH_1):PAGE15
     2    GND @SCM_LIB.SCM(SCH_1):GND   I259 @SCM_LIB.SCM(SCH_1):PAGE15

C318 Q_CAP_0402-0.1UF,25V,10%,X7R,CA
     1 P3V3_AUX @SCM_LIB.SCM(SCH_1):P3V3_AUX   I122 @SCM_LIB.SCM(SCH_1):PAGE34
     2    GND @SCM_LIB.SCM(SCH_1):GND   I122 @SCM_LIB.SCM(SCH_1):PAGE34

C321 Q_CAP_0402-0.1UF,25V,10%,X7R,CA
     1 PWR_LED_P5V_AUX @SCM_LIB.SCM(SCH_1):PWR_LED_P5V_AUX    I43 @SCM_LIB.SCM(SCH_1):PAGE49
     2    GND @SCM_LIB.SCM(SCH_1):GND    I43 @SCM_LIB.SCM(SCH_1):PAGE49

C324 Q_CAP_0402-470PF,50V,10%,X7R,TA
     1 HDD_LED_BUF_R @SCM_LIB.SCM(SCH_1):HDD_LED_BUF_R    I37 @SCM_LIB.SCM(SCH_1):PAGE49
     2    GND @SCM_LIB.SCM(SCH_1):GND    I37 @SCM_LIB.SCM(SCH_1):PAGE49

C326 Q_CAP_0402-470PF,50V,10%,X7R,TA
     1 PWR_LED_BUF_N_R @SCM_LIB.SCM(SCH_1):PWR_LED_BUF_N_R    I38 @SCM_LIB.SCM(SCH_1):PAGE49
     2    GND @SCM_LIB.SCM(SCH_1):GND    I38 @SCM_LIB.SCM(SCH_1):PAGE49

C327 Q_CAP_C1206-47UF,6.3V,20%,X6S,A
     1 P5V_USB_REAR @SCM_LIB.SCM(SCH_1):P5V_USB_REAR   I220 @SCM_LIB.SCM(SCH_1):PAGE29
     2    GND @SCM_LIB.SCM(SCH_1):GND   I220 @SCM_LIB.SCM(SCH_1):PAGE29

C329 Q_CAP_C0805-22UF,16V,20%,X6S,CA
     1 P12V_AUX @SCM_LIB.SCM(SCH_1):P12V_AUX   I573 @SCM_LIB.SCM(SCH_1):PAGE10
     2    GND @SCM_LIB.SCM(SCH_1):GND   I573 @SCM_LIB.SCM(SCH_1):PAGE10

C330 Q_CAP_C0805-22UF,16V,20%,X6S,CA
     1 P12V_AUX @SCM_LIB.SCM(SCH_1):P12V_AUX   I574 @SCM_LIB.SCM(SCH_1):PAGE10
     2    GND @SCM_LIB.SCM(SCH_1):GND   I574 @SCM_LIB.SCM(SCH_1):PAGE10

C335 Q_CAP_C0402-1UF,25V,10%,X6S,CHA
     1 REAR_AC_PWR_BMC_BTN_N @SCM_LIB.SCM(SCH_1):REAR_AC_PWR_BMC_BTN_N   I285 @SCM_LIB.SCM(SCH_1):PAGE50
     2    GND @SCM_LIB.SCM(SCH_1):GND   I285 @SCM_LIB.SCM(SCH_1):PAGE50

C336 Q_CAP_0402-0.1UF,25V,10%,X7R,CA
     1 P3V3_AUX @SCM_LIB.SCM(SCH_1):P3V3_AUX   I281 @SCM_LIB.SCM(SCH_1):PAGE50
     2    GND @SCM_LIB.SCM(SCH_1):GND   I281 @SCM_LIB.SCM(SCH_1):PAGE50

C337 Q_CAP_0402-0.1UF,25V,10%,X7R,CA
     1 P3V3_AUX @SCM_LIB.SCM(SCH_1):P3V3_AUX    I97 @SCM_LIB.SCM(SCH_1):PAGE22
     2    GND @SCM_LIB.SCM(SCH_1):GND    I97 @SCM_LIB.SCM(SCH_1):PAGE22

C500 Q_CAP_0402-0.1UF,25V,10%,X7R,CA
     1 P3V3_AUX @SCM_LIB.SCM(SCH_1):P3V3_AUX    I17 @SCM_LIB.SCM(SCH_1):PAGE31
     2    GND @SCM_LIB.SCM(SCH_1):GND    I17 @SCM_LIB.SCM(SCH_1):PAGE31

C501 Q_CAP_0402-0.1UF,25V,10%,X7R,CA
     1 P3V3_AUX @SCM_LIB.SCM(SCH_1):P3V3_AUX    I11 @SCM_LIB.SCM(SCH_1):PAGE31
     2    GND @SCM_LIB.SCM(SCH_1):GND    I11 @SCM_LIB.SCM(SCH_1):PAGE31

  D0 Q_LED_SMLF-LED_GREEN,19-213/GVA
     A LED_POSTCODE_0_R @SCM_LIB.SCM(SCH_1):LED_POSTCODE_0_R     I7 @SCM_LIB.SCM(SCH_1):PAGE47
     C    GND @SCM_LIB.SCM(SCH_1):GND     I7 @SCM_LIB.SCM(SCH_1):PAGE47

  D1 Q_LED_SMLF-LED_GREEN,19-213/GVA
     A LED_POSTCODE_1_R @SCM_LIB.SCM(SCH_1):LED_POSTCODE_1_R     I9 @SCM_LIB.SCM(SCH_1):PAGE47
     C    GND @SCM_LIB.SCM(SCH_1):GND     I9 @SCM_LIB.SCM(SCH_1):PAGE47

  D2 Q_LED_SMLF-LED_GREEN,19-213/GVA
     A LED_POSTCODE_2_R @SCM_LIB.SCM(SCH_1):LED_POSTCODE_2_R    I11 @SCM_LIB.SCM(SCH_1):PAGE47
     C    GND @SCM_LIB.SCM(SCH_1):GND    I11 @SCM_LIB.SCM(SCH_1):PAGE47

  D3 Q_LED_SMLF-LED_GREEN,19-213/GVA
     A LED_POSTCODE_3_R @SCM_LIB.SCM(SCH_1):LED_POSTCODE_3_R    I13 @SCM_LIB.SCM(SCH_1):PAGE47
     C    GND @SCM_LIB.SCM(SCH_1):GND    I13 @SCM_LIB.SCM(SCH_1):PAGE47

  D4 Q_LED_SMLF-LED_RED,19-217/R6C-A
     A LED_POSTCODE_4_R @SCM_LIB.SCM(SCH_1):LED_POSTCODE_4_R    I10 @SCM_LIB.SCM(SCH_1):PAGE47
     C    GND @SCM_LIB.SCM(SCH_1):GND    I10 @SCM_LIB.SCM(SCH_1):PAGE47

  D5 Q_LED_SMLF-LED_RED,19-217/R6C-A
     A LED_POSTCODE_5_R @SCM_LIB.SCM(SCH_1):LED_POSTCODE_5_R    I12 @SCM_LIB.SCM(SCH_1):PAGE47
     C    GND @SCM_LIB.SCM(SCH_1):GND    I12 @SCM_LIB.SCM(SCH_1):PAGE47

  D6 Q_LED_SMLF-LED_RED,19-217/R6C-A
     A LED_POSTCODE_6_R @SCM_LIB.SCM(SCH_1):LED_POSTCODE_6_R    I14 @SCM_LIB.SCM(SCH_1):PAGE47
     C    GND @SCM_LIB.SCM(SCH_1):GND    I14 @SCM_LIB.SCM(SCH_1):PAGE47

  D7 Q_LED_SMLF-LED_RED,19-217/R6C-A
     A LED_POSTCODE_7_R @SCM_LIB.SCM(SCH_1):LED_POSTCODE_7_R     I5 @SCM_LIB.SCM(SCH_1):PAGE47
     C    GND @SCM_LIB.SCM(SCH_1):GND     I5 @SCM_LIB.SCM(SCH_1):PAGE47

  D8 Q_LED_SMLF-LED_GREEN,19-213/GVA
     A BMC_HEARTBEAT_R_N @SCM_LIB.SCM(SCH_1):BMC_HEARTBEAT_R_N    I46 @SCM_LIB.SCM(SCH_1):PAGE13
     C BMC_HEARTBEAT_N @SCM_LIB.SCM(SCH_1):BMC_HEARTBEAT_N    I46 @SCM_LIB.SCM(SCH_1):PAGE13

  D9 SCHOTTKY_AC-SS0530,SMLF,EMPTY,A
     A P5V_AUX @SCM_LIB.SCM(SCH_1):P5V_AUX    I42 @SCM_LIB.SCM(SCH_1):PAGE23
     C CRT_VCC5 @SCM_LIB.SCM(SCH_1):CRT_VCC5    I42 @SCM_LIB.SCM(SCH_1):PAGE23

 D10 DIODE_BIDIRECTIONAL-UCLAMP0511A
     A REAR_AC_PWR_BTN @SCM_LIB.SCM(SCH_1):REAR_AC_PWR_BTN   I244 @SCM_LIB.SCM(SCH_1):PAGE50
     C    GND @SCM_LIB.SCM(SCH_1):GND   I244 @SCM_LIB.SCM(SCH_1):PAGE50

 D11 SCHOTTKY_AC-SS0530,SMLF,IC,BCSA
     A P5V_AUX @SCM_LIB.SCM(SCH_1):P5V_AUX    I41 @SCM_LIB.SCM(SCH_1):PAGE23
     C CRT_VCC5 @SCM_LIB.SCM(SCH_1):CRT_VCC5    I41 @SCM_LIB.SCM(SCH_1):PAGE23

 D12 BZA462A-BZA462A,SMLF,EMPTY,BCZA
     2    GND @SCM_LIB.SCM(SCH_1):GND    I74 @SCM_LIB.SCM(SCH_1):PAGE23
     5    GND @SCM_LIB.SCM(SCH_1):GND    I74 @SCM_LIB.SCM(SCH_1):PAGE23
     1 CRT_VCC5 @SCM_LIB.SCM(SCH_1):CRT_VCC5    I74 @SCM_LIB.SCM(SCH_1):PAGE23
     3 CRT_VCC5 @SCM_LIB.SCM(SCH_1):CRT_VCC5    I74 @SCM_LIB.SCM(SCH_1):PAGE23
     4 CRT_VCC5 @SCM_LIB.SCM(SCH_1):CRT_VCC5    I74 @SCM_LIB.SCM(SCH_1):PAGE23
     6 CRT_VCC5 @SCM_LIB.SCM(SCH_1):CRT_VCC5    I74 @SCM_LIB.SCM(SCH_1):PAGE23

 D13 Q_LED_THLF-LED_YELLOW,LTL-R42FA
     A ID_LED_P3V3_AUX @SCM_LIB.SCM(SCH_1):ID_LED_P3V3_AUX    I97 @SCM_LIB.SCM(SCH_1):PAGE49
     C ID_LED_D_P3V3_AUX @SCM_LIB.SCM(SCH_1):ID_LED_D_P3V3_AUX    I97 @SCM_LIB.SCM(SCH_1):PAGE49

 D14 Q_LED_THLF-LED_BLUE,HV-312470/A
     A PWR_LED_P5V_AUX @SCM_LIB.SCM(SCH_1):PWR_LED_P5V_AUX    I94 @SCM_LIB.SCM(SCH_1):PAGE49
     C PWR_LED_BUF_N_R @SCM_LIB.SCM(SCH_1):PWR_LED_BUF_N_R    I94 @SCM_LIB.SCM(SCH_1):PAGE49

 D15 Q_LED_THLF-LED_BLUE,HV-312470/A
     A HDD_LED_P5V_AUX @SCM_LIB.SCM(SCH_1):HDD_LED_P5V_AUX    I95 @SCM_LIB.SCM(SCH_1):PAGE49
     C HDD_LED_BUF_R @SCM_LIB.SCM(SCH_1):HDD_LED_BUF_R    I95 @SCM_LIB.SCM(SCH_1):PAGE49

 D16 SCHOTTKY_12-SBA130Q,SMLF,EMPTYA
     1 P5V_AUX @SCM_LIB.SCM(SCH_1):P5V_AUX   I161 @SCM_LIB.SCM(SCH_1):PAGE23
     2 CRT_VCC5_2_D @SCM_LIB.SCM(SCH_1):CRT_VCC5_2_D   I161 @SCM_LIB.SCM(SCH_1):PAGE23

 D17 Q_DIODE_SMLF-SDMK0340L-7-F,IC,A
     1 RST_BMC_HW_OUT @SCM_LIB.SCM(SCH_1):RST_BMC_HW_OUT    I28 @SCM_LIB.SCM(SCH_1):PAGE22
     2 RST_BMC_SELF_HW_D @SCM_LIB.SCM(SCH_1):RST_BMC_SELF_HW_D    I28 @SCM_LIB.SCM(SCH_1):PAGE22

 D18 Q_LED_SMLF-LED_BLUE,LTST-C281TA
     A P3V3_AUX @SCM_LIB.SCM(SCH_1):P3V3_AUX    I51 @SCM_LIB.SCM(SCH_1):PAGE49
     C FM_UARTSW_LSB_R1_N @SCM_LIB.SCM(SCH_1):FM_UARTSW_LSB_R1_N    I51 @SCM_LIB.SCM(SCH_1):PAGE49

 D19 Q_LED_SMLF-LED_BLUE,LTST-C281TA
     A P3V3_AUX @SCM_LIB.SCM(SCH_1):P3V3_AUX    I50 @SCM_LIB.SCM(SCH_1):PAGE49
     C FM_UARTSW_MSB_R1_N @SCM_LIB.SCM(SCH_1):FM_UARTSW_MSB_R1_N    I50 @SCM_LIB.SCM(SCH_1):PAGE49

 D20 SCHOTTKY_12-1N5819HW,SMLF,IC,BA
     1 P3V3_AUX @SCM_LIB.SCM(SCH_1):P3V3_AUX   I144 @SCM_LIB.SCM(SCH_1):PAGE32
     2  J7_P1 @SCM_LIB.SCM(SCH_1):J7_P1   I144 @SCM_LIB.SCM(SCH_1):PAGE32

 D21 Q_LED_THLF-LED_BLUE,HV-312470/A
     A LED_D21_R3 @SCM_LIB.SCM(SCH_1):LED_D21_R3   I294 @SCM_LIB.SCM(SCH_1):PAGE50
     C    GND @SCM_LIB.SCM(SCH_1):GND   I294 @SCM_LIB.SCM(SCH_1):PAGE50

 D22 Q_LED_THLF-LED_BLUE,HV-312470/A
     A LED_D22_R @SCM_LIB.SCM(SCH_1):LED_D22_R   I295 @SCM_LIB.SCM(SCH_1):PAGE50
     C LED_D22_R1 @SCM_LIB.SCM(SCH_1):LED_D22_R1   I295 @SCM_LIB.SCM(SCH_1):PAGE50

 D23 Q_DIODE_SMLF-SDMK0340L-7-F,EMPA
     1 PWRGD_P5V_AUX @SCM_LIB.SCM(SCH_1):PWRGD_P5V_AUX   I150 @SCM_LIB.SCM(SCH_1):PAGE35
     2 PWRGD_P5V_AUX_R1 @SCM_LIB.SCM(SCH_1):PWRGD_P5V_AUX_R1   I150 @SCM_LIB.SCM(SCH_1):PAGE35

 DB1 TDR_3P_TH2-EMPTY,N_A
     1  T_GND @SCM_LIB.SCM(SCH_1):T_GND     I1 @SCM_LIB.SCM(SCH_1):PAGE60
     2 TDR_SE_50_OHM_TOP @SCM_LIB.SCM(SCH_1):TDR_SE_50_OHM_TOP     I1 @SCM_LIB.SCM(SCH_1):PAGE60
     3 TDR_SE_50_OHM_TOP @SCM_LIB.SCM(SCH_1):TDR_SE_50_OHM_TOP     I1 @SCM_LIB.SCM(SCH_1):PAGE60

 DB2 TDR_3P_TH2-EMPTY,N_A
     1  T_GND @SCM_LIB.SCM(SCH_1):T_GND    I11 @SCM_LIB.SCM(SCH_1):PAGE60
     2 TDR_SE_50_OHM_IN1 @SCM_LIB.SCM(SCH_1):TDR_SE_50_OHM_IN1    I11 @SCM_LIB.SCM(SCH_1):PAGE60
     3 TDR_SE_50_OHM_IN1 @SCM_LIB.SCM(SCH_1):TDR_SE_50_OHM_IN1    I11 @SCM_LIB.SCM(SCH_1):PAGE60

 DB3 TDR_3P_TH2-EMPTY,N_A
     1  T_GND @SCM_LIB.SCM(SCH_1):T_GND     I9 @SCM_LIB.SCM(SCH_1):PAGE60
     2 TDR_SE_50_OHM_IN2 @SCM_LIB.SCM(SCH_1):TDR_SE_50_OHM_IN2     I9 @SCM_LIB.SCM(SCH_1):PAGE60
     3 TDR_SE_50_OHM_IN2 @SCM_LIB.SCM(SCH_1):TDR_SE_50_OHM_IN2     I9 @SCM_LIB.SCM(SCH_1):PAGE60

 DB4 TDR_3P_TH2-EMPTY,N_A
     1  T_GND @SCM_LIB.SCM(SCH_1):T_GND     I7 @SCM_LIB.SCM(SCH_1):PAGE60
     2 TDR_SE_50_OHM_IN3 @SCM_LIB.SCM(SCH_1):TDR_SE_50_OHM_IN3     I7 @SCM_LIB.SCM(SCH_1):PAGE60
     3 TDR_SE_50_OHM_IN3 @SCM_LIB.SCM(SCH_1):TDR_SE_50_OHM_IN3     I7 @SCM_LIB.SCM(SCH_1):PAGE60

 DB5 TDR_3P_TH2-EMPTY,N_A
     1  T_GND @SCM_LIB.SCM(SCH_1):T_GND     I5 @SCM_LIB.SCM(SCH_1):PAGE60
     2 TDR_SE_50_OHM_IN4 @SCM_LIB.SCM(SCH_1):TDR_SE_50_OHM_IN4     I5 @SCM_LIB.SCM(SCH_1):PAGE60
     3 TDR_SE_50_OHM_IN4 @SCM_LIB.SCM(SCH_1):TDR_SE_50_OHM_IN4     I5 @SCM_LIB.SCM(SCH_1):PAGE60

 DB6 TDR_3P_TH2-EMPTY,N_A
     1  T_GND @SCM_LIB.SCM(SCH_1):T_GND     I3 @SCM_LIB.SCM(SCH_1):PAGE60
     2 TDR_SE_50_OHM_BOT @SCM_LIB.SCM(SCH_1):TDR_SE_50_OHM_BOT     I3 @SCM_LIB.SCM(SCH_1):PAGE60
     3 TDR_SE_50_OHM_BOT @SCM_LIB.SCM(SCH_1):TDR_SE_50_OHM_BOT     I3 @SCM_LIB.SCM(SCH_1):PAGE60

 DM1 DUMMY_SYMBOL-BMC_FLASH,MECH,EMA
     1     NC     NC    I36 @SCM_LIB.SCM(SCH_1):PAGE59

 DM2 DUMMY_SYMBOL-BMC_FLASH,MECH,EMA
     1     NC     NC    I37 @SCM_LIB.SCM(SCH_1):PAGE59

 DM3 DUMMY_SYMBOL-BIOS_FLASH,MECH,MA
     1     NC     NC    I35 @SCM_LIB.SCM(SCH_1):PAGE59

 DM7 ME_DUMMY_SYMBOL-PB-E1_SMALL,MEA

 FS1 Q_FUSE_SMLF-1.1A/8V,EMPTY,DK11A
     1 CRT_VCC5_2_D @SCM_LIB.SCM(SCH_1):CRT_VCC5_2_D   I153 @SCM_LIB.SCM(SCH_1):PAGE23
     2 CRT_VCC5_2_FUSE @SCM_LIB.SCM(SCH_1):CRT_VCC5_2_FUSE   I153 @SCM_LIB.SCM(SCH_1):PAGE23

 GF1 FCONN168_ME1016810202011_SCM-FA
   OA1 P12V_AUX @SCM_LIB.SCM(SCH_1):P12V_AUX   I553 @SCM_LIB.SCM(SCH_1):PAGE10
   OA2 P12V_AUX @SCM_LIB.SCM(SCH_1):P12V_AUX   I553 @SCM_LIB.SCM(SCH_1):PAGE10
   OA3    GND @SCM_LIB.SCM(SCH_1):GND   I553 @SCM_LIB.SCM(SCH_1):PAGE10
   OA4    GND @SCM_LIB.SCM(SCH_1):GND   I553 @SCM_LIB.SCM(SCH_1):PAGE10
   OA5 I3C1_SPD_SCL @SCM_LIB.SCM(SCH_1):I3C1_SPD_SCL   I553 @SCM_LIB.SCM(SCH_1):PAGE10
   OA6 I3C1_SPD_SDA @SCM_LIB.SCM(SCH_1):I3C1_SPD_SDA   I553 @SCM_LIB.SCM(SCH_1):PAGE10
   OA7 I3C2_SPD_SCL @SCM_LIB.SCM(SCH_1):I3C2_SPD_SCL   I553 @SCM_LIB.SCM(SCH_1):PAGE10
   OA8 I3C2_SPD_SDA @SCM_LIB.SCM(SCH_1):I3C2_SPD_SDA   I553 @SCM_LIB.SCM(SCH_1):PAGE10
   OA9 I3C3_SPD_SCL @SCM_LIB.SCM(SCH_1):I3C3_SPD_SCL   I553 @SCM_LIB.SCM(SCH_1):PAGE10
  OA10 I3C3_SPD_SDA @SCM_LIB.SCM(SCH_1):I3C3_SPD_SDA   I553 @SCM_LIB.SCM(SCH_1):PAGE10
  OA11 I3C4_SPD_SCL @SCM_LIB.SCM(SCH_1):I3C4_SPD_SCL   I553 @SCM_LIB.SCM(SCH_1):PAGE10
  OA12 I3C4_SPD_SDA @SCM_LIB.SCM(SCH_1):I3C4_SPD_SDA   I553 @SCM_LIB.SCM(SCH_1):PAGE10
  OA13    GND @SCM_LIB.SCM(SCH_1):GND   I553 @SCM_LIB.SCM(SCH_1):PAGE10
  OA14 FM_VIRTUAL_RESEAT @SCM_LIB.SCM(SCH_1):FM_VIRTUAL_RESEAT   I553 @SCM_LIB.SCM(SCH_1):PAGE10
    A1 SMB_BMC_MM14_R1_SCL @SCM_LIB.SCM(SCH_1):SMB_BMC_MM14_R1_SCL   I553 @SCM_LIB.SCM(SCH_1):PAGE10
    A2 SMB_BMC_MM14_R1_SDA @SCM_LIB.SCM(SCH_1):SMB_BMC_MM14_R1_SDA   I553 @SCM_LIB.SCM(SCH_1):PAGE10
    A3 SMB_BMC_MM1_SCL @SCM_LIB.SCM(SCH_1):SMB_BMC_MM1_SCL   I553 @SCM_LIB.SCM(SCH_1):PAGE10
    A4 SMB_BMC_MM1_SDA @SCM_LIB.SCM(SCH_1):SMB_BMC_MM1_SDA   I553 @SCM_LIB.SCM(SCH_1):PAGE10
    A5 SMB_BMC_MM2_SCL_R1 @SCM_LIB.SCM(SCH_1):SMB_BMC_MM2_SCL_R1   I553 @SCM_LIB.SCM(SCH_1):PAGE10
    A6 SMB_BMC_MM2_SDA @SCM_LIB.SCM(SCH_1):SMB_BMC_MM2_SDA   I553 @SCM_LIB.SCM(SCH_1):PAGE10
    A7 SMB_BMC_MM3_SCL @SCM_LIB.SCM(SCH_1):SMB_BMC_MM3_SCL   I553 @SCM_LIB.SCM(SCH_1):PAGE10
    A8 SMB_BMC_MM3_SDA @SCM_LIB.SCM(SCH_1):SMB_BMC_MM3_SDA   I553 @SCM_LIB.SCM(SCH_1):PAGE10
    A9 SMB_BMC_MM4_SCL @SCM_LIB.SCM(SCH_1):SMB_BMC_MM4_SCL   I553 @SCM_LIB.SCM(SCH_1):PAGE10
   A10 SMB_BMC_MM4_SDA @SCM_LIB.SCM(SCH_1):SMB_BMC_MM4_SDA   I553 @SCM_LIB.SCM(SCH_1):PAGE10
   A11 SMB_BMC_MM5_SCL @SCM_LIB.SCM(SCH_1):SMB_BMC_MM5_SCL   I553 @SCM_LIB.SCM(SCH_1):PAGE10
   A12 SMB_BMC_MM5_SDA @SCM_LIB.SCM(SCH_1):SMB_BMC_MM5_SDA   I553 @SCM_LIB.SCM(SCH_1):PAGE10
   A13    GND @SCM_LIB.SCM(SCH_1):GND   I553 @SCM_LIB.SCM(SCH_1):PAGE10
   A14 CLK_100M_PCH_DP @SCM_LIB.SCM(SCH_1):CLK_100M_PCH_DP   I553 @SCM_LIB.SCM(SCH_1):PAGE10
   A15 CLK_100M_PCH_DN @SCM_LIB.SCM(SCH_1):CLK_100M_PCH_DN   I553 @SCM_LIB.SCM(SCH_1):PAGE10
   A16    GND @SCM_LIB.SCM(SCH_1):GND   I553 @SCM_LIB.SCM(SCH_1):PAGE10
   A17 P2E_PCH_RX_DP @SCM_LIB.SCM(SCH_1):P2E_PCH_RX_DP   I553 @SCM_LIB.SCM(SCH_1):PAGE10
   A18 P2E_PCH_RX_DN @SCM_LIB.SCM(SCH_1):P2E_PCH_RX_DN   I553 @SCM_LIB.SCM(SCH_1):PAGE10
   A19    GND @SCM_LIB.SCM(SCH_1):GND   I553 @SCM_LIB.SCM(SCH_1):PAGE10
   A20 P2E_PCH_TX_C_DP @SCM_LIB.SCM(SCH_1):P2E_PCH_TX_C_DP   I553 @SCM_LIB.SCM(SCH_1):PAGE10
   A21 P2E_PCH_TX_C_DN @SCM_LIB.SCM(SCH_1):P2E_PCH_TX_C_DN   I553 @SCM_LIB.SCM(SCH_1):PAGE10
   A22    GND @SCM_LIB.SCM(SCH_1):GND   I553 @SCM_LIB.SCM(SCH_1):PAGE10
   A23 SMB_BMC_MM6_SCL @SCM_LIB.SCM(SCH_1):SMB_BMC_MM6_SCL   I553 @SCM_LIB.SCM(SCH_1):PAGE10
   A24 SMB_BMC_MM6_SDA @SCM_LIB.SCM(SCH_1):SMB_BMC_MM6_SDA   I553 @SCM_LIB.SCM(SCH_1):PAGE10
   A25 SMB_BMC_MM7_SCL @SCM_LIB.SCM(SCH_1):SMB_BMC_MM7_SCL   I553 @SCM_LIB.SCM(SCH_1):PAGE10
   A26 SMB_BMC_MM7_SDA @SCM_LIB.SCM(SCH_1):SMB_BMC_MM7_SDA   I553 @SCM_LIB.SCM(SCH_1):PAGE10
   A27 SMB_BMC_MM8_SCL @SCM_LIB.SCM(SCH_1):SMB_BMC_MM8_SCL   I553 @SCM_LIB.SCM(SCH_1):PAGE10
   A28 SMB_BMC_MM8_SDA @SCM_LIB.SCM(SCH_1):SMB_BMC_MM8_SDA   I553 @SCM_LIB.SCM(SCH_1):PAGE10
   A29 SMB_BMC_MM9_SCL @SCM_LIB.SCM(SCH_1):SMB_BMC_MM9_SCL   I553 @SCM_LIB.SCM(SCH_1):PAGE10
   A30 SMB_BMC_MM9_SDA @SCM_LIB.SCM(SCH_1):SMB_BMC_MM9_SDA   I553 @SCM_LIB.SCM(SCH_1):PAGE10
   A31 SMB_BMC_MM10_SCL @SCM_LIB.SCM(SCH_1):SMB_BMC_MM10_SCL   I553 @SCM_LIB.SCM(SCH_1):PAGE10
   A32 SMB_BMC_MM10_SDA @SCM_LIB.SCM(SCH_1):SMB_BMC_MM10_SDA   I553 @SCM_LIB.SCM(SCH_1):PAGE10
   A33    GND @SCM_LIB.SCM(SCH_1):GND   I553 @SCM_LIB.SCM(SCH_1):PAGE10
   A34 JTAG_MB_TCK @SCM_LIB.SCM(SCH_1):JTAG_MB_TCK   I553 @SCM_LIB.SCM(SCH_1):PAGE10
   A35 JTAG_MB_TMS @SCM_LIB.SCM(SCH_1):JTAG_MB_TMS   I553 @SCM_LIB.SCM(SCH_1):PAGE10
   A36 JTAG_MB_TDI @SCM_LIB.SCM(SCH_1):JTAG_MB_TDI   I553 @SCM_LIB.SCM(SCH_1):PAGE10
   A37 JTAG_MB_TDO @SCM_LIB.SCM(SCH_1):JTAG_MB_TDO   I553 @SCM_LIB.SCM(SCH_1):PAGE10
   A38 SMB_BMC_MM12_SCL @SCM_LIB.SCM(SCH_1):SMB_BMC_MM12_SCL   I553 @SCM_LIB.SCM(SCH_1):PAGE10
   A39 SMB_BMC_MM12_SDA @SCM_LIB.SCM(SCH_1):SMB_BMC_MM12_SDA   I553 @SCM_LIB.SCM(SCH_1):PAGE10
   A40 SMB_BMC_MM13_SCL @SCM_LIB.SCM(SCH_1):SMB_BMC_MM13_SCL   I553 @SCM_LIB.SCM(SCH_1):PAGE10
   A41 SMB_BMC_MM13_SDA @SCM_LIB.SCM(SCH_1):SMB_BMC_MM13_SDA   I553 @SCM_LIB.SCM(SCH_1):PAGE10
   A42    GND @SCM_LIB.SCM(SCH_1):GND   I553 @SCM_LIB.SCM(SCH_1):PAGE10
   A43 FM_JTAG_SEL @SCM_LIB.SCM(SCH_1):FM_JTAG_SEL   I553 @SCM_LIB.SCM(SCH_1):PAGE10
   A44 PWRGD_PSU_AC_PWROK_R @SCM_LIB.SCM(SCH_1):PWRGD_PSU_AC_PWROK_R   I553 @SCM_LIB.SCM(SCH_1):PAGE10
   A45 TP_GF_A45 @SCM_LIB.SCM(SCH_1):TP_GF_A45   I553 @SCM_LIB.SCM(SCH_1):PAGE10
   A46 RST_MB_STBY_N @SCM_LIB.SCM(SCH_1):RST_MB_STBY_N   I553 @SCM_LIB.SCM(SCH_1):PAGE10
   A47 SYS_PWRBTN_N @SCM_LIB.SCM(SCH_1):SYS_PWRBTN_N   I553 @SCM_LIB.SCM(SCH_1):PAGE10
   A48 PWRGD_SYS_PWROK @SCM_LIB.SCM(SCH_1):PWRGD_SYS_PWROK   I553 @SCM_LIB.SCM(SCH_1):PAGE10
   A49 FM_DBP_CPU_PREQ_GF_R_N @SCM_LIB.SCM(SCH_1):FM_DBP_CPU_PREQ_GF_R_N   I553 @SCM_LIB.SCM(SCH_1):PAGE10
   A50 FM_DBP_BMC_PRDY_N @SCM_LIB.SCM(SCH_1):FM_DBP_BMC_PRDY_N   I553 @SCM_LIB.SCM(SCH_1):PAGE10
   A51 RST_PLTRST_N @SCM_LIB.SCM(SCH_1):RST_PLTRST_N   I553 @SCM_LIB.SCM(SCH_1):PAGE10
   A52 FM_BMC_UARTSW_MSB_N @SCM_LIB.SCM(SCH_1):FM_BMC_UARTSW_MSB_N   I553 @SCM_LIB.SCM(SCH_1):PAGE10
   A53 RST_ROT_CPU_N @SCM_LIB.SCM(SCH_1):RST_ROT_CPU_N   I553 @SCM_LIB.SCM(SCH_1):PAGE10
   A54 FM_INTRUDER_N @SCM_LIB.SCM(SCH_1):FM_INTRUDER_N   I553 @SCM_LIB.SCM(SCH_1):PAGE10
   A55 FM_BMC_UARTSW_LSB_N @SCM_LIB.SCM(SCH_1):FM_BMC_UARTSW_LSB_N   I553 @SCM_LIB.SCM(SCH_1):PAGE10
   A56 IRQ_SMI_ACTIVE_GF_N @SCM_LIB.SCM(SCH_1):IRQ_SMI_ACTIVE_GF_N   I553 @SCM_LIB.SCM(SCH_1):PAGE10
   A57 FM_PRSNT_1_N @SCM_LIB.SCM(SCH_1):FM_PRSNT_1_N   I553 @SCM_LIB.SCM(SCH_1):PAGE10
   A58    GND @SCM_LIB.SCM(SCH_1):GND   I553 @SCM_LIB.SCM(SCH_1):PAGE10
   A59 USB3_FPNL_RXP @SCM_LIB.SCM(SCH_1):USB3_FPNL_RXP   I553 @SCM_LIB.SCM(SCH_1):PAGE10
   A60 USB3_FPNL_RXN @SCM_LIB.SCM(SCH_1):USB3_FPNL_RXN   I553 @SCM_LIB.SCM(SCH_1):PAGE10
   A61    GND @SCM_LIB.SCM(SCH_1):GND   I553 @SCM_LIB.SCM(SCH_1):PAGE10
   A62 TP_GF_A62 @SCM_LIB.SCM(SCH_1):TP_GF_A62   I553 @SCM_LIB.SCM(SCH_1):PAGE10
   A63 TP_GF_A63 @SCM_LIB.SCM(SCH_1):TP_GF_A63   I553 @SCM_LIB.SCM(SCH_1):PAGE10
   A64    GND @SCM_LIB.SCM(SCH_1):GND   I553 @SCM_LIB.SCM(SCH_1):PAGE10
   A65 P2E_GPU_RX_DP @SCM_LIB.SCM(SCH_1):P2E_GPU_RX_DP   I553 @SCM_LIB.SCM(SCH_1):PAGE10
   A66 P2E_GPU_RX_DN @SCM_LIB.SCM(SCH_1):P2E_GPU_RX_DN   I553 @SCM_LIB.SCM(SCH_1):PAGE10
   A67    GND @SCM_LIB.SCM(SCH_1):GND   I553 @SCM_LIB.SCM(SCH_1):PAGE10
   A68 CLK_100M_GPU_DP @SCM_LIB.SCM(SCH_1):CLK_100M_GPU_DP   I553 @SCM_LIB.SCM(SCH_1):PAGE10
   A69 CLK_100M_GPU_DN @SCM_LIB.SCM(SCH_1):CLK_100M_GPU_DN   I553 @SCM_LIB.SCM(SCH_1):PAGE10
   A70    GND @SCM_LIB.SCM(SCH_1):GND   I553 @SCM_LIB.SCM(SCH_1):PAGE10
   OB1 P12V_AUX @SCM_LIB.SCM(SCH_1):P12V_AUX   I553 @SCM_LIB.SCM(SCH_1):PAGE10
   OB2 P12V_AUX @SCM_LIB.SCM(SCH_1):P12V_AUX   I553 @SCM_LIB.SCM(SCH_1):PAGE10
   OB3 FM_PRSNT_0_R_N @SCM_LIB.SCM(SCH_1):FM_PRSNT_0_R_N   I553 @SCM_LIB.SCM(SCH_1):PAGE10
   OB4    GND @SCM_LIB.SCM(SCH_1):GND   I553 @SCM_LIB.SCM(SCH_1):PAGE10
   OB5 UART_BIC_GF_TXD @SCM_LIB.SCM(SCH_1):UART_BIC_GF_TXD   I553 @SCM_LIB.SCM(SCH_1):PAGE10
   OB6 UART_BIC_GF_RXD @SCM_LIB.SCM(SCH_1):UART_BIC_GF_RXD   I553 @SCM_LIB.SCM(SCH_1):PAGE10
   OB7    GND @SCM_LIB.SCM(SCH_1):GND   I553 @SCM_LIB.SCM(SCH_1):PAGE10
   OB8 UART_SYS_DBG_TX @SCM_LIB.SCM(SCH_1):UART_SYS_DBG_TX   I553 @SCM_LIB.SCM(SCH_1):PAGE10
   OB9 UART_SYS_DBG_RX @SCM_LIB.SCM(SCH_1):UART_SYS_DBG_RX   I553 @SCM_LIB.SCM(SCH_1):PAGE10
  OB10    GND @SCM_LIB.SCM(SCH_1):GND   I553 @SCM_LIB.SCM(SCH_1):PAGE10
  OB11 RST_SRST_PLD_BMC_R_N @SCM_LIB.SCM(SCH_1):RST_SRST_PLD_BMC_R_N   I553 @SCM_LIB.SCM(SCH_1):PAGE10
  OB12 SPI_TPM_CS_N @SCM_LIB.SCM(SCH_1):SPI_TPM_CS_N   I553 @SCM_LIB.SCM(SCH_1):PAGE10
  OB13 H_CPU_CATERR_LVC2_R2_N @SCM_LIB.SCM(SCH_1):H_CPU_CATERR_LVC2_R2_N   I553 @SCM_LIB.SCM(SCH_1):PAGE10
  OB14 FM_SOL_UART_CH_SEL @SCM_LIB.SCM(SCH_1):FM_SOL_UART_CH_SEL   I553 @SCM_LIB.SCM(SCH_1):PAGE10
    B1 ESPI_HOST_LPC_BMC_CLK @SCM_LIB.SCM(SCH_1):ESPI_HOST_LPC_BMC_CLK   I553 @SCM_LIB.SCM(SCH_1):PAGE10
    B2 ESPI_HOST_LPC_BMC_LFRAME_N @SCM_LIB.SCM(SCH_1):ESPI_HOST_LPC_BMC_LFRAME_N   I553 @SCM_LIB.SCM(SCH_1):PAGE10
    B3 IRQ_BMC_LPC_SERIRQ_ESPI_GF @SCM_LIB.SCM(SCH_1):IRQ_BMC_LPC_SERIRQ_ESPI_GF   I553 @SCM_LIB.SCM(SCH_1):PAGE10
    B4 RST_BMC_LPC_ESPI_N @SCM_LIB.SCM(SCH_1):RST_BMC_LPC_ESPI_N   I553 @SCM_LIB.SCM(SCH_1):PAGE10
    B5 ESPI_LPC_LAD0_IO0 @SCM_LIB.SCM(SCH_1):ESPI_LPC_LAD0_IO0   I553 @SCM_LIB.SCM(SCH_1):PAGE10
    B6 ESPI_LPC_LAD1_IO1 @SCM_LIB.SCM(SCH_1):ESPI_LPC_LAD1_IO1   I553 @SCM_LIB.SCM(SCH_1):PAGE10
    B7 ESPI_LPC_LAD2_IO2 @SCM_LIB.SCM(SCH_1):ESPI_LPC_LAD2_IO2   I553 @SCM_LIB.SCM(SCH_1):PAGE10
    B8 ESPI_LPC_LAD3_IO3 @SCM_LIB.SCM(SCH_1):ESPI_LPC_LAD3_IO3   I553 @SCM_LIB.SCM(SCH_1):PAGE10
    B9 LPC_ESPI_SEL @SCM_LIB.SCM(SCH_1):LPC_ESPI_SEL   I553 @SCM_LIB.SCM(SCH_1):PAGE10
   B10    GND @SCM_LIB.SCM(SCH_1):GND   I553 @SCM_LIB.SCM(SCH_1):PAGE10
   B11 SPI_SYS_R_CLK @SCM_LIB.SCM(SCH_1):SPI_SYS_R_CLK   I553 @SCM_LIB.SCM(SCH_1):PAGE10
   B12 SPI_SYS_CS0_N @SCM_LIB.SCM(SCH_1):SPI_SYS_CS0_N   I553 @SCM_LIB.SCM(SCH_1):PAGE10
   B13 SPI_SYS_R_MOSI @SCM_LIB.SCM(SCH_1):SPI_SYS_R_MOSI   I553 @SCM_LIB.SCM(SCH_1):PAGE10
   B14 SPI_SYS_R_MISO @SCM_LIB.SCM(SCH_1):SPI_SYS_R_MISO   I553 @SCM_LIB.SCM(SCH_1):PAGE10
   B15 SPI_SYS_WP_R_IO2 @SCM_LIB.SCM(SCH_1):SPI_SYS_WP_R_IO2   I553 @SCM_LIB.SCM(SCH_1):PAGE10
   B16 SPI_SYS_HOLD_R_IO3 @SCM_LIB.SCM(SCH_1):SPI_SYS_HOLD_R_IO3   I553 @SCM_LIB.SCM(SCH_1):PAGE10
   B17    GND @SCM_LIB.SCM(SCH_1):GND   I553 @SCM_LIB.SCM(SCH_1):PAGE10
   B18 RMII_OCP_RCLKI @SCM_LIB.SCM(SCH_1):RMII_OCP_RCLKI   I553 @SCM_LIB.SCM(SCH_1):PAGE10
   B19 RMII_CSRDV @SCM_LIB.SCM(SCH_1):RMII_CSRDV   I553 @SCM_LIB.SCM(SCH_1):PAGE10
   B20 RMII_TXEN @SCM_LIB.SCM(SCH_1):RMII_TXEN   I553 @SCM_LIB.SCM(SCH_1):PAGE10
   B21 RMII_TXD0 @SCM_LIB.SCM(SCH_1):RMII_TXD0   I553 @SCM_LIB.SCM(SCH_1):PAGE10
   B22 RMII_TXD1 @SCM_LIB.SCM(SCH_1):RMII_TXD1   I553 @SCM_LIB.SCM(SCH_1):PAGE10
   B23 RMII_RXER @SCM_LIB.SCM(SCH_1):RMII_RXER   I553 @SCM_LIB.SCM(SCH_1):PAGE10
   B24 RMII_RXD0 @SCM_LIB.SCM(SCH_1):RMII_RXD0   I553 @SCM_LIB.SCM(SCH_1):PAGE10
   B25 RMII_RXD1 @SCM_LIB.SCM(SCH_1):RMII_RXD1   I553 @SCM_LIB.SCM(SCH_1):PAGE10
   B26    GND @SCM_LIB.SCM(SCH_1):GND   I553 @SCM_LIB.SCM(SCH_1):PAGE10
   B27 PECI_BMC @SCM_LIB.SCM(SCH_1):PECI_BMC   I553 @SCM_LIB.SCM(SCH_1):PAGE10
   B28 PVCCIO_PECI_BMC @SCM_LIB.SCM(SCH_1):PVCCIO_PECI_BMC   I553 @SCM_LIB.SCM(SCH_1):PAGE10
   B29 SGPIO_DO_0 @SCM_LIB.SCM(SCH_1):SGPIO_DO_0   I553 @SCM_LIB.SCM(SCH_1):PAGE10
   B30 SGPIO_CLK_0 @SCM_LIB.SCM(SCH_1):SGPIO_CLK_0   I553 @SCM_LIB.SCM(SCH_1):PAGE10
   B31 SGPIO_DI_0 @SCM_LIB.SCM(SCH_1):SGPIO_DI_0   I553 @SCM_LIB.SCM(SCH_1):PAGE10
   B32 SGPIO_LD_0 @SCM_LIB.SCM(SCH_1):SGPIO_LD_0   I553 @SCM_LIB.SCM(SCH_1):PAGE10
   B33    GND @SCM_LIB.SCM(SCH_1):GND   I553 @SCM_LIB.SCM(SCH_1):PAGE10
   B34 SGPIO_DO_1 @SCM_LIB.SCM(SCH_1):SGPIO_DO_1   I553 @SCM_LIB.SCM(SCH_1):PAGE10
   B35 SGPIO_CLK_1 @SCM_LIB.SCM(SCH_1):SGPIO_CLK_1   I553 @SCM_LIB.SCM(SCH_1):PAGE10
   B36 SGPIO_DI_1 @SCM_LIB.SCM(SCH_1):SGPIO_DI_1   I553 @SCM_LIB.SCM(SCH_1):PAGE10
   B37 SGPIO_LD_1 @SCM_LIB.SCM(SCH_1):SGPIO_LD_1   I553 @SCM_LIB.SCM(SCH_1):PAGE10
   B38    GND @SCM_LIB.SCM(SCH_1):GND   I553 @SCM_LIB.SCM(SCH_1):PAGE10
   B39 RST_SGPIO_RESET_N @SCM_LIB.SCM(SCH_1):RST_SGPIO_RESET_N   I553 @SCM_LIB.SCM(SCH_1):PAGE10
   B40 IRQ_SGPIO_N @SCM_LIB.SCM(SCH_1):IRQ_SGPIO_N   I553 @SCM_LIB.SCM(SCH_1):PAGE10
   B41 P3V_BAT_R @SCM_LIB.SCM(SCH_1):P3V_BAT_R   I553 @SCM_LIB.SCM(SCH_1):PAGE10
   B42 AC_PWR_BTN_N @SCM_LIB.SCM(SCH_1):AC_PWR_BTN_N   I553 @SCM_LIB.SCM(SCH_1):PAGE10
   B43 QSPI_2_PLD_CLK @SCM_LIB.SCM(SCH_1):QSPI_2_PLD_CLK   I553 @SCM_LIB.SCM(SCH_1):PAGE10
   B44 TP_GF1_B44 @SCM_LIB.SCM(SCH_1):TP_GF1_B44   I553 @SCM_LIB.SCM(SCH_1):PAGE10
   B45 QSPI_2_PLD_IO0 @SCM_LIB.SCM(SCH_1):QSPI_2_PLD_IO0   I553 @SCM_LIB.SCM(SCH_1):PAGE10
   B46 QSPI_2_PLD_IO1 @SCM_LIB.SCM(SCH_1):QSPI_2_PLD_IO1   I553 @SCM_LIB.SCM(SCH_1):PAGE10
   B47 QSPI_2_PLD_IO2 @SCM_LIB.SCM(SCH_1):QSPI_2_PLD_IO2   I553 @SCM_LIB.SCM(SCH_1):PAGE10
   B48 QSPI_2_PLD_IO3 @SCM_LIB.SCM(SCH_1):QSPI_2_PLD_IO3   I553 @SCM_LIB.SCM(SCH_1):PAGE10
   B49    GND @SCM_LIB.SCM(SCH_1):GND   I553 @SCM_LIB.SCM(SCH_1):PAGE10
   B50 USB_HOST_BMC_B_DP @SCM_LIB.SCM(SCH_1):USB_HOST_BMC_B_DP   I553 @SCM_LIB.SCM(SCH_1):PAGE10
   B51 USB_HOST_BMC_B_DN @SCM_LIB.SCM(SCH_1):USB_HOST_BMC_B_DN   I553 @SCM_LIB.SCM(SCH_1):PAGE10
   B52    GND @SCM_LIB.SCM(SCH_1):GND   I553 @SCM_LIB.SCM(SCH_1):PAGE10
   B53 USB_HOST_BMC_A_DP @SCM_LIB.SCM(SCH_1):USB_HOST_BMC_A_DP   I553 @SCM_LIB.SCM(SCH_1):PAGE10
   B54 USB_HOST_BMC_A_DN @SCM_LIB.SCM(SCH_1):USB_HOST_BMC_A_DN   I553 @SCM_LIB.SCM(SCH_1):PAGE10
   B55    GND @SCM_LIB.SCM(SCH_1):GND   I553 @SCM_LIB.SCM(SCH_1):PAGE10
   B56 USB_FPNL_DP @SCM_LIB.SCM(SCH_1):USB_FPNL_DP   I553 @SCM_LIB.SCM(SCH_1):PAGE10
   B57 USB_FPNL_DN @SCM_LIB.SCM(SCH_1):USB_FPNL_DN   I553 @SCM_LIB.SCM(SCH_1):PAGE10
   B58    GND @SCM_LIB.SCM(SCH_1):GND   I553 @SCM_LIB.SCM(SCH_1):PAGE10
   B59 USB3_FPNL_TXP @SCM_LIB.SCM(SCH_1):USB3_FPNL_TXP   I553 @SCM_LIB.SCM(SCH_1):PAGE10
   B60 USB3_FPNL_TXN @SCM_LIB.SCM(SCH_1):USB3_FPNL_TXN   I553 @SCM_LIB.SCM(SCH_1):PAGE10
   B61    GND @SCM_LIB.SCM(SCH_1):GND   I553 @SCM_LIB.SCM(SCH_1):PAGE10
   B62 TP_GF_B62 @SCM_LIB.SCM(SCH_1):TP_GF_B62   I553 @SCM_LIB.SCM(SCH_1):PAGE10
   B63 TP_GF_B63 @SCM_LIB.SCM(SCH_1):TP_GF_B63   I553 @SCM_LIB.SCM(SCH_1):PAGE10
   B64    GND @SCM_LIB.SCM(SCH_1):GND   I553 @SCM_LIB.SCM(SCH_1):PAGE10
   B65 P2E_GPU_TX_C_DP @SCM_LIB.SCM(SCH_1):P2E_GPU_TX_C_DP   I553 @SCM_LIB.SCM(SCH_1):PAGE10
   B66 P2E_GPU_TX_C_DN @SCM_LIB.SCM(SCH_1):P2E_GPU_TX_C_DN   I553 @SCM_LIB.SCM(SCH_1):PAGE10
   B67    GND @SCM_LIB.SCM(SCH_1):GND   I553 @SCM_LIB.SCM(SCH_1):PAGE10
   B68 HDD_LED_R_N @SCM_LIB.SCM(SCH_1):HDD_LED_R_N   I553 @SCM_LIB.SCM(SCH_1):PAGE10
   B69 PCH_BEEP_R_LED @SCM_LIB.SCM(SCH_1):PCH_BEEP_R_LED   I553 @SCM_LIB.SCM(SCH_1):PAGE10
   B70    GND @SCM_LIB.SCM(SCH_1):GND   I553 @SCM_LIB.SCM(SCH_1):PAGE10

  H1 HOLE_TH-EMPTY,HOLE1248
     1    GND @SCM_LIB.SCM(SCH_1):GND    I49 @SCM_LIB.SCM(SCH_1):PAGE57

  H2 HOLE_TH-EMPTY,HOLE1247
     1     NC     NC    I45 @SCM_LIB.SCM(SCH_1):PAGE57

H2B1 HOLE_TH-EMPTY,DUMMY50
     1     NC     NC    I14 @SCM_LIB.SCM(SCH_1):PAGE57

H2B2 HOLE_TH-EMPTY,DUMMY50
     1     NC     NC    I34 @SCM_LIB.SCM(SCH_1):PAGE57

  H3 HOLE_TH-EMPTY,HOLE620
     1    GND @SCM_LIB.SCM(SCH_1):GND    I38 @SCM_LIB.SCM(SCH_1):PAGE57

  H4 HOLE_TH-EMPTY,HOLE620
     1    GND @SCM_LIB.SCM(SCH_1):GND    I40 @SCM_LIB.SCM(SCH_1):PAGE57

  H5 HOLE_TH-EMPTY,HOLE1211
     1    GND @SCM_LIB.SCM(SCH_1):GND    I35 @SCM_LIB.SCM(SCH_1):PAGE57

  H6 HOLE_TH-EMPTY,TMP-C_HOLE8
     1    GND @SCM_LIB.SCM(SCH_1):GND    I50 @SCM_LIB.SCM(SCH_1):PAGE57

  H7 HOLE_TH-EMPTY,TMP-C_HOLE8
     1    GND @SCM_LIB.SCM(SCH_1):GND    I51 @SCM_LIB.SCM(SCH_1):PAGE57

  H9 HOLE_TH-EMPTY,HOLE1211
     1    GND @SCM_LIB.SCM(SCH_1):GND    I36 @SCM_LIB.SCM(SCH_1):PAGE57

  J1 SCONN3_212H9103GBR1-SCONN3_212A
     3 NC_J1_P3 @SCM_LIB.SCM(SCH_1):NC_J1_P3   I169 @SCM_LIB.SCM(SCH_1):PAGE25
     2 FLASH_LATCH_Q_N_R2 @SCM_LIB.SCM(SCH_1):FLASH_LATCH_Q_N_R2   I169 @SCM_LIB.SCM(SCH_1):PAGE25
     1 PU_J1_P1 @SCM_LIB.SCM(SCH_1):PU_J1_P1   I169 @SCM_LIB.SCM(SCH_1):PAGE25

  J2 CONN9_GSB3111315HR-CONN9_GSB31A
     1 P5V_USB_REAR @SCM_LIB.SCM(SCH_1):P5V_USB_REAR   I221 @SCM_LIB.SCM(SCH_1):PAGE29
     4    GND @SCM_LIB.SCM(SCH_1):GND   I221 @SCM_LIB.SCM(SCH_1):PAGE29
    G1    GND @SCM_LIB.SCM(SCH_1):GND   I221 @SCM_LIB.SCM(SCH_1):PAGE29
    G2    GND @SCM_LIB.SCM(SCH_1):GND   I221 @SCM_LIB.SCM(SCH_1):PAGE29
     9 USB3_01_FB_TXP @SCM_LIB.SCM(SCH_1):USB3_01_FB_TXP   I221 @SCM_LIB.SCM(SCH_1):PAGE29
     8 USB3_01_FB_TXN @SCM_LIB.SCM(SCH_1):USB3_01_FB_TXN   I221 @SCM_LIB.SCM(SCH_1):PAGE29
     2 USB2_01_F_DN @SCM_LIB.SCM(SCH_1):USB2_01_F_DN   I221 @SCM_LIB.SCM(SCH_1):PAGE29
     3 USB2_01_F_DP @SCM_LIB.SCM(SCH_1):USB2_01_F_DP   I221 @SCM_LIB.SCM(SCH_1):PAGE29
     6 USB3_01_FB_RXP @SCM_LIB.SCM(SCH_1):USB3_01_FB_RXP   I221 @SCM_LIB.SCM(SCH_1):PAGE29
     7 DEBUG_PORT_PRSNT_R @SCM_LIB.SCM(SCH_1):DEBUG_PORT_PRSNT_R   I221 @SCM_LIB.SCM(SCH_1):PAGE29
     5 USB3_01_FB_RXN @SCM_LIB.SCM(SCH_1):USB3_01_FB_RXN   I221 @SCM_LIB.SCM(SCH_1):PAGE29

  J4 SCONN67_NASA0S6730TS67-SCONN67A
     2 P3V3_AUX @SCM_LIB.SCM(SCH_1):P3V3_AUX    I84 @SCM_LIB.SCM(SCH_1):PAGE21
     4 P3V3_AUX @SCM_LIB.SCM(SCH_1):P3V3_AUX    I84 @SCM_LIB.SCM(SCH_1):PAGE21
     6     NC     NC    I84 @SCM_LIB.SCM(SCH_1):PAGE21
    16 BSM_PRSNT_N @SCM_LIB.SCM(SCH_1):BSM_PRSNT_N    I84 @SCM_LIB.SCM(SCH_1):PAGE21
    18    GND @SCM_LIB.SCM(SCH_1):GND    I84 @SCM_LIB.SCM(SCH_1):PAGE21
    20     NC     NC    I84 @SCM_LIB.SCM(SCH_1):PAGE21
    22     NC     NC    I84 @SCM_LIB.SCM(SCH_1):PAGE21
    24    GND @SCM_LIB.SCM(SCH_1):GND    I84 @SCM_LIB.SCM(SCH_1):PAGE21
    26 SPI_BMC_HOLD1_N @SCM_LIB.SCM(SCH_1):SPI_BMC_HOLD1_N    I84 @SCM_LIB.SCM(SCH_1):PAGE21
    28 SPI_BMC_HOLD0_N @SCM_LIB.SCM(SCH_1):SPI_BMC_HOLD0_N    I84 @SCM_LIB.SCM(SCH_1):PAGE21
    30    GND @SCM_LIB.SCM(SCH_1):GND    I84 @SCM_LIB.SCM(SCH_1):PAGE21
    32     NC     NC    I84 @SCM_LIB.SCM(SCH_1):PAGE21
    34     NC     NC    I84 @SCM_LIB.SCM(SCH_1):PAGE21
    36    GND @SCM_LIB.SCM(SCH_1):GND    I84 @SCM_LIB.SCM(SCH_1):PAGE21
    38     NC     NC    I84 @SCM_LIB.SCM(SCH_1):PAGE21
    40 SMB_BMC_MM16_R1_SCL @SCM_LIB.SCM(SCH_1):SMB_BMC_MM16_R1_SCL    I84 @SCM_LIB.SCM(SCH_1):PAGE21
    42 SMB_BMC_MM16_R1_SDA @SCM_LIB.SCM(SCH_1):SMB_BMC_MM16_R1_SDA    I84 @SCM_LIB.SCM(SCH_1):PAGE21
    44     NC     NC    I84 @SCM_LIB.SCM(SCH_1):PAGE21
    46 EMMC_WP @SCM_LIB.SCM(SCH_1):EMMC_WP    I84 @SCM_LIB.SCM(SCH_1):PAGE21
    48     NC     NC    I84 @SCM_LIB.SCM(SCH_1):PAGE21
    50     NC     NC    I84 @SCM_LIB.SCM(SCH_1):PAGE21
    52 EMMC_DT7_R @SCM_LIB.SCM(SCH_1):EMMC_DT7_R    I84 @SCM_LIB.SCM(SCH_1):PAGE21
    54 EMMC_DT6_R @SCM_LIB.SCM(SCH_1):EMMC_DT6_R    I84 @SCM_LIB.SCM(SCH_1):PAGE21
    56 EMMC_DT5_R @SCM_LIB.SCM(SCH_1):EMMC_DT5_R    I84 @SCM_LIB.SCM(SCH_1):PAGE21
    58 EMMC_DT4_R @SCM_LIB.SCM(SCH_1):EMMC_DT4_R    I84 @SCM_LIB.SCM(SCH_1):PAGE21
    60     NC     NC    I84 @SCM_LIB.SCM(SCH_1):PAGE21
    62     NC     NC    I84 @SCM_LIB.SCM(SCH_1):PAGE21
    64     NC     NC    I84 @SCM_LIB.SCM(SCH_1):PAGE21
    66 BMC_EMMC_RST_N @SCM_LIB.SCM(SCH_1):BMC_EMMC_RST_N    I84 @SCM_LIB.SCM(SCH_1):PAGE21
    68     NC     NC    I84 @SCM_LIB.SCM(SCH_1):PAGE21
    70     NC     NC    I84 @SCM_LIB.SCM(SCH_1):PAGE21
    72 P3V3_AUX @SCM_LIB.SCM(SCH_1):P3V3_AUX    I84 @SCM_LIB.SCM(SCH_1):PAGE21
    74 P3V3_AUX @SCM_LIB.SCM(SCH_1):P3V3_AUX    I84 @SCM_LIB.SCM(SCH_1):PAGE21
     1    GND @SCM_LIB.SCM(SCH_1):GND    I84 @SCM_LIB.SCM(SCH_1):PAGE21
     3 SPI_BMC_BT_WP1_N_R @SCM_LIB.SCM(SCH_1):SPI_BMC_BT_WP1_N_R    I84 @SCM_LIB.SCM(SCH_1):PAGE21
     5 SPI_BMC_BT_WP0_N_R @SCM_LIB.SCM(SCH_1):SPI_BMC_BT_WP0_N_R    I84 @SCM_LIB.SCM(SCH_1):PAGE21
     7    GND @SCM_LIB.SCM(SCH_1):GND    I84 @SCM_LIB.SCM(SCH_1):PAGE21
    17     NC     NC    I84 @SCM_LIB.SCM(SCH_1):PAGE21
    19 RST_SPI_BMC_FLASH_R2_N @SCM_LIB.SCM(SCH_1):RST_SPI_BMC_FLASH_R2_N    I84 @SCM_LIB.SCM(SCH_1):PAGE21
    21 RST_SPI_BMC_FLASH_R1_N @SCM_LIB.SCM(SCH_1):RST_SPI_BMC_FLASH_R1_N    I84 @SCM_LIB.SCM(SCH_1):PAGE21
    23    GND @SCM_LIB.SCM(SCH_1):GND    I84 @SCM_LIB.SCM(SCH_1):PAGE21
    25 SPI_BMC_IO1_FLASH_R @SCM_LIB.SCM(SCH_1):SPI_BMC_IO1_FLASH_R    I84 @SCM_LIB.SCM(SCH_1):PAGE21
    27 SPI_BMC_IO0_FLASH_R @SCM_LIB.SCM(SCH_1):SPI_BMC_IO0_FLASH_R    I84 @SCM_LIB.SCM(SCH_1):PAGE21
    29    GND @SCM_LIB.SCM(SCH_1):GND    I84 @SCM_LIB.SCM(SCH_1):PAGE21
    31 SPI_BMC_CLK_FLASH_R @SCM_LIB.SCM(SCH_1):SPI_BMC_CLK_FLASH_R    I84 @SCM_LIB.SCM(SCH_1):PAGE21
    33    GND @SCM_LIB.SCM(SCH_1):GND    I84 @SCM_LIB.SCM(SCH_1):PAGE21
    35 SPI_BMC_CS1_FLASH_R_N @SCM_LIB.SCM(SCH_1):SPI_BMC_CS1_FLASH_R_N    I84 @SCM_LIB.SCM(SCH_1):PAGE21
    37 SPI_BMC_CS0_FLASH_R_N @SCM_LIB.SCM(SCH_1):SPI_BMC_CS0_FLASH_R_N    I84 @SCM_LIB.SCM(SCH_1):PAGE21
    39    GND @SCM_LIB.SCM(SCH_1):GND    I84 @SCM_LIB.SCM(SCH_1):PAGE21
    41     NC     NC    I84 @SCM_LIB.SCM(SCH_1):PAGE21
    43     NC     NC    I84 @SCM_LIB.SCM(SCH_1):PAGE21
    45    GND @SCM_LIB.SCM(SCH_1):GND    I84 @SCM_LIB.SCM(SCH_1):PAGE21
    47     NC     NC    I84 @SCM_LIB.SCM(SCH_1):PAGE21
    49     NC     NC    I84 @SCM_LIB.SCM(SCH_1):PAGE21
    51    GND @SCM_LIB.SCM(SCH_1):GND    I84 @SCM_LIB.SCM(SCH_1):PAGE21
    53     NC     NC    I84 @SCM_LIB.SCM(SCH_1):PAGE21
    55 EMMC_CLK_R @SCM_LIB.SCM(SCH_1):EMMC_CLK_R    I84 @SCM_LIB.SCM(SCH_1):PAGE21
    57    GND @SCM_LIB.SCM(SCH_1):GND    I84 @SCM_LIB.SCM(SCH_1):PAGE21
    59 EMMC_CMD_R @SCM_LIB.SCM(SCH_1):EMMC_CMD_R    I84 @SCM_LIB.SCM(SCH_1):PAGE21
    61 EMMC_DT3_R @SCM_LIB.SCM(SCH_1):EMMC_DT3_R    I84 @SCM_LIB.SCM(SCH_1):PAGE21
    63    GND @SCM_LIB.SCM(SCH_1):GND    I84 @SCM_LIB.SCM(SCH_1):PAGE21
    65 EMMC_DT2_R @SCM_LIB.SCM(SCH_1):EMMC_DT2_R    I84 @SCM_LIB.SCM(SCH_1):PAGE21
    67 EMMC_DT1_R @SCM_LIB.SCM(SCH_1):EMMC_DT1_R    I84 @SCM_LIB.SCM(SCH_1):PAGE21
    69    GND @SCM_LIB.SCM(SCH_1):GND    I84 @SCM_LIB.SCM(SCH_1):PAGE21
    71 EMMC_DT0_R @SCM_LIB.SCM(SCH_1):EMMC_DT0_R    I84 @SCM_LIB.SCM(SCH_1):PAGE21
    73     NC     NC    I84 @SCM_LIB.SCM(SCH_1):PAGE21
    75    GND @SCM_LIB.SCM(SCH_1):GND    I84 @SCM_LIB.SCM(SCH_1):PAGE21
    G1    GND @SCM_LIB.SCM(SCH_1):GND    I84 @SCM_LIB.SCM(SCH_1):PAGE21
    G2    GND @SCM_LIB.SCM(SCH_1):GND    I84 @SCM_LIB.SCM(SCH_1):PAGE21

  J5 SCONN11_9192031111LF-SCONN11_9A
     1 SPI_SYS_R1_CLK @SCM_LIB.SCM(SCH_1):SPI_SYS_R1_CLK    I56 @SCM_LIB.SCM(SCH_1):PAGE46
     3 SPI_SYS_R1_MOSI @SCM_LIB.SCM(SCH_1):SPI_SYS_R1_MOSI    I56 @SCM_LIB.SCM(SCH_1):PAGE46
     4 SPI_SYS_R1_MISO @SCM_LIB.SCM(SCH_1):SPI_SYS_R1_MISO    I56 @SCM_LIB.SCM(SCH_1):PAGE46
     5 SPI_TPM_CS_N_R @SCM_LIB.SCM(SCH_1):SPI_TPM_CS_N_R    I56 @SCM_LIB.SCM(SCH_1):PAGE46
     2 RST_PLTRST_TPM_N @SCM_LIB.SCM(SCH_1):RST_PLTRST_TPM_N    I56 @SCM_LIB.SCM(SCH_1):PAGE46
    G1    GND @SCM_LIB.SCM(SCH_1):GND    I56 @SCM_LIB.SCM(SCH_1):PAGE46
    G2    GND @SCM_LIB.SCM(SCH_1):GND    I56 @SCM_LIB.SCM(SCH_1):PAGE46
     6 SMB_PCH_TPM_SDA @SCM_LIB.SCM(SCH_1):SMB_PCH_TPM_SDA    I56 @SCM_LIB.SCM(SCH_1):PAGE46
     7 P3V3_AUX @SCM_LIB.SCM(SCH_1):P3V3_AUX    I56 @SCM_LIB.SCM(SCH_1):PAGE46
     8 FM_TPM_PRSNT_0_N @SCM_LIB.SCM(SCH_1):FM_TPM_PRSNT_0_N    I56 @SCM_LIB.SCM(SCH_1):PAGE46
     9 IRQ_PCH_TPM_SPI_R_N @SCM_LIB.SCM(SCH_1):IRQ_PCH_TPM_SPI_R_N    I56 @SCM_LIB.SCM(SCH_1):PAGE46
    10 SMB_PCH_TPM_SCL @SCM_LIB.SCM(SCH_1):SMB_PCH_TPM_SCL    I56 @SCM_LIB.SCM(SCH_1):PAGE46
    11    GND @SCM_LIB.SCM(SCH_1):GND    I56 @SCM_LIB.SCM(SCH_1):PAGE46

  J6 SCONN3_21291035BR2-SCONN3_212-A
     3 UART_BMC_5_RXD_BUF @SCM_LIB.SCM(SCH_1):UART_BMC_5_RXD_BUF   I184 @SCM_LIB.SCM(SCH_1):PAGE30
     2    GND @SCM_LIB.SCM(SCH_1):GND   I184 @SCM_LIB.SCM(SCH_1):PAGE30
     1 UART_BMC_5_TXD_BUF_R @SCM_LIB.SCM(SCH_1):UART_BMC_5_TXD_BUF_R   I184 @SCM_LIB.SCM(SCH_1):PAGE30

  J7 CONN8_210HP1080BR1-CONN8_210-HA
     1  J7_P1 @SCM_LIB.SCM(SCH_1):J7_P1   I132 @SCM_LIB.SCM(SCH_1):PAGE32
     2 JTAG_SCM_CONN_TDO @SCM_LIB.SCM(SCH_1):JTAG_SCM_CONN_TDO   I132 @SCM_LIB.SCM(SCH_1):PAGE32
     3 JTAG_SCM_CONN_TDI @SCM_LIB.SCM(SCH_1):JTAG_SCM_CONN_TDI   I132 @SCM_LIB.SCM(SCH_1):PAGE32
     4 JTAG_SCM_PLD_R1_JTAGEN @SCM_LIB.SCM(SCH_1):JTAG_SCM_PLD_R1_JTAGEN   I132 @SCM_LIB.SCM(SCH_1):PAGE32
     5 TP_PLD_CONN_P5 @SCM_LIB.SCM(SCH_1):TP_PLD_CONN_P5   I132 @SCM_LIB.SCM(SCH_1):PAGE32
     6 JTAG_SCM_CONN_TMS @SCM_LIB.SCM(SCH_1):JTAG_SCM_CONN_TMS   I132 @SCM_LIB.SCM(SCH_1):PAGE32
     7    GND @SCM_LIB.SCM(SCH_1):GND   I132 @SCM_LIB.SCM(SCH_1):PAGE32
     8 JTAG_SCM_CONN_TCK @SCM_LIB.SCM(SCH_1):JTAG_SCM_CONN_TCK   I132 @SCM_LIB.SCM(SCH_1):PAGE32

  J8 SCONN13_502280130CV01-SCONN13_A
     1 V_DACR_IO @SCM_LIB.SCM(SCH_1):V_DACR_IO   I165 @SCM_LIB.SCM(SCH_1):PAGE23
     2    GND @SCM_LIB.SCM(SCH_1):GND   I165 @SCM_LIB.SCM(SCH_1):PAGE23
     3 V_DACG_IO @SCM_LIB.SCM(SCH_1):V_DACG_IO   I165 @SCM_LIB.SCM(SCH_1):PAGE23
     4    GND @SCM_LIB.SCM(SCH_1):GND   I165 @SCM_LIB.SCM(SCH_1):PAGE23
     5 V_DACB_IO @SCM_LIB.SCM(SCH_1):V_DACB_IO   I165 @SCM_LIB.SCM(SCH_1):PAGE23
     6    GND @SCM_LIB.SCM(SCH_1):GND   I165 @SCM_LIB.SCM(SCH_1):PAGE23
     7 V_VGAVS_BUF @SCM_LIB.SCM(SCH_1):V_VGAVS_BUF   I165 @SCM_LIB.SCM(SCH_1):PAGE23
     8    GND @SCM_LIB.SCM(SCH_1):GND   I165 @SCM_LIB.SCM(SCH_1):PAGE23
     9 V_VGAHS_BUF @SCM_LIB.SCM(SCH_1):V_VGAHS_BUF   I165 @SCM_LIB.SCM(SCH_1):PAGE23
    10    GND @SCM_LIB.SCM(SCH_1):GND   I165 @SCM_LIB.SCM(SCH_1):PAGE23
    11 V_BMC_LS_DDC_SDA_R @SCM_LIB.SCM(SCH_1):V_BMC_LS_DDC_SDA_R   I165 @SCM_LIB.SCM(SCH_1):PAGE23
    12 V_BMC_LS_DDC_SCL_R @SCM_LIB.SCM(SCH_1):V_BMC_LS_DDC_SCL_R   I165 @SCM_LIB.SCM(SCH_1):PAGE23
    13 CRT_VCC5_2_FUSE @SCM_LIB.SCM(SCH_1):CRT_VCC5_2_FUSE   I165 @SCM_LIB.SCM(SCH_1):PAGE23
    G1    GND @SCM_LIB.SCM(SCH_1):GND   I165 @SCM_LIB.SCM(SCH_1):PAGE23
    G2    GND @SCM_LIB.SCM(SCH_1):GND   I165 @SCM_LIB.SCM(SCH_1):PAGE23

  J9 PICOPROBE_BXA-DELTA-L 4.0,SMLFA
     2 85_5INCH_TOP_DP @SCM_LIB.SCM(SCH_1):85_5INCH_TOP_DP    I55 @SCM_LIB.SCM(SCH_1):PAGE58
     3 GND_P1 @SCM_LIB.SCM(SCH_1):GND_P1    I55 @SCM_LIB.SCM(SCH_1):PAGE58
     1 85_5INCH_TOP_DN @SCM_LIB.SCM(SCH_1):85_5INCH_TOP_DN    I55 @SCM_LIB.SCM(SCH_1):PAGE58

 J10 SCONN11_9192031111LF-SCONN11_9A
     1 SPI_BMC_TPM_CLK_R @SCM_LIB.SCM(SCH_1):SPI_BMC_TPM_CLK_R   I113 @SCM_LIB.SCM(SCH_1):PAGE46
     3 SPI_BMC_TPM_MOSI_R @SCM_LIB.SCM(SCH_1):SPI_BMC_TPM_MOSI_R   I113 @SCM_LIB.SCM(SCH_1):PAGE46
     4 SPI_BMC_TPM_MISO_R @SCM_LIB.SCM(SCH_1):SPI_BMC_TPM_MISO_R   I113 @SCM_LIB.SCM(SCH_1):PAGE46
     5 SPI_BMC_TPM_CS2_N_R @SCM_LIB.SCM(SCH_1):SPI_BMC_TPM_CS2_N_R   I113 @SCM_LIB.SCM(SCH_1):PAGE46
     2 RST_BMC_EXTRST_R3_N @SCM_LIB.SCM(SCH_1):RST_BMC_EXTRST_R3_N   I113 @SCM_LIB.SCM(SCH_1):PAGE46
    G1    GND @SCM_LIB.SCM(SCH_1):GND   I113 @SCM_LIB.SCM(SCH_1):PAGE46
    G2    GND @SCM_LIB.SCM(SCH_1):GND   I113 @SCM_LIB.SCM(SCH_1):PAGE46
     6 SMB_BMC_TPM_MM16_SDA @SCM_LIB.SCM(SCH_1):SMB_BMC_TPM_MM16_SDA   I113 @SCM_LIB.SCM(SCH_1):PAGE46
     7 P3V3_AUX @SCM_LIB.SCM(SCH_1):P3V3_AUX   I113 @SCM_LIB.SCM(SCH_1):PAGE46
     8 FM_TPM_PRSNT_1_N @SCM_LIB.SCM(SCH_1):FM_TPM_PRSNT_1_N   I113 @SCM_LIB.SCM(SCH_1):PAGE46
     9 IRQ_BMC_TPM_SPI_R_N @SCM_LIB.SCM(SCH_1):IRQ_BMC_TPM_SPI_R_N   I113 @SCM_LIB.SCM(SCH_1):PAGE46
    10 SMB_BMC_TPM_MM16_SCL @SCM_LIB.SCM(SCH_1):SMB_BMC_TPM_MM16_SCL   I113 @SCM_LIB.SCM(SCH_1):PAGE46
    11    GND @SCM_LIB.SCM(SCH_1):GND   I113 @SCM_LIB.SCM(SCH_1):PAGE46

 J11 PICOPROBE_BXA-DELTA-L 4.0,SMLFA
     2 85_5INCH_IN1_DP @SCM_LIB.SCM(SCH_1):85_5INCH_IN1_DP    I57 @SCM_LIB.SCM(SCH_1):PAGE58
     3 GND_P1 @SCM_LIB.SCM(SCH_1):GND_P1    I57 @SCM_LIB.SCM(SCH_1):PAGE58
     1 85_5INCH_IN1_DN @SCM_LIB.SCM(SCH_1):85_5INCH_IN1_DN    I57 @SCM_LIB.SCM(SCH_1):PAGE58

 J12 PICOPROBE_BXA-DELTA-L 4.0,SMLFA
     2 85_5INCH_TOP_DN @SCM_LIB.SCM(SCH_1):85_5INCH_TOP_DN    I64 @SCM_LIB.SCM(SCH_1):PAGE58
     3 GND_P1 @SCM_LIB.SCM(SCH_1):GND_P1    I64 @SCM_LIB.SCM(SCH_1):PAGE58
     1 85_5INCH_TOP_DP @SCM_LIB.SCM(SCH_1):85_5INCH_TOP_DP    I64 @SCM_LIB.SCM(SCH_1):PAGE58

 J13 SCONN3_212H9103GBR1-SCONN3_212B
     3    GND @SCM_LIB.SCM(SCH_1):GND    I61 @SCM_LIB.SCM(SCH_1):PAGE31
     2 FM_DBG_SW_N @SCM_LIB.SCM(SCH_1):FM_DBG_SW_N    I61 @SCM_LIB.SCM(SCH_1):PAGE31
     1 PU_J13_P1 @SCM_LIB.SCM(SCH_1):PU_J13_P1    I61 @SCM_LIB.SCM(SCH_1):PAGE31

 J14 CONN8_TSW10407FD-CONN8_TSW-104A
     5 TMC75_A1 @SCM_LIB.SCM(SCH_1):TMC75_A1    I71 @SCM_LIB.SCM(SCH_1):PAGE26
     6 SMB_BMC_ALERT16_R_N @SCM_LIB.SCM(SCH_1):SMB_BMC_ALERT16_R_N    I71 @SCM_LIB.SCM(SCH_1):PAGE26
     7 TMC75_A2 @SCM_LIB.SCM(SCH_1):TMC75_A2    I71 @SCM_LIB.SCM(SCH_1):PAGE26
     8    GND @SCM_LIB.SCM(SCH_1):GND    I71 @SCM_LIB.SCM(SCH_1):PAGE26
     3 TMC75_A0 @SCM_LIB.SCM(SCH_1):TMC75_A0    I71 @SCM_LIB.SCM(SCH_1):PAGE26
     1 P3V3_AUX @SCM_LIB.SCM(SCH_1):P3V3_AUX    I71 @SCM_LIB.SCM(SCH_1):PAGE26
     4 SMB_TMP421_BMC_MM2_SCL @SCM_LIB.SCM(SCH_1):SMB_TMP421_BMC_MM2_SCL    I71 @SCM_LIB.SCM(SCH_1):PAGE26
     2 SMB_TMP421_BMC_MM2_SDA @SCM_LIB.SCM(SCH_1):SMB_TMP421_BMC_MM2_SDA    I71 @SCM_LIB.SCM(SCH_1):PAGE26

 J16 PICOPROBE_BXA-DELTA-L 4.0,SMLFA
     2 85_5INCH_IN4_DP @SCM_LIB.SCM(SCH_1):85_5INCH_IN4_DP    I58 @SCM_LIB.SCM(SCH_1):PAGE58
     3 GND_P1 @SCM_LIB.SCM(SCH_1):GND_P1    I58 @SCM_LIB.SCM(SCH_1):PAGE58
     1 85_5INCH_IN4_DN @SCM_LIB.SCM(SCH_1):85_5INCH_IN4_DN    I58 @SCM_LIB.SCM(SCH_1):PAGE58

 J17 PICOPROBE_BXA-DELTA-L 4.0,SMLFA
     2 85_5INCH_BOT_DP @SCM_LIB.SCM(SCH_1):85_5INCH_BOT_DP    I59 @SCM_LIB.SCM(SCH_1):PAGE58
     3 GND_P1 @SCM_LIB.SCM(SCH_1):GND_P1    I59 @SCM_LIB.SCM(SCH_1):PAGE58
     1 85_5INCH_BOT_DN @SCM_LIB.SCM(SCH_1):85_5INCH_BOT_DN    I59 @SCM_LIB.SCM(SCH_1):PAGE58

 J19 PICOPROBE_BXA-DELTA-L 4.0,SMLFA
     2 85_5INCH_IN4_DN @SCM_LIB.SCM(SCH_1):85_5INCH_IN4_DN    I71 @SCM_LIB.SCM(SCH_1):PAGE58
     3 GND_P1 @SCM_LIB.SCM(SCH_1):GND_P1    I71 @SCM_LIB.SCM(SCH_1):PAGE58
     1 85_5INCH_IN4_DP @SCM_LIB.SCM(SCH_1):85_5INCH_IN4_DP    I71 @SCM_LIB.SCM(SCH_1):PAGE58

 J20 PICOPROBE_BXA-DELTA-L 4.0,SMLFA
     2 85_5INCH_BOT_DN @SCM_LIB.SCM(SCH_1):85_5INCH_BOT_DN    I70 @SCM_LIB.SCM(SCH_1):PAGE58
     3 GND_P1 @SCM_LIB.SCM(SCH_1):GND_P1    I70 @SCM_LIB.SCM(SCH_1):PAGE58
     1 85_5INCH_BOT_DP @SCM_LIB.SCM(SCH_1):85_5INCH_BOT_DP    I70 @SCM_LIB.SCM(SCH_1):PAGE58

 J22 PICOPROBE_BXA-DELTA-L 4.0,SMLFA
     2 85_10INCH_TOP_DN @SCM_LIB.SCM(SCH_1):85_10INCH_TOP_DN    I66 @SCM_LIB.SCM(SCH_1):PAGE58
     3 GND_P1 @SCM_LIB.SCM(SCH_1):GND_P1    I66 @SCM_LIB.SCM(SCH_1):PAGE58
     1 85_10INCH_TOP_DP @SCM_LIB.SCM(SCH_1):85_10INCH_TOP_DP    I66 @SCM_LIB.SCM(SCH_1):PAGE58

 J23 PICOPROBE_BXA-DELTA-L 4.0,SMLFA
     2 85_10INCH_IN4_DN @SCM_LIB.SCM(SCH_1):85_10INCH_IN4_DN    I69 @SCM_LIB.SCM(SCH_1):PAGE58
     3 GND_P1 @SCM_LIB.SCM(SCH_1):GND_P1    I69 @SCM_LIB.SCM(SCH_1):PAGE58
     1 85_10INCH_IN4_DP @SCM_LIB.SCM(SCH_1):85_10INCH_IN4_DP    I69 @SCM_LIB.SCM(SCH_1):PAGE58

 J24 PICOPROBE_BXA-DELTA-L 4.0,SMLFA
     2 85_10INCH_BOT_DN @SCM_LIB.SCM(SCH_1):85_10INCH_BOT_DN    I68 @SCM_LIB.SCM(SCH_1):PAGE58
     3 GND_P1 @SCM_LIB.SCM(SCH_1):GND_P1    I68 @SCM_LIB.SCM(SCH_1):PAGE58
     1 85_10INCH_BOT_DP @SCM_LIB.SCM(SCH_1):85_10INCH_BOT_DP    I68 @SCM_LIB.SCM(SCH_1):PAGE58

 J25 PICOPROBE_BXA-DELTA-L 4.0,SMLFA
     2 85_10INCH_TOP_DP @SCM_LIB.SCM(SCH_1):85_10INCH_TOP_DP    I60 @SCM_LIB.SCM(SCH_1):PAGE58
     3 GND_P1 @SCM_LIB.SCM(SCH_1):GND_P1    I60 @SCM_LIB.SCM(SCH_1):PAGE58
     1 85_10INCH_TOP_DN @SCM_LIB.SCM(SCH_1):85_10INCH_TOP_DN    I60 @SCM_LIB.SCM(SCH_1):PAGE58

 J26 PICOPROBE_BXA-DELTA-L 4.0,SMLFA
     2 85_10INCH_IN4_DP @SCM_LIB.SCM(SCH_1):85_10INCH_IN4_DP    I62 @SCM_LIB.SCM(SCH_1):PAGE58
     3 GND_P1 @SCM_LIB.SCM(SCH_1):GND_P1    I62 @SCM_LIB.SCM(SCH_1):PAGE58
     1 85_10INCH_IN4_DN @SCM_LIB.SCM(SCH_1):85_10INCH_IN4_DN    I62 @SCM_LIB.SCM(SCH_1):PAGE58

 J27 PICOPROBE_BXA-DELTA-L 4.0,SMLFA
     2 85_10INCH_BOT_DP @SCM_LIB.SCM(SCH_1):85_10INCH_BOT_DP    I63 @SCM_LIB.SCM(SCH_1):PAGE58
     3 GND_P1 @SCM_LIB.SCM(SCH_1):GND_P1    I63 @SCM_LIB.SCM(SCH_1):PAGE58
     1 85_10INCH_BOT_DN @SCM_LIB.SCM(SCH_1):85_10INCH_BOT_DN    I63 @SCM_LIB.SCM(SCH_1):PAGE58

 J28 PICOPROBE_BXA-DELTA-L 4.0,SMLFA
     2 85_10INCH_IN1_DP @SCM_LIB.SCM(SCH_1):85_10INCH_IN1_DP    I61 @SCM_LIB.SCM(SCH_1):PAGE58
     3 GND_P1 @SCM_LIB.SCM(SCH_1):GND_P1    I61 @SCM_LIB.SCM(SCH_1):PAGE58
     1 85_10INCH_IN1_DN @SCM_LIB.SCM(SCH_1):85_10INCH_IN1_DN    I61 @SCM_LIB.SCM(SCH_1):PAGE58

 J29 PICOPROBE_BXA-DELTA-L 4.0,SMLFA
     2 85_5INCH_IN1_DN @SCM_LIB.SCM(SCH_1):85_5INCH_IN1_DN    I65 @SCM_LIB.SCM(SCH_1):PAGE58
     3 GND_P1 @SCM_LIB.SCM(SCH_1):GND_P1    I65 @SCM_LIB.SCM(SCH_1):PAGE58
     1 85_5INCH_IN1_DP @SCM_LIB.SCM(SCH_1):85_5INCH_IN1_DP    I65 @SCM_LIB.SCM(SCH_1):PAGE58

 J30 PICOPROBE_BXA-DELTA-L 4.0,SMLFA
     2 85_10INCH_IN1_DN @SCM_LIB.SCM(SCH_1):85_10INCH_IN1_DN    I67 @SCM_LIB.SCM(SCH_1):PAGE58
     3 GND_P1 @SCM_LIB.SCM(SCH_1):GND_P1    I67 @SCM_LIB.SCM(SCH_1):PAGE58
     1 85_10INCH_IN1_DP @SCM_LIB.SCM(SCH_1):85_10INCH_IN1_DP    I67 @SCM_LIB.SCM(SCH_1):PAGE58

 J40 SCONN16_ACASPI006P06-SCONN16_AA
     2 P3V3_AUX @SCM_LIB.SCM(SCH_1):P3V3_AUX    I53 @SCM_LIB.SCM(SCH_1):PAGE45
     1 SPI_PCH_IO3_FLASH_R1 @SCM_LIB.SCM(SCH_1):SPI_PCH_IO3_FLASH_R1    I53 @SCM_LIB.SCM(SCH_1):PAGE45
     7 SPI_PCH_CS0_FLASH_R1_N @SCM_LIB.SCM(SCH_1):SPI_PCH_CS0_FLASH_R1_N    I53 @SCM_LIB.SCM(SCH_1):PAGE45
     9 SPI_PCH_IO2_FLASH_R1 @SCM_LIB.SCM(SCH_1):SPI_PCH_IO2_FLASH_R1    I53 @SCM_LIB.SCM(SCH_1):PAGE45
    15 SPI_PCH_IO0_FLASH_R1 @SCM_LIB.SCM(SCH_1):SPI_PCH_IO0_FLASH_R1    I53 @SCM_LIB.SCM(SCH_1):PAGE45
    16 SPI_PCH_CLK_FLASH_R1 @SCM_LIB.SCM(SCH_1):SPI_PCH_CLK_FLASH_R1    I53 @SCM_LIB.SCM(SCH_1):PAGE45
    10    GND @SCM_LIB.SCM(SCH_1):GND    I53 @SCM_LIB.SCM(SCH_1):PAGE45
     8 SPI_PCH_IO1_FLASH_R1 @SCM_LIB.SCM(SCH_1):SPI_PCH_IO1_FLASH_R1    I53 @SCM_LIB.SCM(SCH_1):PAGE45
     3 RST_SPI_PCH_FLASH_R1_N @SCM_LIB.SCM(SCH_1):RST_SPI_PCH_FLASH_R1_N    I53 @SCM_LIB.SCM(SCH_1):PAGE45
     4 TP_J40_4 @SCM_LIB.SCM(SCH_1):TP_J40_4    I53 @SCM_LIB.SCM(SCH_1):PAGE45
     5 TP_J40_5 @SCM_LIB.SCM(SCH_1):TP_J40_5    I53 @SCM_LIB.SCM(SCH_1):PAGE45
     6 TP_J40_6 @SCM_LIB.SCM(SCH_1):TP_J40_6    I53 @SCM_LIB.SCM(SCH_1):PAGE45
    11 TP_J40_11 @SCM_LIB.SCM(SCH_1):TP_J40_11    I53 @SCM_LIB.SCM(SCH_1):PAGE45
    12 TP_J40_12 @SCM_LIB.SCM(SCH_1):TP_J40_12    I53 @SCM_LIB.SCM(SCH_1):PAGE45
    13 TP_J40_13 @SCM_LIB.SCM(SCH_1):TP_J40_13    I53 @SCM_LIB.SCM(SCH_1):PAGE45
    14 TP_J40_14 @SCM_LIB.SCM(SCH_1):TP_J40_14    I53 @SCM_LIB.SCM(SCH_1):PAGE45

  L2 Q_INDUCTOR_SMLF-BLM18PG121SN1DA
     2 P3V3_STBY_PLLAHVDD @SCM_LIB.SCM(SCH_1):P3V3_STBY_PLLAHVDD   I272 @SCM_LIB.SCM(SCH_1):PAGE17
     1 P1V2_AUX @SCM_LIB.SCM(SCH_1):P1V2_AUX   I272 @SCM_LIB.SCM(SCH_1):PAGE17

  L3 Q_INDUCTOR_SMLF-BLM18PG121SN1DA
     2 P1V8_BMC_USB2AV18 @SCM_LIB.SCM(SCH_1):P1V8_BMC_USB2AV18    I65 @SCM_LIB.SCM(SCH_1):PAGE15
     1 P1V8_AUX @SCM_LIB.SCM(SCH_1):P1V8_AUX    I65 @SCM_LIB.SCM(SCH_1):PAGE15

  L4 Q_INDUCTOR_SMLF-BLM18PG121SN1DA
     2 P3V3_BMC_USB2AV33 @SCM_LIB.SCM(SCH_1):P3V3_BMC_USB2AV33    I82 @SCM_LIB.SCM(SCH_1):PAGE15
     1 P3V3_AUX @SCM_LIB.SCM(SCH_1):P3V3_AUX    I82 @SCM_LIB.SCM(SCH_1):PAGE15

  L5 Q_INDUCTOR_SMLF-BLM18PG121SN1DA
     2 P1V8_STBY_AVDDPLL @SCM_LIB.SCM(SCH_1):P1V8_STBY_AVDDPLL   I120 @SCM_LIB.SCM(SCH_1):PAGE17
     1 P1V8_AUX @SCM_LIB.SCM(SCH_1):P1V8_AUX   I120 @SCM_LIB.SCM(SCH_1):PAGE17

  L6 Q_INDUCTOR_SMLF-BLM18PG121SN1DA
     2 P1V0_STBY_RC_VCC10A @SCM_LIB.SCM(SCH_1):P1V0_STBY_RC_VCC10A   I124 @SCM_LIB.SCM(SCH_1):PAGE17
     1 P1V0_AUX @SCM_LIB.SCM(SCH_1):P1V0_AUX   I124 @SCM_LIB.SCM(SCH_1):PAGE17

  L7 Q_INDUCTOR_SMLF-BLM18PG121SN1DA
     2 P3V3_STBY_DACAV33 @SCM_LIB.SCM(SCH_1):P3V3_STBY_DACAV33   I146 @SCM_LIB.SCM(SCH_1):PAGE17
     1 P3V3_AUX @SCM_LIB.SCM(SCH_1):P3V3_AUX   I146 @SCM_LIB.SCM(SCH_1):PAGE17

  L8 Q_INDUCTOR_SMLF-BLM18PG121SN1DA
     2 P1V0_STBY_PLAVDD @SCM_LIB.SCM(SCH_1):P1V0_STBY_PLAVDD    I29 @SCM_LIB.SCM(SCH_1):PAGE16
     1 P1V0_AUX @SCM_LIB.SCM(SCH_1):P1V0_AUX    I29 @SCM_LIB.SCM(SCH_1):PAGE16

  L9 Q_INDUCTOR_SMLF-BLM18PG121SN1DB
     2 P3V3_STBY_PLLAHVDD @SCM_LIB.SCM(SCH_1):P3V3_STBY_PLLAHVDD   I142 @SCM_LIB.SCM(SCH_1):PAGE17
     1 P3V3_AUX @SCM_LIB.SCM(SCH_1):P3V3_AUX   I142 @SCM_LIB.SCM(SCH_1):PAGE17

 L10 Q_INDUCTOR_SMLF-BLM18PG121SN1DA
     2 P1V8_STBY_PE_VCC18A @SCM_LIB.SCM(SCH_1):P1V8_STBY_PE_VCC18A    I24 @SCM_LIB.SCM(SCH_1):PAGE16
     1 P1V8_AUX @SCM_LIB.SCM(SCH_1):P1V8_AUX    I24 @SCM_LIB.SCM(SCH_1):PAGE16

 L11 Q_INDUCTOR_SMLF-BLM18PG121SN1DA
     2 P1V2_STBY_MVDD_CK @SCM_LIB.SCM(SCH_1):P1V2_STBY_MVDD_CK    I47 @SCM_LIB.SCM(SCH_1):PAGE16
     1 P1V2_AUX @SCM_LIB.SCM(SCH_1):P1V2_AUX    I47 @SCM_LIB.SCM(SCH_1):PAGE16

 L12 Q_INDUCTOR_SMLF-BLM18PG121SN1DA
     2 A_BMC_ADCAV33 @SCM_LIB.SCM(SCH_1):A_BMC_ADCAV33    I99 @SCM_LIB.SCM(SCH_1):PAGE16
     1 P3V3_AUX @SCM_LIB.SCM(SCH_1):P3V3_AUX    I99 @SCM_LIB.SCM(SCH_1):PAGE16

 L13 Q_INDUCTOR_SMLF-BLM18PG121SN1DA
     2 P1V0_STBY_PE_VCC10A @SCM_LIB.SCM(SCH_1):P1V0_STBY_PE_VCC10A   I158 @SCM_LIB.SCM(SCH_1):PAGE17
     1 P1V0_AUX @SCM_LIB.SCM(SCH_1):P1V0_AUX   I158 @SCM_LIB.SCM(SCH_1):PAGE17

 L14 Q_INDUCTOR_SMLF-BLM18PG121SN1DA
     2 P1V8_STBY_RC_VCC18A @SCM_LIB.SCM(SCH_1):P1V8_STBY_RC_VCC18A   I154 @SCM_LIB.SCM(SCH_1):PAGE17
     1 P1V8_AUX @SCM_LIB.SCM(SCH_1):P1V8_AUX   I154 @SCM_LIB.SCM(SCH_1):PAGE17

 L15 Q_INDUCTOR_SMLF-BLM18PG121SN1DA
     2 P1V0_STBY_DP_VCC10A @SCM_LIB.SCM(SCH_1):P1V0_STBY_DP_VCC10A   I170 @SCM_LIB.SCM(SCH_1):PAGE17
     1 P1V0_AUX @SCM_LIB.SCM(SCH_1):P1V0_AUX   I170 @SCM_LIB.SCM(SCH_1):PAGE17

 L16 Q_INDUCTOR_SMLF-BLM18PG121SN1DA
     2 P1V8_STBY_DP_VCC18A @SCM_LIB.SCM(SCH_1):P1V8_STBY_DP_VCC18A   I166 @SCM_LIB.SCM(SCH_1):PAGE17
     1 P1V8_AUX @SCM_LIB.SCM(SCH_1):P1V8_AUX   I166 @SCM_LIB.SCM(SCH_1):PAGE17

 L17 Q_INDUCTOR_SMLF-BLM18EG121SN1DA
     2 PGPPA_BMC_AUX @SCM_LIB.SCM(SCH_1):PGPPA_BMC_AUX   I176 @SCM_LIB.SCM(SCH_1):PAGE17
     1 PGPPA_BMC_AUX_L @SCM_LIB.SCM(SCH_1):PGPPA_BMC_AUX_L   I176 @SCM_LIB.SCM(SCH_1):PAGE17

 L19 Q_INDUCTOR_SMLF-BLM18EG121SN1DA
     2 PVCCA_AUX_PLD @SCM_LIB.SCM(SCH_1):PVCCA_AUX_PLD   I107 @SCM_LIB.SCM(SCH_1):PAGE41
     1 P3V3_AUX @SCM_LIB.SCM(SCH_1):P3V3_AUX   I107 @SCM_LIB.SCM(SCH_1):PAGE41

 L21 Q_INDUCTOR4P_12-67/320MA,320MAA
     4 USB3_01_MUX_FB_TXN @SCM_LIB.SCM(SCH_1):USB3_01_MUX_FB_TXN   I123 @SCM_LIB.SCM(SCH_1):PAGE29
     3 USB3_01_FB_TXN @SCM_LIB.SCM(SCH_1):USB3_01_FB_TXN   I123 @SCM_LIB.SCM(SCH_1):PAGE29
     2 USB3_01_FB_TXP @SCM_LIB.SCM(SCH_1):USB3_01_FB_TXP   I123 @SCM_LIB.SCM(SCH_1):PAGE29
     1 USB3_01_MUX_FB_TXP @SCM_LIB.SCM(SCH_1):USB3_01_MUX_FB_TXP   I123 @SCM_LIB.SCM(SCH_1):PAGE29

 L22 Q_INDUCTOR4P_12-67/320MA,320MAA
     4 USB3_01_MUX_FB_RXN @SCM_LIB.SCM(SCH_1):USB3_01_MUX_FB_RXN   I113 @SCM_LIB.SCM(SCH_1):PAGE29
     3 USB3_01_FB_RXN @SCM_LIB.SCM(SCH_1):USB3_01_FB_RXN   I113 @SCM_LIB.SCM(SCH_1):PAGE29
     2 USB3_01_FB_RXP @SCM_LIB.SCM(SCH_1):USB3_01_FB_RXP   I113 @SCM_LIB.SCM(SCH_1):PAGE29
     1 USB3_01_MUX_FB_RXP @SCM_LIB.SCM(SCH_1):USB3_01_MUX_FB_RXP   I113 @SCM_LIB.SCM(SCH_1):PAGE29

 L23 Q_INDUCTOR4P_12-67/320MA,320MAA
     4 USB_FPNL_DN @SCM_LIB.SCM(SCH_1):USB_FPNL_DN   I102 @SCM_LIB.SCM(SCH_1):PAGE29
     3 USB2_01_F_DN @SCM_LIB.SCM(SCH_1):USB2_01_F_DN   I102 @SCM_LIB.SCM(SCH_1):PAGE29
     2 USB2_01_F_DP @SCM_LIB.SCM(SCH_1):USB2_01_F_DP   I102 @SCM_LIB.SCM(SCH_1):PAGE29
     1 USB_FPNL_DP @SCM_LIB.SCM(SCH_1):USB_FPNL_DP   I102 @SCM_LIB.SCM(SCH_1):PAGE29

 L28 Q_INDUCTOR_SMLF-BLM18BB470/500A
     2 V_DACB_IO @SCM_LIB.SCM(SCH_1):V_DACB_IO   I166 @SCM_LIB.SCM(SCH_1):PAGE23
     1 V_DACB @SCM_LIB.SCM(SCH_1):V_DACB   I166 @SCM_LIB.SCM(SCH_1):PAGE23

 L29 Q_INDUCTOR_SMLF-BLM18BB470/500A
     2 V_DACG_IO @SCM_LIB.SCM(SCH_1):V_DACG_IO   I167 @SCM_LIB.SCM(SCH_1):PAGE23
     1 V_DACG @SCM_LIB.SCM(SCH_1):V_DACG   I167 @SCM_LIB.SCM(SCH_1):PAGE23

 L30 Q_INDUCTOR_SMLF-BLM18BB470/500A
     2 V_DACR_IO @SCM_LIB.SCM(SCH_1):V_DACR_IO   I168 @SCM_LIB.SCM(SCH_1):PAGE23
     1 V_DACR @SCM_LIB.SCM(SCH_1):V_DACR   I168 @SCM_LIB.SCM(SCH_1):PAGE23

 ME1 ME_DUMMY_SYMBOL-QUANTA_LOGO_7XA

 ME2 ME_DUMMY_SYMBOL-WEEE,MECH,EMPTA

 ME4 ME_DUMMY_SYMBOL-SNLABEL_7X7,MEA

OSC1 OSC4_7X25000018-25MHZ,SMLF,MISA
     1 PU_25M_BMC_CLK_EN @SCM_LIB.SCM(SCH_1):PU_25M_BMC_CLK_EN    I39 @SCM_LIB.SCM(SCH_1):PAGE15
     2    GND @SCM_LIB.SCM(SCH_1):GND    I39 @SCM_LIB.SCM(SCH_1):PAGE15
     3 BMC_CLK_25M_R @SCM_LIB.SCM(SCH_1):BMC_CLK_25M_R    I39 @SCM_LIB.SCM(SCH_1):PAGE15
     4 P3V3_RGM @SCM_LIB.SCM(SCH_1):P3V3_RGM    I39 @SCM_LIB.SCM(SCH_1):PAGE15

OSC2 OSC4_7X25000018-25MHZ,SMLF,MISA
     1 PU_25M_FPGA_CLK_EN @SCM_LIB.SCM(SCH_1):PU_25M_FPGA_CLK_EN   I127 @SCM_LIB.SCM(SCH_1):PAGE34
     2    GND @SCM_LIB.SCM(SCH_1):GND   I127 @SCM_LIB.SCM(SCH_1):PAGE34
     3 CLK_25M_OSC_FPGA_R @SCM_LIB.SCM(SCH_1):CLK_25M_OSC_FPGA_R   I127 @SCM_LIB.SCM(SCH_1):PAGE34
     4 P3V3_AUX @SCM_LIB.SCM(SCH_1):P3V3_AUX   I127 @SCM_LIB.SCM(SCH_1):PAGE34

PC205 Q_CAP_0402-0.1UF,25V,10%,X7R,CA
     1 EN_P5V_AUX @SCM_LIB.SCM(SCH_1):EN_P5V_AUX     I1 @SCM_LIB.SCM(SCH_1):PAGE51
     2    GND @SCM_LIB.SCM(SCH_1):GND     I1 @SCM_LIB.SCM(SCH_1):PAGE51

PC206 Q_CAP_C0805-22UF,16V,20%,X6S,CA
     1 SW_P5V_AUX_FLT @SCM_LIB.SCM(SCH_1):SW_P5V_AUX_FLT    I47 @SCM_LIB.SCM(SCH_1):PAGE51
     2    GND @SCM_LIB.SCM(SCH_1):GND    I47 @SCM_LIB.SCM(SCH_1):PAGE51

PC207 Q_CAP_C0805-22UF,16V,20%,X6S,CA
     1 SW_P5V_AUX_FLT @SCM_LIB.SCM(SCH_1):SW_P5V_AUX_FLT    I48 @SCM_LIB.SCM(SCH_1):PAGE51
     2    GND @SCM_LIB.SCM(SCH_1):GND    I48 @SCM_LIB.SCM(SCH_1):PAGE51

PC208 Q_CAP_C0402-1UF,25V,10%,X6S,CHA
     1 P5V_AUX_VCC @SCM_LIB.SCM(SCH_1):P5V_AUX_VCC    I13 @SCM_LIB.SCM(SCH_1):PAGE51
     2    GND @SCM_LIB.SCM(SCH_1):GND    I13 @SCM_LIB.SCM(SCH_1):PAGE51

PC210 Q_CAP_0402-0.1UF,25V,10%,X7R,CA
     1 SW_P5V_AUX_FLT @SCM_LIB.SCM(SCH_1):SW_P5V_AUX_FLT    I45 @SCM_LIB.SCM(SCH_1):PAGE51
     2    GND @SCM_LIB.SCM(SCH_1):GND    I45 @SCM_LIB.SCM(SCH_1):PAGE51

PC212 Q_CAP_0402-0.1UF,25V,10%,X7R,CA
     1 P5V_AUX @SCM_LIB.SCM(SCH_1):P5V_AUX    I31 @SCM_LIB.SCM(SCH_1):PAGE51
     2    GND @SCM_LIB.SCM(SCH_1):GND    I31 @SCM_LIB.SCM(SCH_1):PAGE51

PC213 Q_CAP_C0805-22UF,10V,20%,X6S,CA
     1 P5V_AUX @SCM_LIB.SCM(SCH_1):P5V_AUX    I32 @SCM_LIB.SCM(SCH_1):PAGE51
     2    GND @SCM_LIB.SCM(SCH_1):GND    I32 @SCM_LIB.SCM(SCH_1):PAGE51

PC214 Q_CAP_C0805-22UF,10V,20%,X6S,CA
     1 P5V_AUX @SCM_LIB.SCM(SCH_1):P5V_AUX    I33 @SCM_LIB.SCM(SCH_1):PAGE51
     2    GND @SCM_LIB.SCM(SCH_1):GND    I33 @SCM_LIB.SCM(SCH_1):PAGE51

PC215 Q_CAP_C0805-22UF,10V,20%,X6S,CA
     1 P5V_AUX @SCM_LIB.SCM(SCH_1):P5V_AUX    I36 @SCM_LIB.SCM(SCH_1):PAGE51
     2    GND @SCM_LIB.SCM(SCH_1):GND    I36 @SCM_LIB.SCM(SCH_1):PAGE51

PC216 Q_CAP_0402-0.22UF,16V,10%,X7R,A
     1 SW_P5V_AUX_BST @SCM_LIB.SCM(SCH_1):SW_P5V_AUX_BST    I23 @SCM_LIB.SCM(SCH_1):PAGE51
     2 SW_P5V_AUX_SW @SCM_LIB.SCM(SCH_1):SW_P5V_AUX_SW    I23 @SCM_LIB.SCM(SCH_1):PAGE51

PC217 Q_CAP_C0805-22UF,10V,20%,X6S,CA
     1 P5V_AUX @SCM_LIB.SCM(SCH_1):P5V_AUX    I37 @SCM_LIB.SCM(SCH_1):PAGE51
     2    GND @SCM_LIB.SCM(SCH_1):GND    I37 @SCM_LIB.SCM(SCH_1):PAGE51

PC218 Q_CAP_C0805-22UF,16V,20%,X6S,CA
     1 SW_P3V3_AUX_FLT @SCM_LIB.SCM(SCH_1):SW_P3V3_AUX_FLT    I81 @SCM_LIB.SCM(SCH_1):PAGE52
     2    GND @SCM_LIB.SCM(SCH_1):GND    I81 @SCM_LIB.SCM(SCH_1):PAGE52

PC219 Q_CAP_C0805-22UF,16V,20%,X6S,CA
     1 SW_P3V3_AUX_FLT @SCM_LIB.SCM(SCH_1):SW_P3V3_AUX_FLT    I80 @SCM_LIB.SCM(SCH_1):PAGE52
     2    GND @SCM_LIB.SCM(SCH_1):GND    I80 @SCM_LIB.SCM(SCH_1):PAGE52

PC221 Q_CAP_C0402-1UF,25V,10%,X6S,CHA
     1 P3V3_AUX_VCC @SCM_LIB.SCM(SCH_1):P3V3_AUX_VCC     I9 @SCM_LIB.SCM(SCH_1):PAGE52
     2    GND @SCM_LIB.SCM(SCH_1):GND     I9 @SCM_LIB.SCM(SCH_1):PAGE52

PC223 Q_CAP_0402-0.1UF,25V,10%,X7R,CA
     1 SW_P3V3_AUX_FLT @SCM_LIB.SCM(SCH_1):SW_P3V3_AUX_FLT    I11 @SCM_LIB.SCM(SCH_1):PAGE52
     2    GND @SCM_LIB.SCM(SCH_1):GND    I11 @SCM_LIB.SCM(SCH_1):PAGE52

PC224 Q_CAP_0402-0.22UF,16V,10%,X7R,A
     1 SW_P3V3_AUX_BST @SCM_LIB.SCM(SCH_1):SW_P3V3_AUX_BST    I15 @SCM_LIB.SCM(SCH_1):PAGE52
     2 SW_P3V3_AUX_SW @SCM_LIB.SCM(SCH_1):SW_P3V3_AUX_SW    I15 @SCM_LIB.SCM(SCH_1):PAGE52

PC225 Q_CAP_0402-0.1UF,25V,10%,X7R,CA
     1 P3V3_AUX @SCM_LIB.SCM(SCH_1):P3V3_AUX    I23 @SCM_LIB.SCM(SCH_1):PAGE52
     2    GND @SCM_LIB.SCM(SCH_1):GND    I23 @SCM_LIB.SCM(SCH_1):PAGE52

PC226 Q_CAP_C0805-22UF,10V,20%,X6S,CA
     1 P3V3_AUX @SCM_LIB.SCM(SCH_1):P3V3_AUX    I35 @SCM_LIB.SCM(SCH_1):PAGE52
     2    GND @SCM_LIB.SCM(SCH_1):GND    I35 @SCM_LIB.SCM(SCH_1):PAGE52

PC227 Q_CAP_C0805-22UF,10V,20%,X6S,CA
     1 P3V3_AUX @SCM_LIB.SCM(SCH_1):P3V3_AUX    I36 @SCM_LIB.SCM(SCH_1):PAGE52
     2    GND @SCM_LIB.SCM(SCH_1):GND    I36 @SCM_LIB.SCM(SCH_1):PAGE52

PC228 Q_CAP_C0805-22UF,10V,20%,X6S,CA
     1 P3V3_AUX @SCM_LIB.SCM(SCH_1):P3V3_AUX    I37 @SCM_LIB.SCM(SCH_1):PAGE52
     2    GND @SCM_LIB.SCM(SCH_1):GND    I37 @SCM_LIB.SCM(SCH_1):PAGE52

PC229 Q_CAP_C0805-22UF,10V,20%,X6S,CA
     1 P3V3_AUX @SCM_LIB.SCM(SCH_1):P3V3_AUX    I38 @SCM_LIB.SCM(SCH_1):PAGE52
     2    GND @SCM_LIB.SCM(SCH_1):GND    I38 @SCM_LIB.SCM(SCH_1):PAGE52

PC239 Q_CAP_0402-100PF,50V,5%,NPO,CHA
     1 P3V3_AUX_FB_RC @SCM_LIB.SCM(SCH_1):P3V3_AUX_FB_RC    I91 @SCM_LIB.SCM(SCH_1):PAGE52
     2 P3V3_AUX @SCM_LIB.SCM(SCH_1):P3V3_AUX    I91 @SCM_LIB.SCM(SCH_1):PAGE52

PC250 Q_CAP_C0402-1UF,25V,10%,X6S,CHA
     1 P1V2_AUX_VCC @SCM_LIB.SCM(SCH_1):P1V2_AUX_VCC     I7 @SCM_LIB.SCM(SCH_1):PAGE55
     2    GND @SCM_LIB.SCM(SCH_1):GND     I7 @SCM_LIB.SCM(SCH_1):PAGE55

PC251 Q_CAP_C0805-10UF,25V,10%,X6S,CA
     1 SW_P1V2_AUX_FLT @SCM_LIB.SCM(SCH_1):SW_P1V2_AUX_FLT    I43 @SCM_LIB.SCM(SCH_1):PAGE55
     2    GND @SCM_LIB.SCM(SCH_1):GND    I43 @SCM_LIB.SCM(SCH_1):PAGE55

PC252 Q_CAP_C0805-10UF,25V,10%,X6S,CA
     1 SW_P1V2_AUX_FLT @SCM_LIB.SCM(SCH_1):SW_P1V2_AUX_FLT    I42 @SCM_LIB.SCM(SCH_1):PAGE55
     2    GND @SCM_LIB.SCM(SCH_1):GND    I42 @SCM_LIB.SCM(SCH_1):PAGE55

PC253 Q_CAP_0402-0.1UF,25V,10%,X7R,CA
     1 SW_P1V2_AUX_FLT @SCM_LIB.SCM(SCH_1):SW_P1V2_AUX_FLT    I16 @SCM_LIB.SCM(SCH_1):PAGE55
     2    GND @SCM_LIB.SCM(SCH_1):GND    I16 @SCM_LIB.SCM(SCH_1):PAGE55

PC254 Q_CAP_0402-0.22UF,16V,10%,X7R,A
     1 SW_P1V2_AUX_BST @SCM_LIB.SCM(SCH_1):SW_P1V2_AUX_BST    I19 @SCM_LIB.SCM(SCH_1):PAGE55
     2 SW_P1V2_AUX_SW @SCM_LIB.SCM(SCH_1):SW_P1V2_AUX_SW    I19 @SCM_LIB.SCM(SCH_1):PAGE55

PC255 Q_CAP_0402-0.1UF,25V,10%,X7R,CA
     1 P1V2_AUX @SCM_LIB.SCM(SCH_1):P1V2_AUX    I23 @SCM_LIB.SCM(SCH_1):PAGE55
     2    GND @SCM_LIB.SCM(SCH_1):GND    I23 @SCM_LIB.SCM(SCH_1):PAGE55

PC256 Q_CAP_0805-22UF,4V,20%,X6S,TMPA
     1 P1V2_AUX @SCM_LIB.SCM(SCH_1):P1V2_AUX    I24 @SCM_LIB.SCM(SCH_1):PAGE55
     2    GND @SCM_LIB.SCM(SCH_1):GND    I24 @SCM_LIB.SCM(SCH_1):PAGE55

PC257 Q_CAP_0805-22UF,4V,20%,X6S,TMPA
     1 P1V2_AUX @SCM_LIB.SCM(SCH_1):P1V2_AUX    I25 @SCM_LIB.SCM(SCH_1):PAGE55
     2    GND @SCM_LIB.SCM(SCH_1):GND    I25 @SCM_LIB.SCM(SCH_1):PAGE55

PC258 Q_CAP_0805-22UF,4V,20%,X6S,TMPA
     1 P1V2_AUX @SCM_LIB.SCM(SCH_1):P1V2_AUX    I28 @SCM_LIB.SCM(SCH_1):PAGE55
     2    GND @SCM_LIB.SCM(SCH_1):GND    I28 @SCM_LIB.SCM(SCH_1):PAGE55

PC259 Q_CAP_0805-22UF,4V,20%,X6S,TMPA
     1 P1V2_AUX @SCM_LIB.SCM(SCH_1):P1V2_AUX    I29 @SCM_LIB.SCM(SCH_1):PAGE55
     2    GND @SCM_LIB.SCM(SCH_1):GND    I29 @SCM_LIB.SCM(SCH_1):PAGE55

PC260 Q_CAP_C0402-1UF,25V,10%,X6S,CHA
     1 P1V0_AUX_VCC @SCM_LIB.SCM(SCH_1):P1V0_AUX_VCC     I7 @SCM_LIB.SCM(SCH_1):PAGE56
     2    GND @SCM_LIB.SCM(SCH_1):GND     I7 @SCM_LIB.SCM(SCH_1):PAGE56

PC261 Q_CAP_C0805-10UF,25V,10%,X6S,CA
     1 SW_P1V0_AUX_FLT @SCM_LIB.SCM(SCH_1):SW_P1V0_AUX_FLT    I44 @SCM_LIB.SCM(SCH_1):PAGE56
     2    GND @SCM_LIB.SCM(SCH_1):GND    I44 @SCM_LIB.SCM(SCH_1):PAGE56

PC262 Q_CAP_C0805-10UF,25V,10%,X6S,CA
     1 SW_P1V0_AUX_FLT @SCM_LIB.SCM(SCH_1):SW_P1V0_AUX_FLT    I43 @SCM_LIB.SCM(SCH_1):PAGE56
     2    GND @SCM_LIB.SCM(SCH_1):GND    I43 @SCM_LIB.SCM(SCH_1):PAGE56

PC263 Q_CAP_0402-0.1UF,25V,10%,X7R,CA
     1 SW_P1V0_AUX_FLT @SCM_LIB.SCM(SCH_1):SW_P1V0_AUX_FLT    I16 @SCM_LIB.SCM(SCH_1):PAGE56
     2    GND @SCM_LIB.SCM(SCH_1):GND    I16 @SCM_LIB.SCM(SCH_1):PAGE56

PC264 Q_CAP_0402-0.22UF,16V,10%,X7R,A
     1 SW_P1V0_AUX_BST @SCM_LIB.SCM(SCH_1):SW_P1V0_AUX_BST    I19 @SCM_LIB.SCM(SCH_1):PAGE56
     2 SW_P1V0_AUX_SW @SCM_LIB.SCM(SCH_1):SW_P1V0_AUX_SW    I19 @SCM_LIB.SCM(SCH_1):PAGE56

PC266 Q_CAP_0402-0.1UF,25V,10%,X7R,CA
     1 P1V0_AUX @SCM_LIB.SCM(SCH_1):P1V0_AUX    I23 @SCM_LIB.SCM(SCH_1):PAGE56
     2    GND @SCM_LIB.SCM(SCH_1):GND    I23 @SCM_LIB.SCM(SCH_1):PAGE56

PC267 Q_CAP_0805-22UF,4V,20%,X6S,TMPA
     1 P1V0_AUX @SCM_LIB.SCM(SCH_1):P1V0_AUX    I24 @SCM_LIB.SCM(SCH_1):PAGE56
     2    GND @SCM_LIB.SCM(SCH_1):GND    I24 @SCM_LIB.SCM(SCH_1):PAGE56

PC268 Q_CAP_0805-22UF,4V,20%,X6S,TMPA
     1 P1V0_AUX @SCM_LIB.SCM(SCH_1):P1V0_AUX    I25 @SCM_LIB.SCM(SCH_1):PAGE56
     2    GND @SCM_LIB.SCM(SCH_1):GND    I25 @SCM_LIB.SCM(SCH_1):PAGE56

PC269 Q_CAP_0805-22UF,4V,20%,X6S,TMPA
     1 P1V0_AUX @SCM_LIB.SCM(SCH_1):P1V0_AUX    I28 @SCM_LIB.SCM(SCH_1):PAGE56
     2    GND @SCM_LIB.SCM(SCH_1):GND    I28 @SCM_LIB.SCM(SCH_1):PAGE56

PC270 Q_CAP_0805-22UF,4V,20%,X6S,TMPA
     1 P1V0_AUX @SCM_LIB.SCM(SCH_1):P1V0_AUX    I29 @SCM_LIB.SCM(SCH_1):PAGE56
     2    GND @SCM_LIB.SCM(SCH_1):GND    I29 @SCM_LIB.SCM(SCH_1):PAGE56

PC271 Q_CAP_0402-0.1UF,25V,10%,X7R,CA
     1 P5V_AUX_REF @SCM_LIB.SCM(SCH_1):P5V_AUX_REF    I22 @SCM_LIB.SCM(SCH_1):PAGE51
     2    GND @SCM_LIB.SCM(SCH_1):GND    I22 @SCM_LIB.SCM(SCH_1):PAGE51

PC272 Q_CAP_C0402-68PF,50V,5%,COG,CHA
     1 P5V_AUX_FB @SCM_LIB.SCM(SCH_1):P5V_AUX_FB    I27 @SCM_LIB.SCM(SCH_1):PAGE51
     2 P5V_AUX @SCM_LIB.SCM(SCH_1):P5V_AUX    I27 @SCM_LIB.SCM(SCH_1):PAGE51

PC273 Q_CAP_0402-3300PF,50V,10%,X7R,A
     1 P3V3_AUX_REF @SCM_LIB.SCM(SCH_1):P3V3_AUX_REF    I86 @SCM_LIB.SCM(SCH_1):PAGE52
     2    GND @SCM_LIB.SCM(SCH_1):GND    I86 @SCM_LIB.SCM(SCH_1):PAGE52

 PL4 Q_INDUCTOR_SMLF-BLM18SN220TN1DA
     2 SW_P5V_AUX_FLT @SCM_LIB.SCM(SCH_1):SW_P5V_AUX_FLT    I39 @SCM_LIB.SCM(SCH_1):PAGE51
     1 P12V_AUX @SCM_LIB.SCM(SCH_1):P12V_AUX    I39 @SCM_LIB.SCM(SCH_1):PAGE51

PL19 Q_INDUCTOR_SMLF-BLM18SN220TN1DA
     2 SW_P3V3_AUX_FLT @SCM_LIB.SCM(SCH_1):SW_P3V3_AUX_FLT    I32 @SCM_LIB.SCM(SCH_1):PAGE52
     1 P12V_AUX @SCM_LIB.SCM(SCH_1):P12V_AUX    I32 @SCM_LIB.SCM(SCH_1):PAGE52

PL29 Q_INDUCTOR_SMLF-BLM18SN220TN1DA
     2 SW_P1V2_AUX_FLT @SCM_LIB.SCM(SCH_1):SW_P1V2_AUX_FLT    I31 @SCM_LIB.SCM(SCH_1):PAGE55
     1 P12V_AUX @SCM_LIB.SCM(SCH_1):P12V_AUX    I31 @SCM_LIB.SCM(SCH_1):PAGE55

PL31 Q_INDUCTOR_SMLF-1UH,IND,CV-10BA
     2 P1V2_AUX @SCM_LIB.SCM(SCH_1):P1V2_AUX    I21 @SCM_LIB.SCM(SCH_1):PAGE55
     1 SW_P1V2_AUX_SW @SCM_LIB.SCM(SCH_1):SW_P1V2_AUX_SW    I21 @SCM_LIB.SCM(SCH_1):PAGE55

PL32 Q_INDUCTOR_SMLF-BLM18SN220TN1DA
     2 SW_P1V0_AUX_FLT @SCM_LIB.SCM(SCH_1):SW_P1V0_AUX_FLT    I34 @SCM_LIB.SCM(SCH_1):PAGE56
     1 P12V_AUX @SCM_LIB.SCM(SCH_1):P12V_AUX    I34 @SCM_LIB.SCM(SCH_1):PAGE56

PL33 Q_INDUCTOR_SMLF-1UH,IND,CV-10BA
     2 P1V0_AUX @SCM_LIB.SCM(SCH_1):P1V0_AUX    I37 @SCM_LIB.SCM(SCH_1):PAGE56
     1 SW_P1V0_AUX_SW @SCM_LIB.SCM(SCH_1):SW_P1V0_AUX_SW    I37 @SCM_LIB.SCM(SCH_1):PAGE56

PL34 Q_INDUCTOR_SMLF-4.7UH,IND,CV-4A
     2 P5V_AUX @SCM_LIB.SCM(SCH_1):P5V_AUX    I28 @SCM_LIB.SCM(SCH_1):PAGE51
     1 SW_P5V_AUX_SW @SCM_LIB.SCM(SCH_1):SW_P5V_AUX_SW    I28 @SCM_LIB.SCM(SCH_1):PAGE51

PL35 Q_INDUCTOR_SMLF-3.3UH/6A,IND,CA
     2 P3V3_AUX @SCM_LIB.SCM(SCH_1):P3V3_AUX    I92 @SCM_LIB.SCM(SCH_1):PAGE52
     1 SW_P3V3_AUX_SW @SCM_LIB.SCM(SCH_1):SW_P3V3_AUX_SW    I92 @SCM_LIB.SCM(SCH_1):PAGE52

PR193 Q_RES_0402LF-0,5%,1/16W,CHIP,CA
     1 P3V3_AUX @SCM_LIB.SCM(SCH_1):P3V3_AUX    I47 @SCM_LIB.SCM(SCH_1):PAGE56
     2 PVCC2_AUX @SCM_LIB.SCM(SCH_1):PVCC2_AUX    I47 @SCM_LIB.SCM(SCH_1):PAGE56

PR205 Q_RES_0402LF-0,5%,1/16W,EMPTY,A
     1 P5V_AUX @SCM_LIB.SCM(SCH_1):P5V_AUX    I48 @SCM_LIB.SCM(SCH_1):PAGE56
     2 PVCC2_AUX @SCM_LIB.SCM(SCH_1):PVCC2_AUX    I48 @SCM_LIB.SCM(SCH_1):PAGE56

PR241 Q_RES_0402LF-10K,1%,1/16W,CHIPA
     1 P5V_AUX_VCC @SCM_LIB.SCM(SCH_1):P5V_AUX_VCC    I21 @SCM_LIB.SCM(SCH_1):PAGE51
     2 PWRGD_P5V_AUX_R @SCM_LIB.SCM(SCH_1):PWRGD_P5V_AUX_R    I21 @SCM_LIB.SCM(SCH_1):PAGE51

PR242 Q_RES_0402LF-10K,1%,1/16W,CHIPA
     1 P3V3_AUX @SCM_LIB.SCM(SCH_1):P3V3_AUX    I13 @SCM_LIB.SCM(SCH_1):PAGE52
     2 PWRGD_P3V3_AUX_R @SCM_LIB.SCM(SCH_1):PWRGD_P3V3_AUX_R    I13 @SCM_LIB.SCM(SCH_1):PAGE52

PR245 Q_RES_0402LF-100K,1%,1/16W,EMPA
     1 PWRGD_P5V_AUX_R @SCM_LIB.SCM(SCH_1):PWRGD_P5V_AUX_R    I43 @SCM_LIB.SCM(SCH_1):PAGE51
     2    GND @SCM_LIB.SCM(SCH_1):GND    I43 @SCM_LIB.SCM(SCH_1):PAGE51

PR274 Q_RES_0402LF-0,5%,1/16W,CHIP,CA
     1 P3V3_AUX @SCM_LIB.SCM(SCH_1):P3V3_AUX    I45 @SCM_LIB.SCM(SCH_1):PAGE55
     2 PVCC1_AUX @SCM_LIB.SCM(SCH_1):PVCC1_AUX    I45 @SCM_LIB.SCM(SCH_1):PAGE55

PR275 Q_RES_0402LF-0,5%,1/16W,EMPTY,A
     1 P5V_AUX @SCM_LIB.SCM(SCH_1):P5V_AUX    I48 @SCM_LIB.SCM(SCH_1):PAGE55
     2 PVCC1_AUX @SCM_LIB.SCM(SCH_1):PVCC1_AUX    I48 @SCM_LIB.SCM(SCH_1):PAGE55

PR276 Q_RES_0402LF-5.49K,1%,1/16W,CHA
     1    GND @SCM_LIB.SCM(SCH_1):GND    I87 @SCM_LIB.SCM(SCH_1):PAGE52
     2 P3V3_AUX_CS @SCM_LIB.SCM(SCH_1):P3V3_AUX_CS    I87 @SCM_LIB.SCM(SCH_1):PAGE52

PR496 Q_RES_0402LF-150K,1%,1/16W,CHIA
     1 P1V2_AUX_MODE @SCM_LIB.SCM(SCH_1):P1V2_AUX_MODE     I6 @SCM_LIB.SCM(SCH_1):PAGE55
     2    GND @SCM_LIB.SCM(SCH_1):GND     I6 @SCM_LIB.SCM(SCH_1):PAGE55

PR498 Q_RES_0402LF-10K,1%,1/16W,CHIPA
     1 P3V3_AUX @SCM_LIB.SCM(SCH_1):P3V3_AUX    I18 @SCM_LIB.SCM(SCH_1):PAGE55
     2 PWRGD_P1V2_AUX_R @SCM_LIB.SCM(SCH_1):PWRGD_P1V2_AUX_R    I18 @SCM_LIB.SCM(SCH_1):PAGE55

PR500 Q_RES_0402LF-10K,1%,1/16W,CHIPA
     1 P3V3_AUX @SCM_LIB.SCM(SCH_1):P3V3_AUX    I18 @SCM_LIB.SCM(SCH_1):PAGE56
     2 PWRGD_P1V0_AUX_R @SCM_LIB.SCM(SCH_1):PWRGD_P1V0_AUX_R    I18 @SCM_LIB.SCM(SCH_1):PAGE56

PR521 Q_RES_0402LF-681K,1%,1/16W,CHIA
     1 P12V_AUX @SCM_LIB.SCM(SCH_1):P12V_AUX     I4 @SCM_LIB.SCM(SCH_1):PAGE51
     2 EN_P5V_AUX @SCM_LIB.SCM(SCH_1):EN_P5V_AUX     I4 @SCM_LIB.SCM(SCH_1):PAGE51

PR522 Q_RES_0402LF-100K,1%,1/16W,CHIA
     1 EN_P5V_AUX @SCM_LIB.SCM(SCH_1):EN_P5V_AUX     I3 @SCM_LIB.SCM(SCH_1):PAGE51
     2    GND @SCM_LIB.SCM(SCH_1):GND     I3 @SCM_LIB.SCM(SCH_1):PAGE51

PR525 Q_RES_0402LF-20.5K,1%,1/16W,CHA
     1 P5V_AUX_CS @SCM_LIB.SCM(SCH_1):P5V_AUX_CS     I9 @SCM_LIB.SCM(SCH_1):PAGE51
     2    GND @SCM_LIB.SCM(SCH_1):GND     I9 @SCM_LIB.SCM(SCH_1):PAGE51

PR526 Q_RES_0402LF-12.4K,1%,1/16W,CHA
     1 P5V_AUX_FB @SCM_LIB.SCM(SCH_1):P5V_AUX_FB    I26 @SCM_LIB.SCM(SCH_1):PAGE51
     2    GND @SCM_LIB.SCM(SCH_1):GND    I26 @SCM_LIB.SCM(SCH_1):PAGE51

PR527 Q_RES_0402LF-91K,1%,1/16W,CHIPA
     1 P5V_AUX_FB @SCM_LIB.SCM(SCH_1):P5V_AUX_FB    I30 @SCM_LIB.SCM(SCH_1):PAGE51
     2 P5V_AUX @SCM_LIB.SCM(SCH_1):P5V_AUX    I30 @SCM_LIB.SCM(SCH_1):PAGE51

PR530 Q_RES_0402LF-12.4K,1%,1/16W,CHA
     1    GND @SCM_LIB.SCM(SCH_1):GND    I17 @SCM_LIB.SCM(SCH_1):PAGE52
     2 P3V3_AUX_FB_RC @SCM_LIB.SCM(SCH_1):P3V3_AUX_FB_RC    I17 @SCM_LIB.SCM(SCH_1):PAGE52

PR532 Q_RES_0402LF-60.4K,1%,1/16W,CHA
     1    GND @SCM_LIB.SCM(SCH_1):GND    I88 @SCM_LIB.SCM(SCH_1):PAGE52
     2 P3V3_AUX_MODE @SCM_LIB.SCM(SCH_1):P3V3_AUX_MODE    I88 @SCM_LIB.SCM(SCH_1):PAGE52

PR534 Q_RES_0402LF-56K,1%,1/16W,CHIPA
     1 P3V3_AUX_FB_RC @SCM_LIB.SCM(SCH_1):P3V3_AUX_FB_RC    I25 @SCM_LIB.SCM(SCH_1):PAGE52
     2 P3V3_AUX @SCM_LIB.SCM(SCH_1):P3V3_AUX    I25 @SCM_LIB.SCM(SCH_1):PAGE52

PR539 Q_RES_0402LF-5.1,5%,1/16W,CHIPA
     1 PVCC1_AUX @SCM_LIB.SCM(SCH_1):PVCC1_AUX     I8 @SCM_LIB.SCM(SCH_1):PAGE55
     2 P1V2_AUX_VCC @SCM_LIB.SCM(SCH_1):P1V2_AUX_VCC     I8 @SCM_LIB.SCM(SCH_1):PAGE55

PR541 Q_RES_0402LF-5.1,5%,1/16W,CHIPA
     1 PVCC2_AUX @SCM_LIB.SCM(SCH_1):PVCC2_AUX     I8 @SCM_LIB.SCM(SCH_1):PAGE56
     2 P1V0_AUX_VCC @SCM_LIB.SCM(SCH_1):P1V0_AUX_VCC     I8 @SCM_LIB.SCM(SCH_1):PAGE56

PR543 Q_RES_0402LF-100K,1%,1/16W,CHIA
     1 P1V0_AUX_MODE @SCM_LIB.SCM(SCH_1):P1V0_AUX_MODE    I71 @SCM_LIB.SCM(SCH_1):PAGE56
     2    GND @SCM_LIB.SCM(SCH_1):GND    I71 @SCM_LIB.SCM(SCH_1):PAGE56

 PU1 MPQ8626GDZ-MPQ8626GD-Z,SMLF,ICA
     3 SW_P3V3_AUX_FLT @SCM_LIB.SCM(SCH_1):SW_P3V3_AUX_FLT    I82 @SCM_LIB.SCM(SCH_1):PAGE52
     9 PWRGD_P3V3_AUX_R @SCM_LIB.SCM(SCH_1):PWRGD_P3V3_AUX_R    I82 @SCM_LIB.SCM(SCH_1):PAGE52
    14    GND @SCM_LIB.SCM(SCH_1):GND    I82 @SCM_LIB.SCM(SCH_1):PAGE52
     5 PWRGD_EN_P3V3_R @SCM_LIB.SCM(SCH_1):PWRGD_EN_P3V3_R    I82 @SCM_LIB.SCM(SCH_1):PAGE52
    10 SW_P3V3_AUX_BST_R @SCM_LIB.SCM(SCH_1):SW_P3V3_AUX_BST_R    I82 @SCM_LIB.SCM(SCH_1):PAGE52
     6 P3V3_AUX_FB_RC @SCM_LIB.SCM(SCH_1):P3V3_AUX_FB_RC    I82 @SCM_LIB.SCM(SCH_1):PAGE52
     7    GND @SCM_LIB.SCM(SCH_1):GND    I82 @SCM_LIB.SCM(SCH_1):PAGE52
    13 P3V3_AUX_VCC @SCM_LIB.SCM(SCH_1):P3V3_AUX_VCC    I82 @SCM_LIB.SCM(SCH_1):PAGE52
     1    GND @SCM_LIB.SCM(SCH_1):GND    I82 @SCM_LIB.SCM(SCH_1):PAGE52
    11 SW_P3V3_AUX_SW @SCM_LIB.SCM(SCH_1):SW_P3V3_AUX_SW    I82 @SCM_LIB.SCM(SCH_1):PAGE52
     8 P3V3_AUX_REF @SCM_LIB.SCM(SCH_1):P3V3_AUX_REF    I82 @SCM_LIB.SCM(SCH_1):PAGE52
    12 P3V3_AUX_MODE @SCM_LIB.SCM(SCH_1):P3V3_AUX_MODE    I82 @SCM_LIB.SCM(SCH_1):PAGE52
     4 P3V3_AUX_CS @SCM_LIB.SCM(SCH_1):P3V3_AUX_CS    I82 @SCM_LIB.SCM(SCH_1):PAGE52
     2 SW_P3V3_AUX_SW @SCM_LIB.SCM(SCH_1):SW_P3V3_AUX_SW    I82 @SCM_LIB.SCM(SCH_1):PAGE52

PU38 MPQ8633AGLEC807Z-MPQ8633AGLE-CA
    10 SW_P5V_AUX_FLT @SCM_LIB.SCM(SCH_1):SW_P5V_AUX_FLT    I42 @SCM_LIB.SCM(SCH_1):PAGE51
     9 PWRGD_P5V_AUX_R @SCM_LIB.SCM(SCH_1):PWRGD_P5V_AUX_R    I42 @SCM_LIB.SCM(SCH_1):PAGE51
 11_18    GND @SCM_LIB.SCM(SCH_1):GND    I42 @SCM_LIB.SCM(SCH_1):PAGE51
     8 EN_P5V_AUX @SCM_LIB.SCM(SCH_1):EN_P5V_AUX    I42 @SCM_LIB.SCM(SCH_1):PAGE51
     1 SW_P5V_AUX_BST @SCM_LIB.SCM(SCH_1):SW_P5V_AUX_BST    I42 @SCM_LIB.SCM(SCH_1):PAGE51
     7 P5V_AUX_FB @SCM_LIB.SCM(SCH_1):P5V_AUX_FB    I42 @SCM_LIB.SCM(SCH_1):PAGE51
     2    GND @SCM_LIB.SCM(SCH_1):GND    I42 @SCM_LIB.SCM(SCH_1):PAGE51
    19 P5V_AUX_VCC @SCM_LIB.SCM(SCH_1):P5V_AUX_VCC    I42 @SCM_LIB.SCM(SCH_1):PAGE51
     6    GND @SCM_LIB.SCM(SCH_1):GND    I42 @SCM_LIB.SCM(SCH_1):PAGE51
    20 SW_P5V_AUX_SW @SCM_LIB.SCM(SCH_1):SW_P5V_AUX_SW    I42 @SCM_LIB.SCM(SCH_1):PAGE51
     5 P5V_AUX_REF @SCM_LIB.SCM(SCH_1):P5V_AUX_REF    I42 @SCM_LIB.SCM(SCH_1):PAGE51
     4    GND @SCM_LIB.SCM(SCH_1):GND    I42 @SCM_LIB.SCM(SCH_1):PAGE51
     3 P5V_AUX_CS @SCM_LIB.SCM(SCH_1):P5V_AUX_CS    I42 @SCM_LIB.SCM(SCH_1):PAGE51
    21 SW_P5V_AUX_FLT @SCM_LIB.SCM(SCH_1):SW_P5V_AUX_FLT    I42 @SCM_LIB.SCM(SCH_1):PAGE51

PU41 NB695GDZ-NB695GD-Z,SMLF,IC,AL0A
     1 SW_P1V2_AUX_FLT @SCM_LIB.SCM(SCH_1):SW_P1V2_AUX_FLT    I15 @SCM_LIB.SCM(SCH_1):PAGE55
    13 PWRGD_P1V2_AUX_R @SCM_LIB.SCM(SCH_1):PWRGD_P1V2_AUX_R    I15 @SCM_LIB.SCM(SCH_1):PAGE55
     2    GND @SCM_LIB.SCM(SCH_1):GND    I15 @SCM_LIB.SCM(SCH_1):PAGE55
     5 EN_P1V2_AUX_R @SCM_LIB.SCM(SCH_1):EN_P1V2_AUX_R    I15 @SCM_LIB.SCM(SCH_1):PAGE55
     9 SW_P1V2_AUX_BST @SCM_LIB.SCM(SCH_1):SW_P1V2_AUX_BST    I15 @SCM_LIB.SCM(SCH_1):PAGE55
    11    GND @SCM_LIB.SCM(SCH_1):GND    I15 @SCM_LIB.SCM(SCH_1):PAGE55
     6 P1V2_AUX_VCC @SCM_LIB.SCM(SCH_1):P1V2_AUX_VCC    I15 @SCM_LIB.SCM(SCH_1):PAGE55
     3    GND @SCM_LIB.SCM(SCH_1):GND    I15 @SCM_LIB.SCM(SCH_1):PAGE55
     4    GND @SCM_LIB.SCM(SCH_1):GND    I15 @SCM_LIB.SCM(SCH_1):PAGE55
     7 P1V2_AUX_MODE @SCM_LIB.SCM(SCH_1):P1V2_AUX_MODE    I15 @SCM_LIB.SCM(SCH_1):PAGE55
    12 P1V2_AUX @SCM_LIB.SCM(SCH_1):P1V2_AUX    I15 @SCM_LIB.SCM(SCH_1):PAGE55
     8 SW_P1V2_AUX_SW @SCM_LIB.SCM(SCH_1):SW_P1V2_AUX_SW    I15 @SCM_LIB.SCM(SCH_1):PAGE55
    10 P1V2_AUX_VCC @SCM_LIB.SCM(SCH_1):P1V2_AUX_VCC    I15 @SCM_LIB.SCM(SCH_1):PAGE55

PU42 NB695GDZ-NB695GD-Z,SMLF,IC,AL0A
     1 SW_P1V0_AUX_FLT @SCM_LIB.SCM(SCH_1):SW_P1V0_AUX_FLT    I15 @SCM_LIB.SCM(SCH_1):PAGE56
    13 PWRGD_P1V0_AUX_R @SCM_LIB.SCM(SCH_1):PWRGD_P1V0_AUX_R    I15 @SCM_LIB.SCM(SCH_1):PAGE56
     2    GND @SCM_LIB.SCM(SCH_1):GND    I15 @SCM_LIB.SCM(SCH_1):PAGE56
     5 EN_P1V0_AUX_R @SCM_LIB.SCM(SCH_1):EN_P1V0_AUX_R    I15 @SCM_LIB.SCM(SCH_1):PAGE56
     9 SW_P1V0_AUX_BST @SCM_LIB.SCM(SCH_1):SW_P1V0_AUX_BST    I15 @SCM_LIB.SCM(SCH_1):PAGE56
    11    GND @SCM_LIB.SCM(SCH_1):GND    I15 @SCM_LIB.SCM(SCH_1):PAGE56
     6 P1V0_AUX_VCC @SCM_LIB.SCM(SCH_1):P1V0_AUX_VCC    I15 @SCM_LIB.SCM(SCH_1):PAGE56
     3 P1V0_AUX_VCC @SCM_LIB.SCM(SCH_1):P1V0_AUX_VCC    I15 @SCM_LIB.SCM(SCH_1):PAGE56
     4    GND @SCM_LIB.SCM(SCH_1):GND    I15 @SCM_LIB.SCM(SCH_1):PAGE56
     7 P1V0_AUX_MODE @SCM_LIB.SCM(SCH_1):P1V0_AUX_MODE    I15 @SCM_LIB.SCM(SCH_1):PAGE56
    12 P1V0_AUX @SCM_LIB.SCM(SCH_1):P1V0_AUX    I15 @SCM_LIB.SCM(SCH_1):PAGE56
     8 SW_P1V0_AUX_SW @SCM_LIB.SCM(SCH_1):SW_P1V0_AUX_SW    I15 @SCM_LIB.SCM(SCH_1):PAGE56
    10 P1V0_AUX_VCC @SCM_LIB.SCM(SCH_1):P1V0_AUX_VCC    I15 @SCM_LIB.SCM(SCH_1):PAGE56

  Q1 MMBT39047F-MMBT3904-7-F,SMLF,IA
     B BJT_Q3_C @SCM_LIB.SCM(SCH_1):BJT_Q3_C     I2 @SCM_LIB.SCM(SCH_1):PAGE22
     E    GND @SCM_LIB.SCM(SCH_1):GND     I2 @SCM_LIB.SCM(SCH_1):PAGE22
     C RST_BMC_EXTRST_R2_N @SCM_LIB.SCM(SCH_1):RST_BMC_EXTRST_R2_N     I2 @SCM_LIB.SCM(SCH_1):PAGE22

  Q2 MOSFET_NCH_DUAL-2N7002KDW,SMLFA
     1 V_BMC_DDC_SDA @SCM_LIB.SCM(SCH_1):V_BMC_DDC_SDA    I56 @SCM_LIB.SCM(SCH_1):PAGE23
     2 V_BMC_DDC_LS_GATE @SCM_LIB.SCM(SCH_1):V_BMC_DDC_LS_GATE    I56 @SCM_LIB.SCM(SCH_1):PAGE23
     6 V_BMC_LS_DDC_SDA @SCM_LIB.SCM(SCH_1):V_BMC_LS_DDC_SDA    I56 @SCM_LIB.SCM(SCH_1):PAGE23
     3 V_BMC_LS_DDC_SCL @SCM_LIB.SCM(SCH_1):V_BMC_LS_DDC_SCL     I2 @SCM_LIB.SCM(SCH_1):PAGE23
     5 V_BMC_DDC_LS_GATE @SCM_LIB.SCM(SCH_1):V_BMC_DDC_LS_GATE     I2 @SCM_LIB.SCM(SCH_1):PAGE23
     4 V_BMC_DDC_SCL @SCM_LIB.SCM(SCH_1):V_BMC_DDC_SCL     I2 @SCM_LIB.SCM(SCH_1):PAGE23

  Q3 MMBT39047F-MMBT3904-7-F,SMLF,IA
     B BJT_Q3_B @SCM_LIB.SCM(SCH_1):BJT_Q3_B     I4 @SCM_LIB.SCM(SCH_1):PAGE22
     E    GND @SCM_LIB.SCM(SCH_1):GND     I4 @SCM_LIB.SCM(SCH_1):PAGE22
     C BJT_Q3_C @SCM_LIB.SCM(SCH_1):BJT_Q3_C     I4 @SCM_LIB.SCM(SCH_1):PAGE22

  Q4 MOSFET_PCH_GDS-NTR1P02LT1G,SMLA
     D PGPPA_BMC_AUX_L @SCM_LIB.SCM(SCH_1):PGPPA_BMC_AUX_L   I289 @SCM_LIB.SCM(SCH_1):PAGE17
     G LPC_ESPI_SEL_N @SCM_LIB.SCM(SCH_1):LPC_ESPI_SEL_N   I289 @SCM_LIB.SCM(SCH_1):PAGE17
     S P3V3_AUX @SCM_LIB.SCM(SCH_1):P3V3_AUX   I289 @SCM_LIB.SCM(SCH_1):PAGE17

  Q5 MOSFET_NCH_4D1S-NTGS4141NT1G,SA
     1 PGPPA_BMC_AUX_L @SCM_LIB.SCM(SCH_1):PGPPA_BMC_AUX_L   I274 @SCM_LIB.SCM(SCH_1):PAGE17
     6 PGPPA_BMC_AUX_L @SCM_LIB.SCM(SCH_1):PGPPA_BMC_AUX_L   I274 @SCM_LIB.SCM(SCH_1):PAGE17
     3 LPC_ESPI_SEL_N @SCM_LIB.SCM(SCH_1):LPC_ESPI_SEL_N   I274 @SCM_LIB.SCM(SCH_1):PAGE17
     2 PGPPA_BMC_AUX_L @SCM_LIB.SCM(SCH_1):PGPPA_BMC_AUX_L   I274 @SCM_LIB.SCM(SCH_1):PAGE17
     4 P1V8_AUX @SCM_LIB.SCM(SCH_1):P1V8_AUX   I274 @SCM_LIB.SCM(SCH_1):PAGE17
     5 PGPPA_BMC_AUX_L @SCM_LIB.SCM(SCH_1):PGPPA_BMC_AUX_L   I274 @SCM_LIB.SCM(SCH_1):PAGE17

  Q6 2N7002A7-2N7002A-7,SMLF,IC,BAMA
     G DEBUG_PORT_PRSNT @SCM_LIB.SCM(SCH_1):DEBUG_PORT_PRSNT   I202 @SCM_LIB.SCM(SCH_1):PAGE29
     D FM_DEBUG_PORT_R_PRSNT_N @SCM_LIB.SCM(SCH_1):FM_DEBUG_PORT_R_PRSNT_N   I202 @SCM_LIB.SCM(SCH_1):PAGE29
     S    GND @SCM_LIB.SCM(SCH_1):GND   I202 @SCM_LIB.SCM(SCH_1):PAGE29

  Q7 2N7002A7-2N7002A-7,SMLF,IC,BAMA
     G LPC_ESPI_SEL_R1 @SCM_LIB.SCM(SCH_1):LPC_ESPI_SEL_R1   I243 @SCM_LIB.SCM(SCH_1):PAGE27
     D   Q7_D @SCM_LIB.SCM(SCH_1):Q7_D   I243 @SCM_LIB.SCM(SCH_1):PAGE27
     S SPI_BMC_TPM_MOSI @SCM_LIB.SCM(SCH_1):SPI_BMC_TPM_MOSI   I243 @SCM_LIB.SCM(SCH_1):PAGE27

  Q8 2N7002A7-2N7002A-7,SMLF,IC,BAMA
     G FM_UART_SEL_N @SCM_LIB.SCM(SCH_1):FM_UART_SEL_N   I163 @SCM_LIB.SCM(SCH_1):PAGE28
     D FM_SOL_UART_CH_SEL_R3 @SCM_LIB.SCM(SCH_1):FM_SOL_UART_CH_SEL_R3   I163 @SCM_LIB.SCM(SCH_1):PAGE28
     S    GND @SCM_LIB.SCM(SCH_1):GND   I163 @SCM_LIB.SCM(SCH_1):PAGE28

  Q9 MOSFET_NCH_DUAL-PJT138K,SMLF,IA
     1    GND @SCM_LIB.SCM(SCH_1):GND     I6 @SCM_LIB.SCM(SCH_1):PAGE49
     2 ID_LED_BUF @SCM_LIB.SCM(SCH_1):ID_LED_BUF     I6 @SCM_LIB.SCM(SCH_1):PAGE49
     6 ID_LED_D_P3V3_AUX @SCM_LIB.SCM(SCH_1):ID_LED_D_P3V3_AUX     I6 @SCM_LIB.SCM(SCH_1):PAGE49

 Q10 MOSFET_N_GSD-DMG6968U-7,SMLF,IA
     G LPC_ESPI_SEL_R @SCM_LIB.SCM(SCH_1):LPC_ESPI_SEL_R   I227 @SCM_LIB.SCM(SCH_1):PAGE17
     S    GND @SCM_LIB.SCM(SCH_1):GND   I227 @SCM_LIB.SCM(SCH_1):PAGE17
     D LPC_ESPI_SEL_N @SCM_LIB.SCM(SCH_1):LPC_ESPI_SEL_N   I227 @SCM_LIB.SCM(SCH_1):PAGE17

 Q11 MOSFET_N_GSD-NX7002AK,SMLF,IC,A
     G BATTERY_DETECT_R @SCM_LIB.SCM(SCH_1):BATTERY_DETECT_R   I179 @SCM_LIB.SCM(SCH_1):PAGE15
     S P3V_BAT_SENSOR @SCM_LIB.SCM(SCH_1):P3V_BAT_SENSOR   I179 @SCM_LIB.SCM(SCH_1):PAGE15
     D P3V_BAT_R1 @SCM_LIB.SCM(SCH_1):P3V_BAT_R1   I179 @SCM_LIB.SCM(SCH_1):PAGE15

 Q12 MOSFET_DUAL_6P-2N7002KDW,SMLF,A
     2 PWR_LED @SCM_LIB.SCM(SCH_1):PWR_LED    I24 @SCM_LIB.SCM(SCH_1):PAGE49
     5 HDD_LED_N @SCM_LIB.SCM(SCH_1):HDD_LED_N    I24 @SCM_LIB.SCM(SCH_1):PAGE49
     1    GND @SCM_LIB.SCM(SCH_1):GND    I24 @SCM_LIB.SCM(SCH_1):PAGE49
     4    GND @SCM_LIB.SCM(SCH_1):GND    I24 @SCM_LIB.SCM(SCH_1):PAGE49
     6 PWR_LED_BUF_N @SCM_LIB.SCM(SCH_1):PWR_LED_BUF_N    I24 @SCM_LIB.SCM(SCH_1):PAGE49
     3 HDD_LED_BUF @SCM_LIB.SCM(SCH_1):HDD_LED_BUF    I24 @SCM_LIB.SCM(SCH_1):PAGE49

 Q13 MOSFET_NCH_DUAL-PJT138K,SMLF,IA
     1    GND @SCM_LIB.SCM(SCH_1):GND   I218 @SCM_LIB.SCM(SCH_1):PAGE50
     2 PWRGD_P1V0_AUX_DELAY @SCM_LIB.SCM(SCH_1):PWRGD_P1V0_AUX_DELAY   I218 @SCM_LIB.SCM(SCH_1):PAGE50
     6 LED_D22_R1 @SCM_LIB.SCM(SCH_1):LED_D22_R1   I218 @SCM_LIB.SCM(SCH_1):PAGE50

  R1 Q_RES_0402LF-0,5%,1/16W,EMPTY,A
     1 M_BMC_DDR4_BG1 @SCM_LIB.SCM(SCH_1):M_BMC_DDR4_BG1    I14 @SCM_LIB.SCM(SCH_1):PAGE20
     2 M_BMC_DDR4_MBG1 @SCM_LIB.SCM(SCH_1):M_BMC_DDR4_MBG1    I14 @SCM_LIB.SCM(SCH_1):PAGE20

  R2 Q_RES_0402LF-0,5%,1/16W,CHIP,CA
     1 M_BMC_DDR4_BG1 @SCM_LIB.SCM(SCH_1):M_BMC_DDR4_BG1    I13 @SCM_LIB.SCM(SCH_1):PAGE20
     2    GND @SCM_LIB.SCM(SCH_1):GND    I13 @SCM_LIB.SCM(SCH_1):PAGE20

  R3 Q_RES_0402LF-0,5%,1/16W,CHIP,CA
     1 M_BMC_DDR4_ZQU @SCM_LIB.SCM(SCH_1):M_BMC_DDR4_ZQU    I17 @SCM_LIB.SCM(SCH_1):PAGE20
     2    GND @SCM_LIB.SCM(SCH_1):GND    I17 @SCM_LIB.SCM(SCH_1):PAGE20

  R4 Q_RES_0402LF-1K,1%,1/16W,CHIP,A
     1 PD_M_BMC_DDR4_PAR @SCM_LIB.SCM(SCH_1):PD_M_BMC_DDR4_PAR   I141 @SCM_LIB.SCM(SCH_1):PAGE20
     2    GND @SCM_LIB.SCM(SCH_1):GND   I141 @SCM_LIB.SCM(SCH_1):PAGE20

  R5 Q_RES_0402LF-1K,1%,1/16W,CHIP,A
     1 PD_M_BMC_DDR4_TEN @SCM_LIB.SCM(SCH_1):PD_M_BMC_DDR4_TEN   I142 @SCM_LIB.SCM(SCH_1):PAGE20
     2    GND @SCM_LIB.SCM(SCH_1):GND   I142 @SCM_LIB.SCM(SCH_1):PAGE20

  R6 Q_RES_0402LF-240,1%,1/16W,CHIPA
     1 PD_M_BMC_DDR4_ZQ @SCM_LIB.SCM(SCH_1):PD_M_BMC_DDR4_ZQ   I143 @SCM_LIB.SCM(SCH_1):PAGE20
     2    GND @SCM_LIB.SCM(SCH_1):GND   I143 @SCM_LIB.SCM(SCH_1):PAGE20

  R7 Q_RES_0402LF-60.4,1%,1/16W,CHIA
     1 M_BMC_DDR4_MCLK_DN @SCM_LIB.SCM(SCH_1):M_BMC_DDR4_MCLK_DN    I90 @SCM_LIB.SCM(SCH_1):PAGE20
     2 M_BMC_DDR4_MCLK_C @SCM_LIB.SCM(SCH_1):M_BMC_DDR4_MCLK_C    I90 @SCM_LIB.SCM(SCH_1):PAGE20

  R8 Q_RES_0402LF-60.4,1%,1/16W,CHIA
     1 M_BMC_DDR4_MCLK_DP @SCM_LIB.SCM(SCH_1):M_BMC_DDR4_MCLK_DP    I89 @SCM_LIB.SCM(SCH_1):PAGE20
     2 M_BMC_DDR4_MCLK_C @SCM_LIB.SCM(SCH_1):M_BMC_DDR4_MCLK_C    I89 @SCM_LIB.SCM(SCH_1):PAGE20

  R9 Q_RES_0402LF-4.7K,1%,1/16W,CHIA
     1 M_BMC_DDR4_ALERT_N @SCM_LIB.SCM(SCH_1):M_BMC_DDR4_ALERT_N   I111 @SCM_LIB.SCM(SCH_1):PAGE20
     2 P1V2_AUX @SCM_LIB.SCM(SCH_1):P1V2_AUX   I111 @SCM_LIB.SCM(SCH_1):PAGE20

 R10 Q_RES_0402LF-0,5%,1/16W,CHIP,CA
     1 RST_SRST_PLD_BMC_R2_N @SCM_LIB.SCM(SCH_1):RST_SRST_PLD_BMC_R2_N   I155 @SCM_LIB.SCM(SCH_1):PAGE34
     2 RST_SRST_PLD_BMC_R_N @SCM_LIB.SCM(SCH_1):RST_SRST_PLD_BMC_R_N   I155 @SCM_LIB.SCM(SCH_1):PAGE34

 R11 Q_RES_0402LF-4.7K,1%,1/16W,CHIA
     1 P3V3_AUX @SCM_LIB.SCM(SCH_1):P3V3_AUX   I172 @SCM_LIB.SCM(SCH_1):PAGE21
     2 BMC_EMMC_RST_N @SCM_LIB.SCM(SCH_1):BMC_EMMC_RST_N   I172 @SCM_LIB.SCM(SCH_1):PAGE21

 R12 Q_RES_0402LF-4.7K,1%,1/16W,EMPA
     1 P3V3_AUX @SCM_LIB.SCM(SCH_1):P3V3_AUX     I9 @SCM_LIB.SCM(SCH_1):PAGE26
     2 FRU_E0 @SCM_LIB.SCM(SCH_1):FRU_E0     I9 @SCM_LIB.SCM(SCH_1):PAGE26

 R13 Q_RES_0402LF-4.7K,1%,1/16W,EMPA
     1 P3V3_AUX @SCM_LIB.SCM(SCH_1):P3V3_AUX    I11 @SCM_LIB.SCM(SCH_1):PAGE26
     2 FRU_E1 @SCM_LIB.SCM(SCH_1):FRU_E1    I11 @SCM_LIB.SCM(SCH_1):PAGE26

 R14 Q_RES_0402LF-4.7K,1%,1/16W,EMPA
     1 P3V3_AUX @SCM_LIB.SCM(SCH_1):P3V3_AUX    I14 @SCM_LIB.SCM(SCH_1):PAGE26
     2 FRU_E2 @SCM_LIB.SCM(SCH_1):FRU_E2    I14 @SCM_LIB.SCM(SCH_1):PAGE26

 R15 Q_RES_0402LF-1K,1%,1/16W,CHIP,A
     1 PD_FRU_WC_N @SCM_LIB.SCM(SCH_1):PD_FRU_WC_N    I32 @SCM_LIB.SCM(SCH_1):PAGE26
     2    GND @SCM_LIB.SCM(SCH_1):GND    I32 @SCM_LIB.SCM(SCH_1):PAGE26

 R16 Q_RES_0402LF-2.21K,1%,1/16W,EMA
     1 V_BMC_LS_DDC_SCL_R @SCM_LIB.SCM(SCH_1):V_BMC_LS_DDC_SCL_R    I75 @SCM_LIB.SCM(SCH_1):PAGE23
     2 CRT_VCC5 @SCM_LIB.SCM(SCH_1):CRT_VCC5    I75 @SCM_LIB.SCM(SCH_1):PAGE23

 R17 Q_RES_0402LF-2.21K,1%,1/16W,EMA
     1 V_BMC_LS_DDC_SDA_R @SCM_LIB.SCM(SCH_1):V_BMC_LS_DDC_SDA_R    I68 @SCM_LIB.SCM(SCH_1):PAGE23
     2 CRT_VCC5 @SCM_LIB.SCM(SCH_1):CRT_VCC5    I68 @SCM_LIB.SCM(SCH_1):PAGE23

 R18 Q_RES_0402LF-0,5%,1/16W,CHIP,CA
     1 P5V_AUX @SCM_LIB.SCM(SCH_1):P5V_AUX    I19 @SCM_LIB.SCM(SCH_1):PAGE23
     2 BMC_DDC_BUF_PWR @SCM_LIB.SCM(SCH_1):BMC_DDC_BUF_PWR    I19 @SCM_LIB.SCM(SCH_1):PAGE23

 R19 Q_RES_0402LF-0,5%,1/16W,CHIP,CA
     1 V_VGAHS_R @SCM_LIB.SCM(SCH_1):V_VGAHS_R   I141 @SCM_LIB.SCM(SCH_1):PAGE15
     2 V_VGAHS @SCM_LIB.SCM(SCH_1):V_VGAHS   I141 @SCM_LIB.SCM(SCH_1):PAGE15

 R20 Q_RES_0402LF-0,5%,1/16W,CHIP,CA
     1 V_VGAVS_R @SCM_LIB.SCM(SCH_1):V_VGAVS_R   I140 @SCM_LIB.SCM(SCH_1):PAGE15
     2 V_VGAVS @SCM_LIB.SCM(SCH_1):V_VGAVS   I140 @SCM_LIB.SCM(SCH_1):PAGE15

 R21 Q_RES_0402LF-10,1%,1/16W,CHIP,A
     1 V_DACG_R @SCM_LIB.SCM(SCH_1):V_DACG_R   I133 @SCM_LIB.SCM(SCH_1):PAGE15
     2 V_DACG @SCM_LIB.SCM(SCH_1):V_DACG   I133 @SCM_LIB.SCM(SCH_1):PAGE15

 R22 Q_RES_0402LF-150,1%,1/16W,CHIPA
     1 V_DACB_R @SCM_LIB.SCM(SCH_1):V_DACB_R   I151 @SCM_LIB.SCM(SCH_1):PAGE15
     2    GND @SCM_LIB.SCM(SCH_1):GND   I151 @SCM_LIB.SCM(SCH_1):PAGE15

 R23 Q_RES_0402LF-150,1%,1/16W,CHIPA
     1 V_DACG_R @SCM_LIB.SCM(SCH_1):V_DACG_R   I150 @SCM_LIB.SCM(SCH_1):PAGE15
     2    GND @SCM_LIB.SCM(SCH_1):GND   I150 @SCM_LIB.SCM(SCH_1):PAGE15

 R24 Q_RES_0402LF-10,1%,1/16W,CHIP,A
     1 V_DACB_R @SCM_LIB.SCM(SCH_1):V_DACB_R   I134 @SCM_LIB.SCM(SCH_1):PAGE15
     2 V_DACB @SCM_LIB.SCM(SCH_1):V_DACB   I134 @SCM_LIB.SCM(SCH_1):PAGE15

 R25 Q_RES_0402LF-150,1%,1/16W,CHIPA
     1 V_DACR_R @SCM_LIB.SCM(SCH_1):V_DACR_R   I149 @SCM_LIB.SCM(SCH_1):PAGE15
     2    GND @SCM_LIB.SCM(SCH_1):GND   I149 @SCM_LIB.SCM(SCH_1):PAGE15

 R26 Q_RES_0402LF-10,1%,1/16W,CHIP,A
     1 V_DACR_R @SCM_LIB.SCM(SCH_1):V_DACR_R   I142 @SCM_LIB.SCM(SCH_1):PAGE15
     2 V_DACR @SCM_LIB.SCM(SCH_1):V_DACR   I142 @SCM_LIB.SCM(SCH_1):PAGE15

 R27 Q_RES_0603LF-0,5%,1/10W,EMPTY,A
     1 P5V_AUX @SCM_LIB.SCM(SCH_1):P5V_AUX    I40 @SCM_LIB.SCM(SCH_1):PAGE23
     2 CRT_VCC5 @SCM_LIB.SCM(SCH_1):CRT_VCC5    I40 @SCM_LIB.SCM(SCH_1):PAGE23

 R28 Q_RES_0402LF-33.2,1%,1/16W,CHIA
     1 V_BMC_LS_DDC_SCL @SCM_LIB.SCM(SCH_1):V_BMC_LS_DDC_SCL    I99 @SCM_LIB.SCM(SCH_1):PAGE23
     2 V_BMC_LS_DDC_SCL_R @SCM_LIB.SCM(SCH_1):V_BMC_LS_DDC_SCL_R    I99 @SCM_LIB.SCM(SCH_1):PAGE23

 R29 Q_RES_0402LF-33.2,1%,1/16W,CHIA
     1 V_BMC_LS_DDC_SDA @SCM_LIB.SCM(SCH_1):V_BMC_LS_DDC_SDA    I34 @SCM_LIB.SCM(SCH_1):PAGE23
     2 V_BMC_LS_DDC_SDA_R @SCM_LIB.SCM(SCH_1):V_BMC_LS_DDC_SDA_R    I34 @SCM_LIB.SCM(SCH_1):PAGE23

 R30 Q_RES_0402LF-0,5%,1/16W,CHIP,CA
     1 CRT_VCC5 @SCM_LIB.SCM(SCH_1):CRT_VCC5    I39 @SCM_LIB.SCM(SCH_1):PAGE23
     2 BMC_DDC_BUF_EN @SCM_LIB.SCM(SCH_1):BMC_DDC_BUF_EN    I39 @SCM_LIB.SCM(SCH_1):PAGE23

 R31 Q_RES_0402LF-4.7K,1%,1/16W,CHIA
     1 P3V3_RGM @SCM_LIB.SCM(SCH_1):P3V3_RGM    I27 @SCM_LIB.SCM(SCH_1):PAGE23
     2 V_BMC_DDC_SDA @SCM_LIB.SCM(SCH_1):V_BMC_DDC_SDA    I27 @SCM_LIB.SCM(SCH_1):PAGE23

 R32 Q_RES_0402LF-4.7K,1%,1/16W,CHIA
     1 P3V3_RGM @SCM_LIB.SCM(SCH_1):P3V3_RGM    I50 @SCM_LIB.SCM(SCH_1):PAGE23
     2 V_BMC_DDC_SCL @SCM_LIB.SCM(SCH_1):V_BMC_DDC_SCL    I50 @SCM_LIB.SCM(SCH_1):PAGE23

 R33 Q_RES_0402LF-33.2,1%,1/16W,CHIA
     1 SMB_BMC_MM16_R5_SDA @SCM_LIB.SCM(SCH_1):SMB_BMC_MM16_R5_SDA   I117 @SCM_LIB.SCM(SCH_1):PAGE46
     2 SMB_BMC_TPM_MM16_SDA @SCM_LIB.SCM(SCH_1):SMB_BMC_TPM_MM16_SDA   I117 @SCM_LIB.SCM(SCH_1):PAGE46

 R34 Q_RES_0402LF-4.7K,1%,1/16W,EMPA
     1 P3V3_RGM @SCM_LIB.SCM(SCH_1):P3V3_RGM   I194 @SCM_LIB.SCM(SCH_1):PAGE11
     2 RST_PLTRST_N @SCM_LIB.SCM(SCH_1):RST_PLTRST_N   I194 @SCM_LIB.SCM(SCH_1):PAGE11

 R35 Q_RES_0402LF-0,5%,1/16W,CHIP,CA
     1 PWRGD_P2V5_AUX @SCM_LIB.SCM(SCH_1):PWRGD_P2V5_AUX    I58 @SCM_LIB.SCM(SCH_1):PAGE53
     2 PWRGD_P2V5_AUX_R @SCM_LIB.SCM(SCH_1):PWRGD_P2V5_AUX_R    I58 @SCM_LIB.SCM(SCH_1):PAGE53

 R36 Q_RES_0402LF-33.2,1%,1/16W,CHIA
     1 SMB_BMC_MM14_SCL @SCM_LIB.SCM(SCH_1):SMB_BMC_MM14_SCL   I458 @SCM_LIB.SCM(SCH_1):PAGE10
     2 SMB_BMC_MM14_R1_SCL @SCM_LIB.SCM(SCH_1):SMB_BMC_MM14_R1_SCL   I458 @SCM_LIB.SCM(SCH_1):PAGE10

 R37 Q_RES_0402LF-33.2,1%,1/16W,CHIA
     1 IRQ_SMI_ACTIVE_GF_N @SCM_LIB.SCM(SCH_1):IRQ_SMI_ACTIVE_GF_N   I133 @SCM_LIB.SCM(SCH_1):PAGE13
     2 IRQ_SMI_ACTIVE_BMC_N @SCM_LIB.SCM(SCH_1):IRQ_SMI_ACTIVE_BMC_N   I133 @SCM_LIB.SCM(SCH_1):PAGE13

 R38 Q_RES_0402LF-4.7K,1%,1/16W,CHIA
     1 P3V3_AUX @SCM_LIB.SCM(SCH_1):P3V3_AUX   I200 @SCM_LIB.SCM(SCH_1):PAGE13
     2 FM_BMC_SUSACK_N @SCM_LIB.SCM(SCH_1):FM_BMC_SUSACK_N   I200 @SCM_LIB.SCM(SCH_1):PAGE13

 R39 Q_RES_0402LF-0,5%,1/16W,CHIP,CA
     1 SPA_SOUT_SW_BUF_R @SCM_LIB.SCM(SCH_1):SPA_SOUT_SW_BUF_R   I267 @SCM_LIB.SCM(SCH_1):PAGE30
     2 SPA_SOUT_SW_BUF @SCM_LIB.SCM(SCH_1):SPA_SOUT_SW_BUF   I267 @SCM_LIB.SCM(SCH_1):PAGE30

 R40 Q_RES_0402LF-2K,1%,1/16W,EMPTYA
     1    GND @SCM_LIB.SCM(SCH_1):GND   I171 @SCM_LIB.SCM(SCH_1):PAGE11
     2 PWRGD_SYS_PWROK @SCM_LIB.SCM(SCH_1):PWRGD_SYS_PWROK   I171 @SCM_LIB.SCM(SCH_1):PAGE11

 R41 Q_RES_0402LF-10K,1%,1/16W,EMPTA
     1 P3V3_AUX @SCM_LIB.SCM(SCH_1):P3V3_AUX   I225 @SCM_LIB.SCM(SCH_1):PAGE11
     2 LPC_ESPI_SEL @SCM_LIB.SCM(SCH_1):LPC_ESPI_SEL   I225 @SCM_LIB.SCM(SCH_1):PAGE11

 R42 Q_RES_0402LF-4.7K,1%,1/16W,CHIA
     1 P3V3_AUX @SCM_LIB.SCM(SCH_1):P3V3_AUX   I222 @SCM_LIB.SCM(SCH_1):PAGE27
     2   Q7_D @SCM_LIB.SCM(SCH_1):Q7_D   I222 @SCM_LIB.SCM(SCH_1):PAGE27

 R43 Q_RES_0402LF-220,1%,1/16W,CHIPA
     1 ID_LED_P3V3_AUX @SCM_LIB.SCM(SCH_1):ID_LED_P3V3_AUX    I79 @SCM_LIB.SCM(SCH_1):PAGE49
     2 P3V3_AUX @SCM_LIB.SCM(SCH_1):P3V3_AUX    I79 @SCM_LIB.SCM(SCH_1):PAGE49

 R44 Q_RES_0402LF-4.7K,1%,1/16W,EMPA
     1 P3V3_AUX @SCM_LIB.SCM(SCH_1):P3V3_AUX   I175 @SCM_LIB.SCM(SCH_1):PAGE11
     2 SYS_PWRBTN_N @SCM_LIB.SCM(SCH_1):SYS_PWRBTN_N   I175 @SCM_LIB.SCM(SCH_1):PAGE11

 R45 Q_RES_0402LF-4.7K,1%,1/16W,CHIA
     1 P3V3_AUX @SCM_LIB.SCM(SCH_1):P3V3_AUX   I176 @SCM_LIB.SCM(SCH_1):PAGE11
     2 FM_THROTTLE_N @SCM_LIB.SCM(SCH_1):FM_THROTTLE_N   I176 @SCM_LIB.SCM(SCH_1):PAGE11

 R46 Q_RES_0402LF-33.2,1%,1/16W,CHIA
     1 SMB_BMC_MM14_SDA @SCM_LIB.SCM(SCH_1):SMB_BMC_MM14_SDA   I459 @SCM_LIB.SCM(SCH_1):PAGE10
     2 SMB_BMC_MM14_R1_SDA @SCM_LIB.SCM(SCH_1):SMB_BMC_MM14_R1_SDA   I459 @SCM_LIB.SCM(SCH_1):PAGE10

 R47 Q_RES_0402LF-33.2,1%,1/16W,CHIA
     1 SMB_BMC_TPM_MM16_SCL @SCM_LIB.SCM(SCH_1):SMB_BMC_TPM_MM16_SCL   I106 @SCM_LIB.SCM(SCH_1):PAGE46
     2 SMB_BMC_MM16_R5_SCL @SCM_LIB.SCM(SCH_1):SMB_BMC_MM16_R5_SCL   I106 @SCM_LIB.SCM(SCH_1):PAGE46

 R48 Q_RES_0402LF-33.2,1%,1/16W,EMPA
     1 EMMC_CMD_R @SCM_LIB.SCM(SCH_1):EMMC_CMD_R    I35 @SCM_LIB.SCM(SCH_1):PAGE21
     2 BMC_EMMC_CMD @SCM_LIB.SCM(SCH_1):BMC_EMMC_CMD    I35 @SCM_LIB.SCM(SCH_1):PAGE21

 R49 Q_RES_0402LF-0,5%,1/16W,CHIP,CA
     1 PWRGD_P1V0_AUX @SCM_LIB.SCM(SCH_1):PWRGD_P1V0_AUX    I72 @SCM_LIB.SCM(SCH_1):PAGE22
     2 PWRGD_P1V0_AUX_R2 @SCM_LIB.SCM(SCH_1):PWRGD_P1V0_AUX_R2    I72 @SCM_LIB.SCM(SCH_1):PAGE22

 R50 Q_RES_0402LF-10K,1%,1/16W,CHIPA
     1 P3V3_AUX @SCM_LIB.SCM(SCH_1):P3V3_AUX   I104 @SCM_LIB.SCM(SCH_1):PAGE46
     2 FM_TPM_PRSNT_1_N @SCM_LIB.SCM(SCH_1):FM_TPM_PRSNT_1_N   I104 @SCM_LIB.SCM(SCH_1):PAGE46

 R51 Q_RES_0402LF-0,5%,1/16W,CHIP,CA
     1 H_CPU0_PROCHOT_LVC1_N @SCM_LIB.SCM(SCH_1):H_CPU0_PROCHOT_LVC1_N    I80 @SCM_LIB.SCM(SCH_1):PAGE35
     2 H_CPU0_PROCHOT_LVC1_R_N @SCM_LIB.SCM(SCH_1):H_CPU0_PROCHOT_LVC1_R_N    I80 @SCM_LIB.SCM(SCH_1):PAGE35

 R52 Q_RES_0402LF-4.7K,1%,1/16W,CHIA
     1 P3V3_AUX @SCM_LIB.SCM(SCH_1):P3V3_AUX    I67 @SCM_LIB.SCM(SCH_1):PAGE26
     2 TMC75_A1 @SCM_LIB.SCM(SCH_1):TMC75_A1    I67 @SCM_LIB.SCM(SCH_1):PAGE26

 R53 Q_RES_0402LF-1K,1%,1/16W,EMPTYA
     1 TMC75_A1 @SCM_LIB.SCM(SCH_1):TMC75_A1    I66 @SCM_LIB.SCM(SCH_1):PAGE26
     2    GND @SCM_LIB.SCM(SCH_1):GND    I66 @SCM_LIB.SCM(SCH_1):PAGE26

 R54 Q_RES_0402LF-10K,1%,1/16W,CHIPA
     1 SMB_BMC_ALERT16_R_N @SCM_LIB.SCM(SCH_1):SMB_BMC_ALERT16_R_N    I65 @SCM_LIB.SCM(SCH_1):PAGE26
     2 SMB_BMC_ALERT16_N @SCM_LIB.SCM(SCH_1):SMB_BMC_ALERT16_N    I65 @SCM_LIB.SCM(SCH_1):PAGE26

 R55 Q_RES_0402LF-4.7K,1%,1/16W,CHIA
     1 P3V3_AUX @SCM_LIB.SCM(SCH_1):P3V3_AUX   I278 @SCM_LIB.SCM(SCH_1):PAGE13
     2 FM_BMC_READY_R_PLD_N @SCM_LIB.SCM(SCH_1):FM_BMC_READY_R_PLD_N   I278 @SCM_LIB.SCM(SCH_1):PAGE13

 R56 Q_RES_0402LF-4.7K,1%,1/16W,CHIA
     1 P3V3_AUX @SCM_LIB.SCM(SCH_1):P3V3_AUX   I279 @SCM_LIB.SCM(SCH_1):PAGE13
     2 FM_BIOS_DEBUG_EN_R_N @SCM_LIB.SCM(SCH_1):FM_BIOS_DEBUG_EN_R_N   I279 @SCM_LIB.SCM(SCH_1):PAGE13

 R57 Q_RES_0402LF-0,5%,1/16W,CHIP,CA
     1 BSM_PRSNT_R_N @SCM_LIB.SCM(SCH_1):BSM_PRSNT_R_N   I167 @SCM_LIB.SCM(SCH_1):PAGE21
     2 BSM_PRSNT_N @SCM_LIB.SCM(SCH_1):BSM_PRSNT_N   I167 @SCM_LIB.SCM(SCH_1):PAGE21

 R58 Q_RES_0402LF-4.7K,1%,1/16W,EMPB
     1 P3V3_AUX @SCM_LIB.SCM(SCH_1):P3V3_AUX   I168 @SCM_LIB.SCM(SCH_1):PAGE21
     2 SPI_BMC_HOLD0_N @SCM_LIB.SCM(SCH_1):SPI_BMC_HOLD0_N   I168 @SCM_LIB.SCM(SCH_1):PAGE21

 R59 Q_RES_0402LF-10K,1%,1/16W,CHIPA
     1 P3V3_AUX @SCM_LIB.SCM(SCH_1):P3V3_AUX    I98 @SCM_LIB.SCM(SCH_1):PAGE46
     2 IRQ_TPM_SPI_N @SCM_LIB.SCM(SCH_1):IRQ_TPM_SPI_N    I98 @SCM_LIB.SCM(SCH_1):PAGE46

 R60 Q_RES_0402LF-33.2,1%,1/16W,CHIA
     1 RST_ROT_CPU_R1_N @SCM_LIB.SCM(SCH_1):RST_ROT_CPU_R1_N   I382 @SCM_LIB.SCM(SCH_1):PAGE13
     2 RST_ROT_CPU_N @SCM_LIB.SCM(SCH_1):RST_ROT_CPU_N   I382 @SCM_LIB.SCM(SCH_1):PAGE13

 R61 Q_RES_0402LF-4.7K,1%,1/16W,CHIA
     1 P3V3_AUX @SCM_LIB.SCM(SCH_1):P3V3_AUX   I204 @SCM_LIB.SCM(SCH_1):PAGE13
     2 IRQ_BMC_PCH_NMI_N @SCM_LIB.SCM(SCH_1):IRQ_BMC_PCH_NMI_N   I204 @SCM_LIB.SCM(SCH_1):PAGE13

 R62 Q_RES_0402LF-4.7K,1%,1/16W,CHIA
     1 P3V3_AUX @SCM_LIB.SCM(SCH_1):P3V3_AUX   I350 @SCM_LIB.SCM(SCH_1):PAGE12
     2 FM_PCH_BMC_THERMTRIP_N @SCM_LIB.SCM(SCH_1):FM_PCH_BMC_THERMTRIP_N   I350 @SCM_LIB.SCM(SCH_1):PAGE12

 R63 Q_RES_0402LF-0,5%,1/16W,EMPTY,A
     1 SGPIO_CLK_1 @SCM_LIB.SCM(SCH_1):SGPIO_CLK_1   I231 @SCM_LIB.SCM(SCH_1):PAGE11
     2    GND @SCM_LIB.SCM(SCH_1):GND   I231 @SCM_LIB.SCM(SCH_1):PAGE11

 R64 Q_RES_0402LF-0,5%,1/16W,EMPTY,A
     1 SGPIO_CLK_0 @SCM_LIB.SCM(SCH_1):SGPIO_CLK_0   I233 @SCM_LIB.SCM(SCH_1):PAGE11
     2    GND @SCM_LIB.SCM(SCH_1):GND   I233 @SCM_LIB.SCM(SCH_1):PAGE11

 R65 Q_RES_0402LF-33.2,1%,1/16W,CHIA
     1 BMC_CPLD_GPIO_2_R1 @SCM_LIB.SCM(SCH_1):BMC_CPLD_GPIO_2_R1   I421 @SCM_LIB.SCM(SCH_1):PAGE13
     2 BMC_CPLD_GPIO_2 @SCM_LIB.SCM(SCH_1):BMC_CPLD_GPIO_2   I421 @SCM_LIB.SCM(SCH_1):PAGE13

 R66 Q_RES_0402LF-100K,1%,1/16W,CHIA
     1    GND @SCM_LIB.SCM(SCH_1):GND   I181 @SCM_LIB.SCM(SCH_1):PAGE11
     2 PWRGD_PSU_AC_PWROK @SCM_LIB.SCM(SCH_1):PWRGD_PSU_AC_PWROK   I181 @SCM_LIB.SCM(SCH_1):PAGE11

 R67 Q_RES_0402LF-4.7K,1%,1/16W,CHIA
     1 P3V3_AUX @SCM_LIB.SCM(SCH_1):P3V3_AUX   I146 @SCM_LIB.SCM(SCH_1):PAGE30
     2 UART_BMC_5_TXD_BUF1_R @SCM_LIB.SCM(SCH_1):UART_BMC_5_TXD_BUF1_R   I146 @SCM_LIB.SCM(SCH_1):PAGE30

 R68 Q_RES_0402LF-4.7K,1%,1/16W,CHIA
     1 P3V3_AUX @SCM_LIB.SCM(SCH_1):P3V3_AUX   I179 @SCM_LIB.SCM(SCH_1):PAGE11
     2 IRQ_SGPIO_N @SCM_LIB.SCM(SCH_1):IRQ_SGPIO_N   I179 @SCM_LIB.SCM(SCH_1):PAGE11

 R69 Q_RES_0402LF-4.7K,1%,1/16W,CHIA
     1 P3V3_AUX @SCM_LIB.SCM(SCH_1):P3V3_AUX   I227 @SCM_LIB.SCM(SCH_1):PAGE11
     2 RST_SGPIO_RESET_N @SCM_LIB.SCM(SCH_1):RST_SGPIO_RESET_N   I227 @SCM_LIB.SCM(SCH_1):PAGE11

 R70 Q_RES_0402LF-33.2,1%,1/16W,CHIA
     1 RST_PCA9548_SENSOR_R_N @SCM_LIB.SCM(SCH_1):RST_PCA9548_SENSOR_R_N   I419 @SCM_LIB.SCM(SCH_1):PAGE13
     2 RST_PCA9548_SENSOR_N @SCM_LIB.SCM(SCH_1):RST_PCA9548_SENSOR_N   I419 @SCM_LIB.SCM(SCH_1):PAGE13

 R71 Q_RES_0402LF-33.2,1%,1/16W,CHIA
     1 SMB_BMC_MM5_R_SCL @SCM_LIB.SCM(SCH_1):SMB_BMC_MM5_R_SCL   I277 @SCM_LIB.SCM(SCH_1):PAGE12
     2 SMB_BMC_MM5_SCL @SCM_LIB.SCM(SCH_1):SMB_BMC_MM5_SCL   I277 @SCM_LIB.SCM(SCH_1):PAGE12

 R72 Q_RES_0402LF-4.7K,1%,1/16W,CHIA
     1 P3V3_AUX @SCM_LIB.SCM(SCH_1):P3V3_AUX   I231 @SCM_LIB.SCM(SCH_1):PAGE30
     2 UART_BMC_5_RXD_BUF1 @SCM_LIB.SCM(SCH_1):UART_BMC_5_RXD_BUF1   I231 @SCM_LIB.SCM(SCH_1):PAGE30

 R73 Q_RES_0402LF-1K,1%,1/16W,EMPTYA
     1 P3V3_AUX @SCM_LIB.SCM(SCH_1):P3V3_AUX   I118 @SCM_LIB.SCM(SCH_1):PAGE11
     2 SGPIO_LD_1 @SCM_LIB.SCM(SCH_1):SGPIO_LD_1   I118 @SCM_LIB.SCM(SCH_1):PAGE11

 R74 Q_RES_0402LF-2K,1%,1/16W,CHIP,A
     1 P3V3_AUX @SCM_LIB.SCM(SCH_1):P3V3_AUX   I117 @SCM_LIB.SCM(SCH_1):PAGE11
     2 SGPIO_DI_1 @SCM_LIB.SCM(SCH_1):SGPIO_DI_1   I117 @SCM_LIB.SCM(SCH_1):PAGE11

 R75 Q_RES_0402LF-2K,1%,1/16W,CHIP,A
     1 P3V3_AUX @SCM_LIB.SCM(SCH_1):P3V3_AUX   I110 @SCM_LIB.SCM(SCH_1):PAGE11
     2 SGPIO_DO_1 @SCM_LIB.SCM(SCH_1):SGPIO_DO_1   I110 @SCM_LIB.SCM(SCH_1):PAGE11

 R76 Q_RES_0402LF-2K,1%,1/16W,CHIP,A
     1 P3V3_AUX @SCM_LIB.SCM(SCH_1):P3V3_AUX   I230 @SCM_LIB.SCM(SCH_1):PAGE11
     2 SGPIO_CLK_1 @SCM_LIB.SCM(SCH_1):SGPIO_CLK_1   I230 @SCM_LIB.SCM(SCH_1):PAGE11

 R77 Q_RES_0402LF-1K,1%,1/16W,EMPTYA
     1 P3V3_AUX @SCM_LIB.SCM(SCH_1):P3V3_AUX   I128 @SCM_LIB.SCM(SCH_1):PAGE11
     2 SGPIO_LD_0 @SCM_LIB.SCM(SCH_1):SGPIO_LD_0   I128 @SCM_LIB.SCM(SCH_1):PAGE11

 R78 Q_RES_0402LF-2K,1%,1/16W,CHIP,A
     1 P3V3_AUX @SCM_LIB.SCM(SCH_1):P3V3_AUX   I129 @SCM_LIB.SCM(SCH_1):PAGE11
     2 SGPIO_DI_0 @SCM_LIB.SCM(SCH_1):SGPIO_DI_0   I129 @SCM_LIB.SCM(SCH_1):PAGE11

 R79 Q_RES_0402LF-2K,1%,1/16W,CHIP,A
     1 P3V3_AUX @SCM_LIB.SCM(SCH_1):P3V3_AUX   I130 @SCM_LIB.SCM(SCH_1):PAGE11
     2 SGPIO_DO_0 @SCM_LIB.SCM(SCH_1):SGPIO_DO_0   I130 @SCM_LIB.SCM(SCH_1):PAGE11

 R80 Q_RES_0402LF-220,1%,1/16W,CHIPA
     1 LED_D22_R @SCM_LIB.SCM(SCH_1):LED_D22_R   I210 @SCM_LIB.SCM(SCH_1):PAGE50
     2 P5V_AUX @SCM_LIB.SCM(SCH_1):P5V_AUX   I210 @SCM_LIB.SCM(SCH_1):PAGE50

 R81 Q_RES_0402LF-4.7K,1%,1/16W,CHIA
     1 P3V3_AUX @SCM_LIB.SCM(SCH_1):P3V3_AUX   I245 @SCM_LIB.SCM(SCH_1):PAGE11
     2 PWR_BTN_BMC_N @SCM_LIB.SCM(SCH_1):PWR_BTN_BMC_N   I245 @SCM_LIB.SCM(SCH_1):PAGE11

 R82 Q_RES_0402LF-2K,1%,1/16W,CHIP,A
     1 P3V3_AUX @SCM_LIB.SCM(SCH_1):P3V3_AUX   I232 @SCM_LIB.SCM(SCH_1):PAGE11
     2 SGPIO_CLK_0 @SCM_LIB.SCM(SCH_1):SGPIO_CLK_0   I232 @SCM_LIB.SCM(SCH_1):PAGE11

 R83 Q_RES_0402LF-0,5%,1/16W,CHIP,CA
     1 FM_UART_SEL_N @SCM_LIB.SCM(SCH_1):FM_UART_SEL_N   I164 @SCM_LIB.SCM(SCH_1):PAGE28
     2 FM_UART_SWITCH_N @SCM_LIB.SCM(SCH_1):FM_UART_SWITCH_N   I164 @SCM_LIB.SCM(SCH_1):PAGE28

 R84 Q_RES_0402LF-0,5%,1/16W,CHIP,CA
     1 V_VGAVS_BUF_R @SCM_LIB.SCM(SCH_1):V_VGAVS_BUF_R    I61 @SCM_LIB.SCM(SCH_1):PAGE23
     2 V_VGAVS_BUF @SCM_LIB.SCM(SCH_1):V_VGAVS_BUF    I61 @SCM_LIB.SCM(SCH_1):PAGE23

 R85 Q_RES_0402LF-0,5%,1/16W,CHIP,CA
     1 V_VGAHS_BUF_R @SCM_LIB.SCM(SCH_1):V_VGAHS_BUF_R    I60 @SCM_LIB.SCM(SCH_1):PAGE23
     2 V_VGAHS_BUF @SCM_LIB.SCM(SCH_1):V_VGAHS_BUF    I60 @SCM_LIB.SCM(SCH_1):PAGE23

 R86 Q_RES_0402LF-0,5%,1/16W,CHIP,CA
     1 P3V3_RGM @SCM_LIB.SCM(SCH_1):P3V3_RGM    I51 @SCM_LIB.SCM(SCH_1):PAGE23
     2 V_BMC_DDC_LS_GATE @SCM_LIB.SCM(SCH_1):V_BMC_DDC_LS_GATE    I51 @SCM_LIB.SCM(SCH_1):PAGE23

 R87 Q_RES_0402LF-150,1%,1/16W,CHIPA
     1 V_DACB_IO @SCM_LIB.SCM(SCH_1):V_DACB_IO    I57 @SCM_LIB.SCM(SCH_1):PAGE23
     2    GND @SCM_LIB.SCM(SCH_1):GND    I57 @SCM_LIB.SCM(SCH_1):PAGE23

 R88 Q_RES_0402LF-150,1%,1/16W,CHIPA
     1 V_DACG_IO @SCM_LIB.SCM(SCH_1):V_DACG_IO    I59 @SCM_LIB.SCM(SCH_1):PAGE23
     2    GND @SCM_LIB.SCM(SCH_1):GND    I59 @SCM_LIB.SCM(SCH_1):PAGE23

 R89 Q_RES_0402LF-150,1%,1/16W,CHIPA
     1 V_DACR_IO @SCM_LIB.SCM(SCH_1):V_DACR_IO    I65 @SCM_LIB.SCM(SCH_1):PAGE23
     2    GND @SCM_LIB.SCM(SCH_1):GND    I65 @SCM_LIB.SCM(SCH_1):PAGE23

 R90 Q_RES_0402LF-4.7K,1%,1/16W,EMPA
     1 P3V3_AUX @SCM_LIB.SCM(SCH_1):P3V3_AUX   I182 @SCM_LIB.SCM(SCH_1):PAGE21
     2 RST_SPI_BMC_FLASH_R2_N @SCM_LIB.SCM(SCH_1):RST_SPI_BMC_FLASH_R2_N   I182 @SCM_LIB.SCM(SCH_1):PAGE21

 R91 Q_RES_0402LF-2.2K,5%,1/16W,CHIA
     1 CRT_VCC5 @SCM_LIB.SCM(SCH_1):CRT_VCC5    I62 @SCM_LIB.SCM(SCH_1):PAGE23
     2 V_BMC_LS_DDC_SDA @SCM_LIB.SCM(SCH_1):V_BMC_LS_DDC_SDA    I62 @SCM_LIB.SCM(SCH_1):PAGE23

 R92 Q_RES_0402LF-2.2K,5%,1/16W,CHIA
     1 CRT_VCC5 @SCM_LIB.SCM(SCH_1):CRT_VCC5    I64 @SCM_LIB.SCM(SCH_1):PAGE23
     2 V_BMC_LS_DDC_SCL @SCM_LIB.SCM(SCH_1):V_BMC_LS_DDC_SCL    I64 @SCM_LIB.SCM(SCH_1):PAGE23

 R93 Q_RES_0402LF-33.2,1%,1/16W,CHIA
     1 SMB_BMC_MM5_R_SDA @SCM_LIB.SCM(SCH_1):SMB_BMC_MM5_R_SDA   I276 @SCM_LIB.SCM(SCH_1):PAGE12
     2 SMB_BMC_MM5_SDA @SCM_LIB.SCM(SCH_1):SMB_BMC_MM5_SDA   I276 @SCM_LIB.SCM(SCH_1):PAGE12

 R94 Q_RES_0402LF-4.7K,1%,1/16W,CHIA
     1 SPI_BMC_BOOT_MOSI @SCM_LIB.SCM(SCH_1):SPI_BMC_BOOT_MOSI   I246 @SCM_LIB.SCM(SCH_1):PAGE27
     2    GND @SCM_LIB.SCM(SCH_1):GND   I246 @SCM_LIB.SCM(SCH_1):PAGE27

 R95 Q_RES_0402LF-0,5%,1/16W,CHIP,CA
     1 SMB_DEBUG_AUX_LVC3_USB_SDA @SCM_LIB.SCM(SCH_1):SMB_DEBUG_AUX_LVC3_USB_SDA   I152 @SCM_LIB.SCM(SCH_1):PAGE28
     2 SMB_DEBUG_AUX_LVC3_USB_R3_SDA @SCM_LIB.SCM(SCH_1):SMB_DEBUG_AUX_LVC3_USB_R3_SDA   I152 @SCM_LIB.SCM(SCH_1):PAGE28

 R96 Q_RES_0402LF-33.2,1%,1/16W,CHIA
     1 BMC_EMMC_RST_R_N @SCM_LIB.SCM(SCH_1):BMC_EMMC_RST_R_N   I286 @SCM_LIB.SCM(SCH_1):PAGE13
     2 BMC_EMMC_RST_N @SCM_LIB.SCM(SCH_1):BMC_EMMC_RST_N   I286 @SCM_LIB.SCM(SCH_1):PAGE13

 R97 Q_RES_0402LF-0,5%,1/16W,CHIP,CA
     1 SPI_BMC_TPM_MOSI_R @SCM_LIB.SCM(SCH_1):SPI_BMC_TPM_MOSI_R   I115 @SCM_LIB.SCM(SCH_1):PAGE46
     2 SPI_BMC_TPM_MOSI @SCM_LIB.SCM(SCH_1):SPI_BMC_TPM_MOSI   I115 @SCM_LIB.SCM(SCH_1):PAGE46

 R98 Q_RES_0402LF-0,5%,1/16W,CHIP,CA
     1 SPI_BMC_TPM_MISO_R @SCM_LIB.SCM(SCH_1):SPI_BMC_TPM_MISO_R   I119 @SCM_LIB.SCM(SCH_1):PAGE46
     2 SPI_BMC_TPM_MISO @SCM_LIB.SCM(SCH_1):SPI_BMC_TPM_MISO   I119 @SCM_LIB.SCM(SCH_1):PAGE46

 R99 Q_RES_0402LF-0,5%,1/16W,CHIP,CA
     1 PWRGD_P3V3_RGM_R @SCM_LIB.SCM(SCH_1):PWRGD_P3V3_RGM_R    I96 @SCM_LIB.SCM(SCH_1):PAGE52
     2 PWRGD_P3V3_RGM @SCM_LIB.SCM(SCH_1):PWRGD_P3V3_RGM    I96 @SCM_LIB.SCM(SCH_1):PAGE52

R100 Q_RES_0402LF-33.2,1%,1/16W,CHIA
     1 SPI_BMC_TPM_CS2_N_R @SCM_LIB.SCM(SCH_1):SPI_BMC_TPM_CS2_N_R   I147 @SCM_LIB.SCM(SCH_1):PAGE46
     2 SPI_BMC_TPM_CS2_R_N @SCM_LIB.SCM(SCH_1):SPI_BMC_TPM_CS2_R_N   I147 @SCM_LIB.SCM(SCH_1):PAGE46

R101 Q_RES_0402LF-4.7K,1%,1/16W,CHIA
     1 P3V3_AUX @SCM_LIB.SCM(SCH_1):P3V3_AUX   I214 @SCM_LIB.SCM(SCH_1):PAGE11
     2 RMII_RXER @SCM_LIB.SCM(SCH_1):RMII_RXER   I214 @SCM_LIB.SCM(SCH_1):PAGE11

R102 Q_RES_0402LF-33.2,1%,1/16W,CHIA
     1 UART_BMC_5_TXD_BUF @SCM_LIB.SCM(SCH_1):UART_BMC_5_TXD_BUF   I148 @SCM_LIB.SCM(SCH_1):PAGE30
     2 UART_BMC_5_TXD_BUF_R @SCM_LIB.SCM(SCH_1):UART_BMC_5_TXD_BUF_R   I148 @SCM_LIB.SCM(SCH_1):PAGE30

R103 Q_RES_0402LF-4.7K,1%,1/16W,CHIA
     1 P3V3_AUX @SCM_LIB.SCM(SCH_1):P3V3_AUX   I219 @SCM_LIB.SCM(SCH_1):PAGE11
     2 RMII_TXEN @SCM_LIB.SCM(SCH_1):RMII_TXEN   I219 @SCM_LIB.SCM(SCH_1):PAGE11

R104 Q_RES_0402LF-33.2,1%,1/16W,CHIA
     1 UART_BMC_5_RXD_BUF_R @SCM_LIB.SCM(SCH_1):UART_BMC_5_RXD_BUF_R   I147 @SCM_LIB.SCM(SCH_1):PAGE30
     2 UART_BMC_5_RXD_BUF1 @SCM_LIB.SCM(SCH_1):UART_BMC_5_RXD_BUF1   I147 @SCM_LIB.SCM(SCH_1):PAGE30

R105 Q_RES_0402LF-0,5%,1/16W,CHIP,CA
     1 SMB_BMC_MM16_R4_SCL @SCM_LIB.SCM(SCH_1):SMB_BMC_MM16_R4_SCL    I58 @SCM_LIB.SCM(SCH_1):PAGE36
     2 SMB_BMC_MM16_R5_SCL @SCM_LIB.SCM(SCH_1):SMB_BMC_MM16_R5_SCL    I58 @SCM_LIB.SCM(SCH_1):PAGE36

R106 Q_RES_0402LF-0,5%,1/16W,EMPTY,A
     1 RST_BMC_SRST_N @SCM_LIB.SCM(SCH_1):RST_BMC_SRST_N    I12 @SCM_LIB.SCM(SCH_1):PAGE22
     2 RST_BMC_EXTRST_R2_N @SCM_LIB.SCM(SCH_1):RST_BMC_EXTRST_R2_N    I12 @SCM_LIB.SCM(SCH_1):PAGE22

R107 Q_RES_0402LF-316,1%,1/16W,CHIPA
     1 LED_D21_R3 @SCM_LIB.SCM(SCH_1):LED_D21_R3   I222 @SCM_LIB.SCM(SCH_1):PAGE50
     2 LED_D21_R2 @SCM_LIB.SCM(SCH_1):LED_D21_R2   I222 @SCM_LIB.SCM(SCH_1):PAGE50

R108 Q_RES_0402LF-49.9,1%,1/16W,CHIA
     1 RST_SRST_PLD_BMC_BUF_N @SCM_LIB.SCM(SCH_1):RST_SRST_PLD_BMC_BUF_N    I65 @SCM_LIB.SCM(SCH_1):PAGE22
     2 RST_BMC_SRST_BUF_R_N @SCM_LIB.SCM(SCH_1):RST_BMC_SRST_BUF_R_N    I65 @SCM_LIB.SCM(SCH_1):PAGE22

R109 Q_RES_0402LF-0,5%,1/16W,CHIP,CA
     1 SPI_BMC_TPM_CLK_R @SCM_LIB.SCM(SCH_1):SPI_BMC_TPM_CLK_R   I114 @SCM_LIB.SCM(SCH_1):PAGE46
     2 SPI_BMC_TPM_CLK @SCM_LIB.SCM(SCH_1):SPI_BMC_TPM_CLK   I114 @SCM_LIB.SCM(SCH_1):PAGE46

R110 Q_RES_0402LF-0,5%,1/16W,CHIP,CA
     1 RST_BMC_EXTRST_R3_N @SCM_LIB.SCM(SCH_1):RST_BMC_EXTRST_R3_N   I116 @SCM_LIB.SCM(SCH_1):PAGE46
     2 RST_BMC_EXTRST_R2_N @SCM_LIB.SCM(SCH_1):RST_BMC_EXTRST_R2_N   I116 @SCM_LIB.SCM(SCH_1):PAGE46

R111 Q_RES_0402LF-33.2,1%,1/16W,CHIA
     1 FM_BMC_READY_R_PLD_N @SCM_LIB.SCM(SCH_1):FM_BMC_READY_R_PLD_N   I266 @SCM_LIB.SCM(SCH_1):PAGE13
     2 FM_BMC_READY_PLD_N @SCM_LIB.SCM(SCH_1):FM_BMC_READY_PLD_N   I266 @SCM_LIB.SCM(SCH_1):PAGE13

R112 Q_RES_0402LF-33.2,1%,1/16W,CHIA
     1 FM_BIOS_DEBUG_EN_R_N @SCM_LIB.SCM(SCH_1):FM_BIOS_DEBUG_EN_R_N   I427 @SCM_LIB.SCM(SCH_1):PAGE13
     2 FM_BIOS_DEBUG_EN_N @SCM_LIB.SCM(SCH_1):FM_BIOS_DEBUG_EN_N   I427 @SCM_LIB.SCM(SCH_1):PAGE13

R113 Q_RES_0402LF-0,5%,1/16W,CHIP,CA
     1 IRQ_TPM_SPI_N @SCM_LIB.SCM(SCH_1):IRQ_TPM_SPI_N   I105 @SCM_LIB.SCM(SCH_1):PAGE46
     2 IRQ_BMC_TPM_SPI_R_N @SCM_LIB.SCM(SCH_1):IRQ_BMC_TPM_SPI_R_N   I105 @SCM_LIB.SCM(SCH_1):PAGE46

R114 Q_RES_0402LF-0,5%,1/16W,CHIP,CA
     1 SMB_BMC_MM16_R4_SDA @SCM_LIB.SCM(SCH_1):SMB_BMC_MM16_R4_SDA    I57 @SCM_LIB.SCM(SCH_1):PAGE36
     2 SMB_BMC_MM16_R5_SDA @SCM_LIB.SCM(SCH_1):SMB_BMC_MM16_R5_SDA    I57 @SCM_LIB.SCM(SCH_1):PAGE36

R115 Q_RES_0402LF-4.7K,1%,1/16W,EMPA
     1 PGPPA_BMC_AUX @SCM_LIB.SCM(SCH_1):PGPPA_BMC_AUX     I4 @SCM_LIB.SCM(SCH_1):PAGE12
     2 ESPI_HOST_LPC_BMC_LFRAME_N @SCM_LIB.SCM(SCH_1):ESPI_HOST_LPC_BMC_LFRAME_N     I4 @SCM_LIB.SCM(SCH_1):PAGE12

R116 Q_RES_0402LF-4.7K,1%,1/16W,CHIA
     1 PGPPA_BMC_AUX @SCM_LIB.SCM(SCH_1):PGPPA_BMC_AUX     I3 @SCM_LIB.SCM(SCH_1):PAGE12
     2 IRQ_BMC_LPC_SERIRQ_ESPI_GF @SCM_LIB.SCM(SCH_1):IRQ_BMC_LPC_SERIRQ_ESPI_GF     I3 @SCM_LIB.SCM(SCH_1):PAGE12

R117 Q_RES_0402LF-4.7K,1%,1/16W,EMPA
     1 PGPPA_BMC_AUX @SCM_LIB.SCM(SCH_1):PGPPA_BMC_AUX     I2 @SCM_LIB.SCM(SCH_1):PAGE12
     2 RST_BMC_LPC_ESPI_N @SCM_LIB.SCM(SCH_1):RST_BMC_LPC_ESPI_N     I2 @SCM_LIB.SCM(SCH_1):PAGE12

R118 Q_RES_0402LF-100K,1%,1/16W,CHIA
     1    GND @SCM_LIB.SCM(SCH_1):GND    I53 @SCM_LIB.SCM(SCH_1):PAGE12
     2 RST_PLTRST_N @SCM_LIB.SCM(SCH_1):RST_PLTRST_N    I53 @SCM_LIB.SCM(SCH_1):PAGE12

R119 Q_RES_0402LF-33.2,1%,1/16W,CHIA
     1 IRQ_BMC_LPC_SERIRQ_ESPI_GF @SCM_LIB.SCM(SCH_1):IRQ_BMC_LPC_SERIRQ_ESPI_GF    I34 @SCM_LIB.SCM(SCH_1):PAGE12
     2 IRQ_ESPI_LPC_SERIRQ_ALERT0_N @SCM_LIB.SCM(SCH_1):IRQ_ESPI_LPC_SERIRQ_ALERT0_N    I34 @SCM_LIB.SCM(SCH_1):PAGE12

R120 Q_RES_0402LF-33.2,1%,1/16W,CHIA
     1 RST_BMC_LPC_ESPI_N @SCM_LIB.SCM(SCH_1):RST_BMC_LPC_ESPI_N    I33 @SCM_LIB.SCM(SCH_1):PAGE12
     2 RST_ESPI_LPC_BMC_N @SCM_LIB.SCM(SCH_1):RST_ESPI_LPC_BMC_N    I33 @SCM_LIB.SCM(SCH_1):PAGE12

R121 Q_RES_0402LF-33.2,1%,1/16W,CHIA
     1 FM_CPU_RMCA_CATERR_LVT3_R_N @SCM_LIB.SCM(SCH_1):FM_CPU_RMCA_CATERR_LVT3_R_N   I381 @SCM_LIB.SCM(SCH_1):PAGE13
     2 FM_CPU_MSMI_CATERR_LVT3_N @SCM_LIB.SCM(SCH_1):FM_CPU_MSMI_CATERR_LVT3_N   I381 @SCM_LIB.SCM(SCH_1):PAGE13

R122 Q_RES_0402LF-33.2,1%,1/16W,CHIA
     1 FM_BIC_DEBUG_SW_N @SCM_LIB.SCM(SCH_1):FM_BIC_DEBUG_SW_N   I399 @SCM_LIB.SCM(SCH_1):PAGE13
     2 FM_BIC_DEBUG_SW_N_R @SCM_LIB.SCM(SCH_1):FM_BIC_DEBUG_SW_N_R   I399 @SCM_LIB.SCM(SCH_1):PAGE13

R123 Q_RES_0402LF-33.2,1%,1/16W,CHIA
     1 FM_TPM_PRSNT_1_N @SCM_LIB.SCM(SCH_1):FM_TPM_PRSNT_1_N   I156 @SCM_LIB.SCM(SCH_1):PAGE34
     2 FM_TPM_PRSNT_1_R_N @SCM_LIB.SCM(SCH_1):FM_TPM_PRSNT_1_R_N   I156 @SCM_LIB.SCM(SCH_1):PAGE34

R124 Q_RES_0402LF-2K,1%,1/16W,CHIP,A
     1 P3V3_AUX @SCM_LIB.SCM(SCH_1):P3V3_AUX    I67 @SCM_LIB.SCM(SCH_1):PAGE22
     2 RST_BMC_SRST_BUF_R_N @SCM_LIB.SCM(SCH_1):RST_BMC_SRST_BUF_R_N    I67 @SCM_LIB.SCM(SCH_1):PAGE22

R125 Q_RES_0402LF-100,1%,1/16W,CHIPA
     1 RST_BMC_SRST_BUF_R_N @SCM_LIB.SCM(SCH_1):RST_BMC_SRST_BUF_R_N    I69 @SCM_LIB.SCM(SCH_1):PAGE22
     2 RST_BMC_SRST_N @SCM_LIB.SCM(SCH_1):RST_BMC_SRST_N    I69 @SCM_LIB.SCM(SCH_1):PAGE22

R126 Q_RES_0402LF-10K,1%,1/16W,CHIPA
     1 SMB_PCH_TPM_SDA @SCM_LIB.SCM(SCH_1):SMB_PCH_TPM_SDA   I134 @SCM_LIB.SCM(SCH_1):PAGE46
     2 P3V3_AUX @SCM_LIB.SCM(SCH_1):P3V3_AUX   I134 @SCM_LIB.SCM(SCH_1):PAGE46

R127 Q_RES_0402LF-240,1%,1/16W,CHIPA
     1    GND @SCM_LIB.SCM(SCH_1):GND    I46 @SCM_LIB.SCM(SCH_1):PAGE12
     2 IBMC_MIOZ @SCM_LIB.SCM(SCH_1):IBMC_MIOZ    I46 @SCM_LIB.SCM(SCH_1):PAGE12

R128 Q_RES_0402LF-22,1%,1/16W,CHIP,A
     1 ESPI_LPC_D0_IO0 @SCM_LIB.SCM(SCH_1):ESPI_LPC_D0_IO0   I442 @SCM_LIB.SCM(SCH_1):PAGE12
     2 ESPI_LPC_LAD0_IO0 @SCM_LIB.SCM(SCH_1):ESPI_LPC_LAD0_IO0   I442 @SCM_LIB.SCM(SCH_1):PAGE12

R129 Q_RES_0402LF-22,1%,1/16W,CHIP,A
     1 ESPI_LPC_D1_IO1 @SCM_LIB.SCM(SCH_1):ESPI_LPC_D1_IO1   I445 @SCM_LIB.SCM(SCH_1):PAGE12
     2 ESPI_LPC_LAD1_IO1 @SCM_LIB.SCM(SCH_1):ESPI_LPC_LAD1_IO1   I445 @SCM_LIB.SCM(SCH_1):PAGE12

R130 Q_RES_0402LF-22,1%,1/16W,CHIP,A
     1 ESPI_LPC_D2_IO2 @SCM_LIB.SCM(SCH_1):ESPI_LPC_D2_IO2   I444 @SCM_LIB.SCM(SCH_1):PAGE12
     2 ESPI_LPC_LAD2_IO2 @SCM_LIB.SCM(SCH_1):ESPI_LPC_LAD2_IO2   I444 @SCM_LIB.SCM(SCH_1):PAGE12

R131 Q_RES_0402LF-22,1%,1/16W,CHIP,A
     1 ESPI_LPC_D3_IO3 @SCM_LIB.SCM(SCH_1):ESPI_LPC_D3_IO3   I443 @SCM_LIB.SCM(SCH_1):PAGE12
     2 ESPI_LPC_LAD3_IO3 @SCM_LIB.SCM(SCH_1):ESPI_LPC_LAD3_IO3   I443 @SCM_LIB.SCM(SCH_1):PAGE12

R132 Q_RES_0402LF-33.2,1%,1/16W,CHIA
     1 SMB_BMC_MM1_R_SCL @SCM_LIB.SCM(SCH_1):SMB_BMC_MM1_R_SCL    I98 @SCM_LIB.SCM(SCH_1):PAGE12
     2 SMB_BMC_MM1_SCL @SCM_LIB.SCM(SCH_1):SMB_BMC_MM1_SCL    I98 @SCM_LIB.SCM(SCH_1):PAGE12

R133 Q_RES_0402LF-33.2,1%,1/16W,CHIA
     1 SMB_BMC_MM1_R_SDA @SCM_LIB.SCM(SCH_1):SMB_BMC_MM1_R_SDA    I97 @SCM_LIB.SCM(SCH_1):PAGE12
     2 SMB_BMC_MM1_SDA @SCM_LIB.SCM(SCH_1):SMB_BMC_MM1_SDA    I97 @SCM_LIB.SCM(SCH_1):PAGE12

R134 Q_RES_0402LF-0,5%,1/16W,CHIP,CA
     1 FM_BMC_UARTSW_LSB_N @SCM_LIB.SCM(SCH_1):FM_BMC_UARTSW_LSB_N    I47 @SCM_LIB.SCM(SCH_1):PAGE36
     2 FM_UARTSW_LSB_N @SCM_LIB.SCM(SCH_1):FM_UARTSW_LSB_N    I47 @SCM_LIB.SCM(SCH_1):PAGE36

R135 Q_RES_0402LF-0,5%,1/16W,CHIP,CA
     1 SMB_BMC_MM15_SCL @SCM_LIB.SCM(SCH_1):SMB_BMC_MM15_SCL   I109 @SCM_LIB.SCM(SCH_1):PAGE28
     2 SMB_BMC_MM15_R1_SCL @SCM_LIB.SCM(SCH_1):SMB_BMC_MM15_R1_SCL   I109 @SCM_LIB.SCM(SCH_1):PAGE28

R136 Q_RES_0402LF-10K,1%,1/16W,CHIPA
     1 P3V3_AUX @SCM_LIB.SCM(SCH_1):P3V3_AUX   I132 @SCM_LIB.SCM(SCH_1):PAGE46
     2 SMB_PCH_TPM_SCL @SCM_LIB.SCM(SCH_1):SMB_PCH_TPM_SCL   I132 @SCM_LIB.SCM(SCH_1):PAGE46

R137 Q_RES_0402LF-33.2,1%,1/16W,CHIA
     1 SMB_BMC_MM12_R_SCL @SCM_LIB.SCM(SCH_1):SMB_BMC_MM12_R_SCL   I385 @SCM_LIB.SCM(SCH_1):PAGE12
     2 SMB_BMC_MM12_SCL @SCM_LIB.SCM(SCH_1):SMB_BMC_MM12_SCL   I385 @SCM_LIB.SCM(SCH_1):PAGE12

R138 Q_RES_0402LF-40.2,1%,1/16W,CHIA
     1 SMB_BMC_MM4_R_SCL @SCM_LIB.SCM(SCH_1):SMB_BMC_MM4_R_SCL   I513 @SCM_LIB.SCM(SCH_1):PAGE12
     2 SMB_BMC_MM4_SCL @SCM_LIB.SCM(SCH_1):SMB_BMC_MM4_SCL   I513 @SCM_LIB.SCM(SCH_1):PAGE12

R139 Q_RES_0402LF-33.2,1%,1/16W,CHIA
     1 SMB_BMC_MM4_R_SDA @SCM_LIB.SCM(SCH_1):SMB_BMC_MM4_R_SDA   I512 @SCM_LIB.SCM(SCH_1):PAGE12
     2 SMB_BMC_MM4_SDA @SCM_LIB.SCM(SCH_1):SMB_BMC_MM4_SDA   I512 @SCM_LIB.SCM(SCH_1):PAGE12

R140 Q_RES_0402LF-4.7K,1%,1/16W,EMPA
     1 P3V3_AUX @SCM_LIB.SCM(SCH_1):P3V3_AUX   I228 @SCM_LIB.SCM(SCH_1):PAGE27
     2 SPI_BMC_BOOT_MOSI @SCM_LIB.SCM(SCH_1):SPI_BMC_BOOT_MOSI   I228 @SCM_LIB.SCM(SCH_1):PAGE27

R142 Q_RES_0402LF-33.2,1%,1/16W,CHIA
     1 SMB_BMC_MM6_R_SCL @SCM_LIB.SCM(SCH_1):SMB_BMC_MM6_R_SCL    I88 @SCM_LIB.SCM(SCH_1):PAGE12
     2 SMB_BMC_MM6_SCL @SCM_LIB.SCM(SCH_1):SMB_BMC_MM6_SCL    I88 @SCM_LIB.SCM(SCH_1):PAGE12

R143 Q_RES_0402LF-33.2,1%,1/16W,CHIA
     1 SMB_BMC_MM6_R_SDA @SCM_LIB.SCM(SCH_1):SMB_BMC_MM6_R_SDA    I89 @SCM_LIB.SCM(SCH_1):PAGE12
     2 SMB_BMC_MM6_SDA @SCM_LIB.SCM(SCH_1):SMB_BMC_MM6_SDA    I89 @SCM_LIB.SCM(SCH_1):PAGE12

R144 Q_RES_0402LF-33.2,1%,1/16W,CHIA
     1 SMB_BMC_MM12_R_SDA @SCM_LIB.SCM(SCH_1):SMB_BMC_MM12_R_SDA   I386 @SCM_LIB.SCM(SCH_1):PAGE12
     2 SMB_BMC_MM12_SDA @SCM_LIB.SCM(SCH_1):SMB_BMC_MM12_SDA   I386 @SCM_LIB.SCM(SCH_1):PAGE12

R145 Q_RES_0402LF-10K,1%,1/16W,CHIPA
     1 P3V3_AUX @SCM_LIB.SCM(SCH_1):P3V3_AUX   I235 @SCM_LIB.SCM(SCH_1):PAGE27
     2 SMB_BMC_MM12_SCL @SCM_LIB.SCM(SCH_1):SMB_BMC_MM12_SCL   I235 @SCM_LIB.SCM(SCH_1):PAGE27

R146 Q_RES_0402LF-33.2,1%,1/16W,CHIA
     1 SMB_BMC_MM8_R_SCL @SCM_LIB.SCM(SCH_1):SMB_BMC_MM8_R_SCL   I235 @SCM_LIB.SCM(SCH_1):PAGE12
     2 SMB_BMC_MM8_SCL @SCM_LIB.SCM(SCH_1):SMB_BMC_MM8_SCL   I235 @SCM_LIB.SCM(SCH_1):PAGE12

R147 Q_RES_0402LF-33.2,1%,1/16W,CHIA
     1 SMB_BMC_MM8_R_SDA @SCM_LIB.SCM(SCH_1):SMB_BMC_MM8_R_SDA   I236 @SCM_LIB.SCM(SCH_1):PAGE12
     2 SMB_BMC_MM8_SDA @SCM_LIB.SCM(SCH_1):SMB_BMC_MM8_SDA   I236 @SCM_LIB.SCM(SCH_1):PAGE12

R148 Q_RES_0402LF-33.2,1%,1/16W,CHIA
     1 SGPIO_CLK_1 @SCM_LIB.SCM(SCH_1):SGPIO_CLK_1   I379 @SCM_LIB.SCM(SCH_1):PAGE12
     2 SGPIO_BMC_M1_CLK @SCM_LIB.SCM(SCH_1):SGPIO_BMC_M1_CLK   I379 @SCM_LIB.SCM(SCH_1):PAGE12

R149 Q_RES_0402LF-10K,1%,1/16W,CHIPA
     1 P3V3_AUX @SCM_LIB.SCM(SCH_1):P3V3_AUX   I236 @SCM_LIB.SCM(SCH_1):PAGE27
     2 SMB_BMC_MM12_SDA @SCM_LIB.SCM(SCH_1):SMB_BMC_MM12_SDA   I236 @SCM_LIB.SCM(SCH_1):PAGE27

R150 Q_RES_0402LF-33.2,1%,1/16W,CHIA
     1 SGPIO_LD_1 @SCM_LIB.SCM(SCH_1):SGPIO_LD_1   I380 @SCM_LIB.SCM(SCH_1):PAGE12
     2 SGPIO_BMC_M1_LD @SCM_LIB.SCM(SCH_1):SGPIO_BMC_M1_LD   I380 @SCM_LIB.SCM(SCH_1):PAGE12

R151 Q_RES_0402LF-33.2,1%,1/16W,CHIA
     1 SGPIO_DO_1 @SCM_LIB.SCM(SCH_1):SGPIO_DO_1   I381 @SCM_LIB.SCM(SCH_1):PAGE12
     2 SGPIO_BMC_M1_DO @SCM_LIB.SCM(SCH_1):SGPIO_BMC_M1_DO   I381 @SCM_LIB.SCM(SCH_1):PAGE12

R152 Q_RES_0402LF-33.2,1%,1/16W,CHIA
     1 SMB_BMC_MM16_SCL @SCM_LIB.SCM(SCH_1):SMB_BMC_MM16_SCL   I249 @SCM_LIB.SCM(SCH_1):PAGE12
     2 SMB_BMC_MM16_R_SCL @SCM_LIB.SCM(SCH_1):SMB_BMC_MM16_R_SCL   I249 @SCM_LIB.SCM(SCH_1):PAGE12

R153 Q_RES_0402LF-33.2,1%,1/16W,CHIA
     1 SMB_BMC_MM16_SDA @SCM_LIB.SCM(SCH_1):SMB_BMC_MM16_SDA   I248 @SCM_LIB.SCM(SCH_1):PAGE12
     2 SMB_BMC_MM16_R_SDA @SCM_LIB.SCM(SCH_1):SMB_BMC_MM16_R_SDA   I248 @SCM_LIB.SCM(SCH_1):PAGE12

R154 Q_RES_0402LF-0,5%,1/16W,EMPTY,A
     1 P1V8_AUX @SCM_LIB.SCM(SCH_1):P1V8_AUX     I3 @SCM_LIB.SCM(SCH_1):PAGE13
     2 P3V3_P2V5_P1V8_RVDD @SCM_LIB.SCM(SCH_1):P3V3_P2V5_P1V8_RVDD     I3 @SCM_LIB.SCM(SCH_1):PAGE13

R155 Q_RES_0402LF-0,5%,1/16W,CHIP,CA
     1 P3V3_AUX @SCM_LIB.SCM(SCH_1):P3V3_AUX     I5 @SCM_LIB.SCM(SCH_1):PAGE13
     2 P3V3_P2V5_P1V8_RVDD @SCM_LIB.SCM(SCH_1):P3V3_P2V5_P1V8_RVDD     I5 @SCM_LIB.SCM(SCH_1):PAGE13

R156 Q_RES_0402LF-0,5%,1/16W,EMPTY,A
     1 P2V5_AUX @SCM_LIB.SCM(SCH_1):P2V5_AUX     I4 @SCM_LIB.SCM(SCH_1):PAGE13
     2 P3V3_P2V5_P1V8_RVDD @SCM_LIB.SCM(SCH_1):P3V3_P2V5_P1V8_RVDD     I4 @SCM_LIB.SCM(SCH_1):PAGE13

R157 Q_RES_0402LF-33.2,1%,1/16W,CHIA
     1 UART_BMC_1_TXD_R @SCM_LIB.SCM(SCH_1):UART_BMC_1_TXD_R    I18 @SCM_LIB.SCM(SCH_1):PAGE13
     2 UART_BMC_1_TXD @SCM_LIB.SCM(SCH_1):UART_BMC_1_TXD    I18 @SCM_LIB.SCM(SCH_1):PAGE13

R158 Q_RES_0402LF-33.2,1%,1/16W,CHIA
     1 FM_DBP_CPU_PREQ_GF_R_N @SCM_LIB.SCM(SCH_1):FM_DBP_CPU_PREQ_GF_R_N    I16 @SCM_LIB.SCM(SCH_1):PAGE13
     2 FM_DBP_CPU_PREQ_GF_N @SCM_LIB.SCM(SCH_1):FM_DBP_CPU_PREQ_GF_N    I16 @SCM_LIB.SCM(SCH_1):PAGE13

R159 Q_RES_0402LF-33.2,1%,1/16W,CHIA
     1 FM_JTAG_TCK_MUX_BMC_SEL @SCM_LIB.SCM(SCH_1):FM_JTAG_TCK_MUX_BMC_SEL    I17 @SCM_LIB.SCM(SCH_1):PAGE13
     2 FM_JTAG_TCK_MUX_BMC_SEL_R1 @SCM_LIB.SCM(SCH_1):FM_JTAG_TCK_MUX_BMC_SEL_R1    I17 @SCM_LIB.SCM(SCH_1):PAGE13

R160 Q_RES_0402LF-33.2,1%,1/16W,CHIA
     1 RST_RSMRST_N @SCM_LIB.SCM(SCH_1):RST_RSMRST_N   I159 @SCM_LIB.SCM(SCH_1):PAGE13
     2 RST_RSMRST_R_N @SCM_LIB.SCM(SCH_1):RST_RSMRST_R_N   I159 @SCM_LIB.SCM(SCH_1):PAGE13

R161 Q_RES_0402LF-4.7K,1%,1/16W,CHIA
     1 P3V3_AUX @SCM_LIB.SCM(SCH_1):P3V3_AUX   I218 @SCM_LIB.SCM(SCH_1):PAGE11
     2 RMII_CSRDV @SCM_LIB.SCM(SCH_1):RMII_CSRDV   I218 @SCM_LIB.SCM(SCH_1):PAGE11

R162 Q_RES_0402LF-33.2,1%,1/16W,CHIA
     1 SMB_BMC_MM15_SCL @SCM_LIB.SCM(SCH_1):SMB_BMC_MM15_SCL   I245 @SCM_LIB.SCM(SCH_1):PAGE12
     2 SMB_BMC_MM15_R_SCL @SCM_LIB.SCM(SCH_1):SMB_BMC_MM15_R_SCL   I245 @SCM_LIB.SCM(SCH_1):PAGE12

R163 Q_RES_0402LF-4.7K,1%,1/16W,CHIA
     1 P3V3_AUX @SCM_LIB.SCM(SCH_1):P3V3_AUX   I212 @SCM_LIB.SCM(SCH_1):PAGE11
     2 FM_CPU_MSMI_CATERR_LVT3_N @SCM_LIB.SCM(SCH_1):FM_CPU_MSMI_CATERR_LVT3_N   I212 @SCM_LIB.SCM(SCH_1):PAGE11

R164 Q_RES_0402LF-100,1%,1/16W,EMPTA
     1 SPI_BMC_BOOT_MISO @SCM_LIB.SCM(SCH_1):SPI_BMC_BOOT_MISO   I244 @SCM_LIB.SCM(SCH_1):PAGE27
     2    GND @SCM_LIB.SCM(SCH_1):GND   I244 @SCM_LIB.SCM(SCH_1):PAGE27

R165 Q_RES_0402LF-33.2,1%,1/16W,CHIA
     1 SMB_BMC_MM2_R_SCL @SCM_LIB.SCM(SCH_1):SMB_BMC_MM2_R_SCL   I315 @SCM_LIB.SCM(SCH_1):PAGE12
     2 SMB_BMC_MM2_SCL @SCM_LIB.SCM(SCH_1):SMB_BMC_MM2_SCL   I315 @SCM_LIB.SCM(SCH_1):PAGE12

R166 Q_RES_0402LF-33.2,1%,1/16W,CHIA
     1 IRQ_BMC_CPU_NMI_R @SCM_LIB.SCM(SCH_1):IRQ_BMC_CPU_NMI_R    I50 @SCM_LIB.SCM(SCH_1):PAGE13
     2 IRQ_BMC_CPU_NMI @SCM_LIB.SCM(SCH_1):IRQ_BMC_CPU_NMI    I50 @SCM_LIB.SCM(SCH_1):PAGE13

R167 Q_RES_0402LF-330,1%,1/16W,CHIPA
     1 P3V3_AUX @SCM_LIB.SCM(SCH_1):P3V3_AUX    I33 @SCM_LIB.SCM(SCH_1):PAGE13
     2 BMC_HEARTBEAT_R_N @SCM_LIB.SCM(SCH_1):BMC_HEARTBEAT_R_N    I33 @SCM_LIB.SCM(SCH_1):PAGE13

R168 Q_RES_0402LF-33.2,1%,1/16W,CHIA
     1 RST_PLTRST_N @SCM_LIB.SCM(SCH_1):RST_PLTRST_N   I268 @SCM_LIB.SCM(SCH_1):PAGE12
     2 RST_PLTRST_R_N @SCM_LIB.SCM(SCH_1):RST_PLTRST_R_N   I268 @SCM_LIB.SCM(SCH_1):PAGE12

R169 Q_RES_0402LF-4.7K,1%,1/16W,CHIA
     1 P3V3_AUX @SCM_LIB.SCM(SCH_1):P3V3_AUX   I256 @SCM_LIB.SCM(SCH_1):PAGE11
     2 RST_PCA9548_SENSOR_N @SCM_LIB.SCM(SCH_1):RST_PCA9548_SENSOR_N   I256 @SCM_LIB.SCM(SCH_1):PAGE11

R170 Q_RES_0402LF-33.2,1%,1/16W,CHIA
     1 UART_BMC_5_TXD @SCM_LIB.SCM(SCH_1):UART_BMC_5_TXD    I67 @SCM_LIB.SCM(SCH_1):PAGE13
     2 UART_BMC_5_TXD_R @SCM_LIB.SCM(SCH_1):UART_BMC_5_TXD_R    I67 @SCM_LIB.SCM(SCH_1):PAGE13

R171 Q_RES_0402LF-22,1%,1/16W,CHIP,A
     1 RMII_TXEN_R @SCM_LIB.SCM(SCH_1):RMII_TXEN_R   I451 @SCM_LIB.SCM(SCH_1):PAGE13
     2 RMII_TXEN @SCM_LIB.SCM(SCH_1):RMII_TXEN   I451 @SCM_LIB.SCM(SCH_1):PAGE13

R172 Q_RES_0402LF-22,1%,1/16W,CHIP,A
     1 RMII_TXD0_R @SCM_LIB.SCM(SCH_1):RMII_TXD0_R   I452 @SCM_LIB.SCM(SCH_1):PAGE13
     2 RMII_TXD0 @SCM_LIB.SCM(SCH_1):RMII_TXD0   I452 @SCM_LIB.SCM(SCH_1):PAGE13

R173 Q_RES_0402LF-22,1%,1/16W,CHIP,A
     1 RMII_TXD1_R @SCM_LIB.SCM(SCH_1):RMII_TXD1_R   I453 @SCM_LIB.SCM(SCH_1):PAGE13
     2 RMII_TXD1 @SCM_LIB.SCM(SCH_1):RMII_TXD1   I453 @SCM_LIB.SCM(SCH_1):PAGE13

R174 Q_RES_0402LF-33.2,1%,1/16W,CHIA
     1 SPI_BMC_BIOS_ROM_CLK @SCM_LIB.SCM(SCH_1):SPI_BMC_BIOS_ROM_CLK   I331 @SCM_LIB.SCM(SCH_1):PAGE44
     2 SPI_BMC_BIOS_ROM_R_CLK @SCM_LIB.SCM(SCH_1):SPI_BMC_BIOS_ROM_R_CLK   I331 @SCM_LIB.SCM(SCH_1):PAGE44

R175 Q_RES_0402LF-33.2,1%,1/16W,CHIA
     1 SPI_BMC_BIOS_ROM_MOSI @SCM_LIB.SCM(SCH_1):SPI_BMC_BIOS_ROM_MOSI   I330 @SCM_LIB.SCM(SCH_1):PAGE44
     2 SPI_BMC_BIOS_ROM_R_MOSI @SCM_LIB.SCM(SCH_1):SPI_BMC_BIOS_ROM_R_MOSI   I330 @SCM_LIB.SCM(SCH_1):PAGE44

R176 Q_RES_0402LF-33.2,1%,1/16W,CHIA
     1 SPI_BMC_BIOS_ROM_MISO @SCM_LIB.SCM(SCH_1):SPI_BMC_BIOS_ROM_MISO   I332 @SCM_LIB.SCM(SCH_1):PAGE44
     2 SPI_BMC_BIOS_ROM_R_MISO @SCM_LIB.SCM(SCH_1):SPI_BMC_BIOS_ROM_R_MISO   I332 @SCM_LIB.SCM(SCH_1):PAGE44

R177 Q_RES_0402LF-33.2,1%,1/16W,CHIA
     1 H_CPU1_PROCHOT_LVC1_N @SCM_LIB.SCM(SCH_1):H_CPU1_PROCHOT_LVC1_N    I87 @SCM_LIB.SCM(SCH_1):PAGE13
     2 H_CPU1_PROCHOT_LVC1_R_N @SCM_LIB.SCM(SCH_1):H_CPU1_PROCHOT_LVC1_R_N    I87 @SCM_LIB.SCM(SCH_1):PAGE13

R178 Q_RES_0402LF-33.2,1%,1/16W,CHIA
     1 SPI_BMC_CLK_R @SCM_LIB.SCM(SCH_1):SPI_BMC_CLK_R    I94 @SCM_LIB.SCM(SCH_1):PAGE13
     2 SPI_BMC_BOOT_CLK @SCM_LIB.SCM(SCH_1):SPI_BMC_BOOT_CLK    I94 @SCM_LIB.SCM(SCH_1):PAGE13

R179 Q_RES_0402LF-33.2,1%,1/16W,CHIA
     1 SPI_BMC_MOSI_IO0_R @SCM_LIB.SCM(SCH_1):SPI_BMC_MOSI_IO0_R    I95 @SCM_LIB.SCM(SCH_1):PAGE13
     2 SPI_BMC_BOOT_MOSI @SCM_LIB.SCM(SCH_1):SPI_BMC_BOOT_MOSI    I95 @SCM_LIB.SCM(SCH_1):PAGE13

R180 Q_RES_0402LF-33.2,1%,1/16W,CHIA
     1 SPI_BMC_MISO_IO1_R @SCM_LIB.SCM(SCH_1):SPI_BMC_MISO_IO1_R    I96 @SCM_LIB.SCM(SCH_1):PAGE13
     2 SPI_BMC_BOOT_MISO @SCM_LIB.SCM(SCH_1):SPI_BMC_BOOT_MISO    I96 @SCM_LIB.SCM(SCH_1):PAGE13

R181 Q_RES_0402LF-4.7K,1%,1/16W,CHIA
     1 P3V3_AUX @SCM_LIB.SCM(SCH_1):P3V3_AUX   I170 @SCM_LIB.SCM(SCH_1):PAGE25
     2 FM_FLASH_LATCH_N @SCM_LIB.SCM(SCH_1):FM_FLASH_LATCH_N   I170 @SCM_LIB.SCM(SCH_1):PAGE25

R182 Q_RES_0402LF-0,5%,1/16W,CHIP,CA
     1    GND @SCM_LIB.SCM(SCH_1):GND   I142 @SCM_LIB.SCM(SCH_1):PAGE25
     2 FLASH_LATCH_D @SCM_LIB.SCM(SCH_1):FLASH_LATCH_D   I142 @SCM_LIB.SCM(SCH_1):PAGE25

R183 Q_RES_0402LF-0,5%,1/16W,CHIP,CA
     1 P3V3_AUX @SCM_LIB.SCM(SCH_1):P3V3_AUX   I139 @SCM_LIB.SCM(SCH_1):PAGE34
     2 PVCCIO_AUX_PLD @SCM_LIB.SCM(SCH_1):PVCCIO_AUX_PLD   I139 @SCM_LIB.SCM(SCH_1):PAGE34

R184 Q_RES_0402LF-110,1%,1/16W,CHIPA
     1 I3C1_SPD_SCL @SCM_LIB.SCM(SCH_1):I3C1_SPD_SCL   I232 @SCM_LIB.SCM(SCH_1):PAGE14
     2 I3C1_SCL_R @SCM_LIB.SCM(SCH_1):I3C1_SCL_R   I232 @SCM_LIB.SCM(SCH_1):PAGE14

R185 Q_RES_0402LF-33.2,1%,1/16W,CHIA
     1 I3C1_SPD_SDA @SCM_LIB.SCM(SCH_1):I3C1_SPD_SDA   I236 @SCM_LIB.SCM(SCH_1):PAGE14
     2 I3C1_SDA_R @SCM_LIB.SCM(SCH_1):I3C1_SDA_R   I236 @SCM_LIB.SCM(SCH_1):PAGE14

R186 Q_RES_0402LF-110,1%,1/16W,CHIPA
     1 I3C2_SPD_SCL @SCM_LIB.SCM(SCH_1):I3C2_SPD_SCL   I233 @SCM_LIB.SCM(SCH_1):PAGE14
     2 I3C2_SCL_R @SCM_LIB.SCM(SCH_1):I3C2_SCL_R   I233 @SCM_LIB.SCM(SCH_1):PAGE14

R187 Q_RES_0402LF-33.2,1%,1/16W,CHIA
     1 I3C2_SPD_SDA @SCM_LIB.SCM(SCH_1):I3C2_SPD_SDA   I237 @SCM_LIB.SCM(SCH_1):PAGE14
     2 I3C2_SDA_R @SCM_LIB.SCM(SCH_1):I3C2_SDA_R   I237 @SCM_LIB.SCM(SCH_1):PAGE14

R188 Q_RES_0402LF-1K,1%,1/16W,CHIP,A
     1 P1V2_P1V0_I3C_VDDL1 @SCM_LIB.SCM(SCH_1):P1V2_P1V0_I3C_VDDL1   I183 @SCM_LIB.SCM(SCH_1):PAGE14
     2 I3C3_SPD_SCL @SCM_LIB.SCM(SCH_1):I3C3_SPD_SCL   I183 @SCM_LIB.SCM(SCH_1):PAGE14

R189 Q_RES_0402LF-1K,1%,1/16W,CHIP,A
     1 P1V2_P1V0_I3C_VDDL1 @SCM_LIB.SCM(SCH_1):P1V2_P1V0_I3C_VDDL1   I188 @SCM_LIB.SCM(SCH_1):PAGE14
     2 I3C3_SPD_SDA @SCM_LIB.SCM(SCH_1):I3C3_SPD_SDA   I188 @SCM_LIB.SCM(SCH_1):PAGE14

R190 Q_RES_0402LF-1K,1%,1/16W,CHIP,A
     1 P1V2_P1V0_I3C_VDDL1 @SCM_LIB.SCM(SCH_1):P1V2_P1V0_I3C_VDDL1   I173 @SCM_LIB.SCM(SCH_1):PAGE14
     2 I3C2_SPD_SCL @SCM_LIB.SCM(SCH_1):I3C2_SPD_SCL   I173 @SCM_LIB.SCM(SCH_1):PAGE14

R191 Q_RES_0402LF-1K,1%,1/16W,CHIP,A
     1 P1V2_P1V0_I3C_VDDL1 @SCM_LIB.SCM(SCH_1):P1V2_P1V0_I3C_VDDL1   I174 @SCM_LIB.SCM(SCH_1):PAGE14
     2 I3C2_SPD_SDA @SCM_LIB.SCM(SCH_1):I3C2_SPD_SDA   I174 @SCM_LIB.SCM(SCH_1):PAGE14

R192 Q_RES_0402LF-49.9,1%,1/16W,CHIA
     1 PWRGD_P1V0_AUX_DELAY_BUF @SCM_LIB.SCM(SCH_1):PWRGD_P1V0_AUX_DELAY_BUF    I41 @SCM_LIB.SCM(SCH_1):PAGE22
     2 RST_BMC_SRST_BUF_R_N @SCM_LIB.SCM(SCH_1):RST_BMC_SRST_BUF_R_N    I41 @SCM_LIB.SCM(SCH_1):PAGE22

R193 Q_RES_0402LF-100K,1%,1/16W,CHIA
     1 P3V3_AUX @SCM_LIB.SCM(SCH_1):P3V3_AUX   I166 @SCM_LIB.SCM(SCH_1):PAGE29
     2 SPA_SIN_SW_DBG @SCM_LIB.SCM(SCH_1):SPA_SIN_SW_DBG   I166 @SCM_LIB.SCM(SCH_1):PAGE29

R194 Q_RES_0402LF-1K,1%,1/16W,CHIP,A
     1 P1V2_P1V0_I3C_VDDL1 @SCM_LIB.SCM(SCH_1):P1V2_P1V0_I3C_VDDL1   I171 @SCM_LIB.SCM(SCH_1):PAGE14
     2 I3C1_SPD_SCL @SCM_LIB.SCM(SCH_1):I3C1_SPD_SCL   I171 @SCM_LIB.SCM(SCH_1):PAGE14

R195 Q_RES_0402LF-1K,1%,1/16W,CHIP,A
     1 P1V2_P1V0_I3C_VDDL1 @SCM_LIB.SCM(SCH_1):P1V2_P1V0_I3C_VDDL1   I172 @SCM_LIB.SCM(SCH_1):PAGE14
     2 I3C1_SPD_SDA @SCM_LIB.SCM(SCH_1):I3C1_SPD_SDA   I172 @SCM_LIB.SCM(SCH_1):PAGE14

R196 Q_RES_0402LF-1K,1%,1/16W,CHIP,A
     1 P1V2_P1V0_I3C_VDDL1 @SCM_LIB.SCM(SCH_1):P1V2_P1V0_I3C_VDDL1   I189 @SCM_LIB.SCM(SCH_1):PAGE14
     2 I3C4_SPD_SCL @SCM_LIB.SCM(SCH_1):I3C4_SPD_SCL   I189 @SCM_LIB.SCM(SCH_1):PAGE14

R197 Q_RES_0402LF-1K,1%,1/16W,CHIP,A
     1 P1V2_P1V0_I3C_VDDL1 @SCM_LIB.SCM(SCH_1):P1V2_P1V0_I3C_VDDL1   I190 @SCM_LIB.SCM(SCH_1):PAGE14
     2 I3C4_SPD_SDA @SCM_LIB.SCM(SCH_1):I3C4_SPD_SDA   I190 @SCM_LIB.SCM(SCH_1):PAGE14

R198 Q_RES_0402LF-110,1%,1/16W,CHIPA
     1 I3C3_SCL_R @SCM_LIB.SCM(SCH_1):I3C3_SCL_R   I234 @SCM_LIB.SCM(SCH_1):PAGE14
     2 I3C3_SPD_SCL @SCM_LIB.SCM(SCH_1):I3C3_SPD_SCL   I234 @SCM_LIB.SCM(SCH_1):PAGE14

R199 Q_RES_0402LF-33.2,1%,1/16W,CHIA
     1 I3C3_SDA_R @SCM_LIB.SCM(SCH_1):I3C3_SDA_R   I238 @SCM_LIB.SCM(SCH_1):PAGE14
     2 I3C3_SPD_SDA @SCM_LIB.SCM(SCH_1):I3C3_SPD_SDA   I238 @SCM_LIB.SCM(SCH_1):PAGE14

R200 Q_RES_0402LF-110,1%,1/16W,CHIPA
     1 I3C4_SCL_R @SCM_LIB.SCM(SCH_1):I3C4_SCL_R   I235 @SCM_LIB.SCM(SCH_1):PAGE14
     2 I3C4_SPD_SCL @SCM_LIB.SCM(SCH_1):I3C4_SPD_SCL   I235 @SCM_LIB.SCM(SCH_1):PAGE14

R201 Q_RES_0402LF-33.2,1%,1/16W,CHIA
     1 I3C4_SDA_R @SCM_LIB.SCM(SCH_1):I3C4_SDA_R   I239 @SCM_LIB.SCM(SCH_1):PAGE14
     2 I3C4_SPD_SDA @SCM_LIB.SCM(SCH_1):I3C4_SPD_SDA   I239 @SCM_LIB.SCM(SCH_1):PAGE14

R202 Q_RES_0402LF-10K,1%,1/16W,EMPTA
     1    GND @SCM_LIB.SCM(SCH_1):GND   I140 @SCM_LIB.SCM(SCH_1):PAGE32
     2 JTAG_SCM_TCK @SCM_LIB.SCM(SCH_1):JTAG_SCM_TCK   I140 @SCM_LIB.SCM(SCH_1):PAGE32

R203 Q_RES_0402LF-10K,1%,1/16W,CHIPA
     1 P3V3_RGM @SCM_LIB.SCM(SCH_1):P3V3_RGM   I117 @SCM_LIB.SCM(SCH_1):PAGE32
     2 JTAG_SCM_TMS @SCM_LIB.SCM(SCH_1):JTAG_SCM_TMS   I117 @SCM_LIB.SCM(SCH_1):PAGE32

R204 Q_RES_0402LF-10K,1%,1/16W,CHIPA
     1 P3V3_RGM @SCM_LIB.SCM(SCH_1):P3V3_RGM   I120 @SCM_LIB.SCM(SCH_1):PAGE32
     2 JTAG_SCM_TDI @SCM_LIB.SCM(SCH_1):JTAG_SCM_TDI   I120 @SCM_LIB.SCM(SCH_1):PAGE32

R205 Q_RES_0402LF-20K,1%,1/16W,CHIPA
     1 DEBUG_PORT_PRSNT_R @SCM_LIB.SCM(SCH_1):DEBUG_PORT_PRSNT_R   I184 @SCM_LIB.SCM(SCH_1):PAGE29
     2    GND @SCM_LIB.SCM(SCH_1):GND   I184 @SCM_LIB.SCM(SCH_1):PAGE29

R206 Q_RES_0402LF-10K,1%,1/16W,CHIPA
     1    GND @SCM_LIB.SCM(SCH_1):GND   I143 @SCM_LIB.SCM(SCH_1):PAGE32
     2 JTAG_SCM_NTRST @SCM_LIB.SCM(SCH_1):JTAG_SCM_NTRST   I143 @SCM_LIB.SCM(SCH_1):PAGE32

R207 Q_RES_0402LF-0,5%,1/16W,CHIP,CA
     1 P3V3_AUX @SCM_LIB.SCM(SCH_1):P3V3_AUX     I4 @SCM_LIB.SCM(SCH_1):PAGE15
     2 P3V3_P1V8_SD1VDD @SCM_LIB.SCM(SCH_1):P3V3_P1V8_SD1VDD     I4 @SCM_LIB.SCM(SCH_1):PAGE15

R208 Q_RES_0402LF-0,5%,1/16W,EMPTY,A
     1 P1V8_AUX @SCM_LIB.SCM(SCH_1):P1V8_AUX     I2 @SCM_LIB.SCM(SCH_1):PAGE15
     2 P3V3_P1V8_SD1VDD @SCM_LIB.SCM(SCH_1):P3V3_P1V8_SD1VDD     I2 @SCM_LIB.SCM(SCH_1):PAGE15

R209 Q_RES_0402LF-10K,1%,1/16W,EMPTA
     1 PECI_BMC @SCM_LIB.SCM(SCH_1):PECI_BMC    I19 @SCM_LIB.SCM(SCH_1):PAGE15
     2    GND @SCM_LIB.SCM(SCH_1):GND    I19 @SCM_LIB.SCM(SCH_1):PAGE15

R210 Q_RES_0402LF-1K,1%,1/16W,CHIP,A
     1    GND @SCM_LIB.SCM(SCH_1):GND    I47 @SCM_LIB.SCM(SCH_1):PAGE15
     2 PD_SP_ENTEST @SCM_LIB.SCM(SCH_1):PD_SP_ENTEST    I47 @SCM_LIB.SCM(SCH_1):PAGE15

R211 Q_RES_0402LF-10K,1%,1/16W,CHIPA
     1 P3V3_RGM @SCM_LIB.SCM(SCH_1):P3V3_RGM    I51 @SCM_LIB.SCM(SCH_1):PAGE15
     2 FM_BMC_SSPRST_N @SCM_LIB.SCM(SCH_1):FM_BMC_SSPRST_N    I51 @SCM_LIB.SCM(SCH_1):PAGE15

R212 Q_RES_0402LF-4.7K,1%,1/16W,CHIA
     1 P3V3_RGM @SCM_LIB.SCM(SCH_1):P3V3_RGM    I21 @SCM_LIB.SCM(SCH_1):PAGE15
     2 PU_25M_BMC_CLK_EN @SCM_LIB.SCM(SCH_1):PU_25M_BMC_CLK_EN    I21 @SCM_LIB.SCM(SCH_1):PAGE15

R213 Q_RES_0402LF-0,5%,1/16W,CHIP,CA
     1 P3V3_AUX @SCM_LIB.SCM(SCH_1):P3V3_AUX    I34 @SCM_LIB.SCM(SCH_1):PAGE15
     2 P3V3_P1V8_SD2VDD @SCM_LIB.SCM(SCH_1):P3V3_P1V8_SD2VDD    I34 @SCM_LIB.SCM(SCH_1):PAGE15

R214 Q_RES_0402LF-0,5%,1/16W,EMPTY,A
     1 P1V8_AUX @SCM_LIB.SCM(SCH_1):P1V8_AUX    I32 @SCM_LIB.SCM(SCH_1):PAGE15
     2 P3V3_P1V8_SD2VDD @SCM_LIB.SCM(SCH_1):P3V3_P1V8_SD2VDD    I32 @SCM_LIB.SCM(SCH_1):PAGE15

R215 Q_RES_0402LF-33.2,1%,1/16W,CHIA
     1 BMC_CLK_25M_R @SCM_LIB.SCM(SCH_1):BMC_CLK_25M_R    I42 @SCM_LIB.SCM(SCH_1):PAGE15
     2 BMC_CLK_25M @SCM_LIB.SCM(SCH_1):BMC_CLK_25M    I42 @SCM_LIB.SCM(SCH_1):PAGE15

R216 Q_RES_0402LF-49.9,1%,1/16W,CHIA
     1 PECI_BMC_R @SCM_LIB.SCM(SCH_1):PECI_BMC_R   I389 @SCM_LIB.SCM(SCH_1):PAGE15
     2 PECI_BMC @SCM_LIB.SCM(SCH_1):PECI_BMC   I389 @SCM_LIB.SCM(SCH_1):PAGE15

R217 Q_RES_0402LF-0,5%,1/16W,CHIP,CA
     1 USB_HOST_BMC_A_R_DP @SCM_LIB.SCM(SCH_1):USB_HOST_BMC_A_R_DP    I92 @SCM_LIB.SCM(SCH_1):PAGE15
     2 USB_HOST_BMC_A_DP @SCM_LIB.SCM(SCH_1):USB_HOST_BMC_A_DP    I92 @SCM_LIB.SCM(SCH_1):PAGE15

R218 Q_RES_0402LF-0,5%,1/16W,CHIP,CA
     1 USB_HOST_BMC_A_R_DN @SCM_LIB.SCM(SCH_1):USB_HOST_BMC_A_R_DN    I93 @SCM_LIB.SCM(SCH_1):PAGE15
     2 USB_HOST_BMC_A_DN @SCM_LIB.SCM(SCH_1):USB_HOST_BMC_A_DN    I93 @SCM_LIB.SCM(SCH_1):PAGE15

R219 Q_RES_0402LF-100K,1%,1/16W,EMPA
     1 DEBUG_PORT_UART_TX @SCM_LIB.SCM(SCH_1):DEBUG_PORT_UART_TX   I170 @SCM_LIB.SCM(SCH_1):PAGE29
     2    GND @SCM_LIB.SCM(SCH_1):GND   I170 @SCM_LIB.SCM(SCH_1):PAGE29

R220 Q_RES_0402LF-0,5%,1/16W,CHIP,CA
     1 FM_BMC_UARTSW_MSB_N @SCM_LIB.SCM(SCH_1):FM_BMC_UARTSW_MSB_N    I46 @SCM_LIB.SCM(SCH_1):PAGE36
     2 FM_UARTSW_MSB_N @SCM_LIB.SCM(SCH_1):FM_UARTSW_MSB_N    I46 @SCM_LIB.SCM(SCH_1):PAGE36

R221 Q_RES_0402LF-33.2,1%,1/16W,CHIA
     1 JTAG_1_BMC_TRST_R @SCM_LIB.SCM(SCH_1):JTAG_1_BMC_TRST_R    I81 @SCM_LIB.SCM(SCH_1):PAGE32
     2 JTAG_MB_TRST_N @SCM_LIB.SCM(SCH_1):JTAG_MB_TRST_N    I81 @SCM_LIB.SCM(SCH_1):PAGE32

R222 Q_RES_0402LF-33.2,1%,1/16W,CHIA
     1 JTAG_1_BMC_TCK_R @SCM_LIB.SCM(SCH_1):JTAG_1_BMC_TCK_R    I80 @SCM_LIB.SCM(SCH_1):PAGE32
     2 JTAG_MB_TCK @SCM_LIB.SCM(SCH_1):JTAG_MB_TCK    I80 @SCM_LIB.SCM(SCH_1):PAGE32

R223 Q_RES_0402LF-33.2,1%,1/16W,CHIA
     1 JTAG_1_BMC_TMS_R @SCM_LIB.SCM(SCH_1):JTAG_1_BMC_TMS_R    I78 @SCM_LIB.SCM(SCH_1):PAGE32
     2 JTAG_MB_TMS @SCM_LIB.SCM(SCH_1):JTAG_MB_TMS    I78 @SCM_LIB.SCM(SCH_1):PAGE32

R224 Q_RES_0402LF-33.2,1%,1/16W,CHIA
     1 JTAG_1_BMC_TDO_R @SCM_LIB.SCM(SCH_1):JTAG_1_BMC_TDO_R    I87 @SCM_LIB.SCM(SCH_1):PAGE32
     2 JTAG_MB_TDO @SCM_LIB.SCM(SCH_1):JTAG_MB_TDO    I87 @SCM_LIB.SCM(SCH_1):PAGE32

R225 Q_RES_0402LF-100,1%,1/16W,CHIPA
     1 FM_PWR_BTN @SCM_LIB.SCM(SCH_1):FM_PWR_BTN   I405 @SCM_LIB.SCM(SCH_1):PAGE15
     2 PWR_BTN_BMC_N @SCM_LIB.SCM(SCH_1):PWR_BTN_BMC_N   I405 @SCM_LIB.SCM(SCH_1):PAGE15

R226 Q_RES_0402LF-10K,1%,1/16W,CHIPA
     1 P3V3_AUX @SCM_LIB.SCM(SCH_1):P3V3_AUX   I103 @SCM_LIB.SCM(SCH_1):PAGE32
     2 JTAG_MB_TDI @SCM_LIB.SCM(SCH_1):JTAG_MB_TDI   I103 @SCM_LIB.SCM(SCH_1):PAGE32

R227 Q_RES_0402LF-10K,1%,1/16W,CHIPA
     1 P3V3_AUX @SCM_LIB.SCM(SCH_1):P3V3_AUX   I104 @SCM_LIB.SCM(SCH_1):PAGE32
     2 JTAG_MB_TMS @SCM_LIB.SCM(SCH_1):JTAG_MB_TMS   I104 @SCM_LIB.SCM(SCH_1):PAGE32

R228 Q_RES_0402LF-10K,1%,1/16W,EMPTA
     1    GND @SCM_LIB.SCM(SCH_1):GND   I107 @SCM_LIB.SCM(SCH_1):PAGE32
     2 JTAG_MB_TCK @SCM_LIB.SCM(SCH_1):JTAG_MB_TCK   I107 @SCM_LIB.SCM(SCH_1):PAGE32

R229 Q_RES_0402LF-4.7K,1%,1/16W,EMPA
     1    GND @SCM_LIB.SCM(SCH_1):GND   I106 @SCM_LIB.SCM(SCH_1):PAGE32
     2 JTAG_MB_TRST_N @SCM_LIB.SCM(SCH_1):JTAG_MB_TRST_N   I106 @SCM_LIB.SCM(SCH_1):PAGE32

R230 Q_RES_0402LF-10K,1%,1/16W,CHIPA
     1 P3V3_AUX @SCM_LIB.SCM(SCH_1):P3V3_AUX   I105 @SCM_LIB.SCM(SCH_1):PAGE32
     2 JTAG_MB_TDO @SCM_LIB.SCM(SCH_1):JTAG_MB_TDO   I105 @SCM_LIB.SCM(SCH_1):PAGE32

R231 Q_RES_0402LF-0,5%,1/16W,CHIP,CA
     1 P3V3_AUX @SCM_LIB.SCM(SCH_1):P3V3_AUX   I131 @SCM_LIB.SCM(SCH_1):PAGE17
     2 P3V3_P1V8_I2C_I3C @SCM_LIB.SCM(SCH_1):P3V3_P1V8_I2C_I3C   I131 @SCM_LIB.SCM(SCH_1):PAGE17

R232 Q_RES_0402LF-0,5%,1/16W,EMPTY,A
     1 P1V8_AUX @SCM_LIB.SCM(SCH_1):P1V8_AUX   I136 @SCM_LIB.SCM(SCH_1):PAGE17
     2 P3V3_P1V8_I2C_I3C @SCM_LIB.SCM(SCH_1):P3V3_P1V8_I2C_I3C   I136 @SCM_LIB.SCM(SCH_1):PAGE17

R233 Q_RES_0402LF-49.9K,1%,1/16W,CHA
     1    GND @SCM_LIB.SCM(SCH_1):GND    I87 @SCM_LIB.SCM(SCH_1):PAGE16
     2 A_BMC_ADCREXT0 @SCM_LIB.SCM(SCH_1):A_BMC_ADCREXT0    I87 @SCM_LIB.SCM(SCH_1):PAGE16

R234 Q_RES_0402LF-49.9K,1%,1/16W,CHA
     1    GND @SCM_LIB.SCM(SCH_1):GND    I86 @SCM_LIB.SCM(SCH_1):PAGE16
     2 A_BMC_ADCREXT1 @SCM_LIB.SCM(SCH_1):A_BMC_ADCREXT1    I86 @SCM_LIB.SCM(SCH_1):PAGE16

R235 Q_RES_0402LF-2.74K,1%,1/16W,CHA
     1    GND @SCM_LIB.SCM(SCH_1):GND   I187 @SCM_LIB.SCM(SCH_1):PAGE16
     2 A_BMC_DACREST @SCM_LIB.SCM(SCH_1):A_BMC_DACREST   I187 @SCM_LIB.SCM(SCH_1):PAGE16

R236 Q_RES_0402LF-33.2,1%,1/16W,CHIA
     1 SMB_BMC_MM15_SDA @SCM_LIB.SCM(SCH_1):SMB_BMC_MM15_SDA   I244 @SCM_LIB.SCM(SCH_1):PAGE12
     2 SMB_BMC_MM15_R_SDA @SCM_LIB.SCM(SCH_1):SMB_BMC_MM15_R_SDA   I244 @SCM_LIB.SCM(SCH_1):PAGE12

R237 Q_RES_0402LF-33.2,1%,1/16W,CHIA
     1 FM_DBP_BMC_PRDY_N @SCM_LIB.SCM(SCH_1):FM_DBP_BMC_PRDY_N   I156 @SCM_LIB.SCM(SCH_1):PAGE13
     2 FM_DBP_BMC_PRDY_R_N @SCM_LIB.SCM(SCH_1):FM_DBP_BMC_PRDY_R_N   I156 @SCM_LIB.SCM(SCH_1):PAGE13

R238 Q_RES_0402LF-4.7K,1%,1/16W,CHIA
     1 P3V3_AUX @SCM_LIB.SCM(SCH_1):P3V3_AUX   I184 @SCM_LIB.SCM(SCH_1):PAGE13
     2 SPI_BMC_TPM_CS2_R_N @SCM_LIB.SCM(SCH_1):SPI_BMC_TPM_CS2_R_N   I184 @SCM_LIB.SCM(SCH_1):PAGE13

R239 Q_RES_0402LF-4.7K,1%,1/16W,CHIA
     1 P3V3_AUX @SCM_LIB.SCM(SCH_1):P3V3_AUX   I185 @SCM_LIB.SCM(SCH_1):PAGE13
     2 PU_BMC_FWSPIABR_N @SCM_LIB.SCM(SCH_1):PU_BMC_FWSPIABR_N   I185 @SCM_LIB.SCM(SCH_1):PAGE13

R240 Q_RES_0402LF-4.7K,1%,1/16W,CHIA
     1 P3V3_AUX @SCM_LIB.SCM(SCH_1):P3V3_AUX   I187 @SCM_LIB.SCM(SCH_1):PAGE13
     2 PU_FWSPIWP_N @SCM_LIB.SCM(SCH_1):PU_FWSPIWP_N   I187 @SCM_LIB.SCM(SCH_1):PAGE13

R241 Q_RES_0402LF-4.7K,1%,1/16W,CHIA
     1 P3V3_AUX @SCM_LIB.SCM(SCH_1):P3V3_AUX   I186 @SCM_LIB.SCM(SCH_1):PAGE13
     2 PU_SPI1ABR @SCM_LIB.SCM(SCH_1):PU_SPI1ABR   I186 @SCM_LIB.SCM(SCH_1):PAGE13

R242 Q_RES_0402LF-33.2,1%,1/16W,CHIA
     1 FM_BMC_CPU_FBRK_OUT_N @SCM_LIB.SCM(SCH_1):FM_BMC_CPU_FBRK_OUT_N   I384 @SCM_LIB.SCM(SCH_1):PAGE13
     2 FM_BMC_CPU_FBRK_OUT_R_N @SCM_LIB.SCM(SCH_1):FM_BMC_CPU_FBRK_OUT_R_N   I384 @SCM_LIB.SCM(SCH_1):PAGE13

R243 Q_RES_0402LF-33.2,1%,1/16W,CHIA
     1 PWRGD_PSU_AC_PWROK @SCM_LIB.SCM(SCH_1):PWRGD_PSU_AC_PWROK   I293 @SCM_LIB.SCM(SCH_1):PAGE10
     2 PWRGD_PSU_AC_PWROK_R @SCM_LIB.SCM(SCH_1):PWRGD_PSU_AC_PWROK_R   I293 @SCM_LIB.SCM(SCH_1):PAGE10

R244 Q_RES_0402LF-1.8K,1%,1/16W,CHIA
     1 P3V3_AUX @SCM_LIB.SCM(SCH_1):P3V3_AUX   I147 @SCM_LIB.SCM(SCH_1):PAGE27
     2 SMB_BMC_MM1_SCL @SCM_LIB.SCM(SCH_1):SMB_BMC_MM1_SCL   I147 @SCM_LIB.SCM(SCH_1):PAGE27

R245 Q_RES_0402LF-1.8K,1%,1/16W,CHIA
     1 P3V3_AUX @SCM_LIB.SCM(SCH_1):P3V3_AUX   I146 @SCM_LIB.SCM(SCH_1):PAGE27
     2 SMB_BMC_MM1_SDA @SCM_LIB.SCM(SCH_1):SMB_BMC_MM1_SDA   I146 @SCM_LIB.SCM(SCH_1):PAGE27

R246 Q_RES_0402LF-2.2K,5%,1/16W,CHIA
     1 P3V3_AUX @SCM_LIB.SCM(SCH_1):P3V3_AUX   I145 @SCM_LIB.SCM(SCH_1):PAGE27
     2 SMB_BMC_MM2_SCL @SCM_LIB.SCM(SCH_1):SMB_BMC_MM2_SCL   I145 @SCM_LIB.SCM(SCH_1):PAGE27

R247 Q_RES_0402LF-2.2K,5%,1/16W,CHIA
     1 P3V3_AUX @SCM_LIB.SCM(SCH_1):P3V3_AUX   I109 @SCM_LIB.SCM(SCH_1):PAGE27
     2 SMB_BMC_MM2_SDA @SCM_LIB.SCM(SCH_1):SMB_BMC_MM2_SDA   I109 @SCM_LIB.SCM(SCH_1):PAGE27

R248 Q_RES_0402LF-2.2K,5%,1/16W,CHIA
     1 P3V3_AUX @SCM_LIB.SCM(SCH_1):P3V3_AUX   I107 @SCM_LIB.SCM(SCH_1):PAGE27
     2 SMB_BMC_MM3_SCL @SCM_LIB.SCM(SCH_1):SMB_BMC_MM3_SCL   I107 @SCM_LIB.SCM(SCH_1):PAGE27

R249 Q_RES_0402LF-2.2K,5%,1/16W,CHIA
     1 P3V3_AUX @SCM_LIB.SCM(SCH_1):P3V3_AUX   I108 @SCM_LIB.SCM(SCH_1):PAGE27
     2 SMB_BMC_MM3_SDA @SCM_LIB.SCM(SCH_1):SMB_BMC_MM3_SDA   I108 @SCM_LIB.SCM(SCH_1):PAGE27

R250 Q_RES_0402LF-402,1%,1/16W,CHIPA
     1 P3V3_AUX @SCM_LIB.SCM(SCH_1):P3V3_AUX   I106 @SCM_LIB.SCM(SCH_1):PAGE27
     2 SMB_BMC_MM4_SCL @SCM_LIB.SCM(SCH_1):SMB_BMC_MM4_SCL   I106 @SCM_LIB.SCM(SCH_1):PAGE27

R251 Q_RES_0402LF-499,1%,1/16W,CHIPA
     1 P3V3_AUX @SCM_LIB.SCM(SCH_1):P3V3_AUX   I247 @SCM_LIB.SCM(SCH_1):PAGE27
     2 SMB_BMC_MM4_SDA @SCM_LIB.SCM(SCH_1):SMB_BMC_MM4_SDA   I247 @SCM_LIB.SCM(SCH_1):PAGE27

R252 Q_RES_0402LF-2.2K,5%,1/16W,CHIA
     1 P3V3_AUX @SCM_LIB.SCM(SCH_1):P3V3_AUX   I105 @SCM_LIB.SCM(SCH_1):PAGE27
     2 SMB_BMC_MM5_R_SCL @SCM_LIB.SCM(SCH_1):SMB_BMC_MM5_R_SCL   I105 @SCM_LIB.SCM(SCH_1):PAGE27

R253 Q_RES_0402LF-2.2K,5%,1/16W,CHIA
     1 P3V3_AUX @SCM_LIB.SCM(SCH_1):P3V3_AUX   I103 @SCM_LIB.SCM(SCH_1):PAGE27
     2 SMB_BMC_MM5_R_SDA @SCM_LIB.SCM(SCH_1):SMB_BMC_MM5_R_SDA   I103 @SCM_LIB.SCM(SCH_1):PAGE27

R254 Q_RES_0402LF-10K,1%,1/16W,CHIPA
     1 P3V3_AUX @SCM_LIB.SCM(SCH_1):P3V3_AUX   I101 @SCM_LIB.SCM(SCH_1):PAGE27
     2 SMB_BMC_MM6_SCL @SCM_LIB.SCM(SCH_1):SMB_BMC_MM6_SCL   I101 @SCM_LIB.SCM(SCH_1):PAGE27

R255 Q_RES_0402LF-10K,1%,1/16W,CHIPA
     1 P3V3_AUX @SCM_LIB.SCM(SCH_1):P3V3_AUX   I102 @SCM_LIB.SCM(SCH_1):PAGE27
     2 SMB_BMC_MM6_SDA @SCM_LIB.SCM(SCH_1):SMB_BMC_MM6_SDA   I102 @SCM_LIB.SCM(SCH_1):PAGE27

R256 Q_RES_0402LF-2.2K,5%,1/16W,CHIA
     1 P3V3_AUX @SCM_LIB.SCM(SCH_1):P3V3_AUX   I100 @SCM_LIB.SCM(SCH_1):PAGE27
     2 SMB_BMC_MM7_R_SCL @SCM_LIB.SCM(SCH_1):SMB_BMC_MM7_R_SCL   I100 @SCM_LIB.SCM(SCH_1):PAGE27

R257 Q_RES_0402LF-2.2K,5%,1/16W,CHIA
     1 P3V3_AUX @SCM_LIB.SCM(SCH_1):P3V3_AUX    I99 @SCM_LIB.SCM(SCH_1):PAGE27
     2 SMB_BMC_MM7_R_SDA @SCM_LIB.SCM(SCH_1):SMB_BMC_MM7_R_SDA    I99 @SCM_LIB.SCM(SCH_1):PAGE27

R258 Q_RES_0402LF-2.2K,5%,1/16W,CHIA
     1 P3V3_AUX @SCM_LIB.SCM(SCH_1):P3V3_AUX    I98 @SCM_LIB.SCM(SCH_1):PAGE27
     2 SMB_BMC_MM8_SCL @SCM_LIB.SCM(SCH_1):SMB_BMC_MM8_SCL    I98 @SCM_LIB.SCM(SCH_1):PAGE27

R259 Q_RES_0402LF-2.2K,5%,1/16W,CHIA
     1 P3V3_AUX @SCM_LIB.SCM(SCH_1):P3V3_AUX    I96 @SCM_LIB.SCM(SCH_1):PAGE27
     2 SMB_BMC_MM8_SDA @SCM_LIB.SCM(SCH_1):SMB_BMC_MM8_SDA    I96 @SCM_LIB.SCM(SCH_1):PAGE27

R260 Q_RES_0402LF-10K,1%,1/16W,CHIPA
     1 P3V3_AUX @SCM_LIB.SCM(SCH_1):P3V3_AUX    I97 @SCM_LIB.SCM(SCH_1):PAGE27
     2 SMB_BMC_MM9_SCL @SCM_LIB.SCM(SCH_1):SMB_BMC_MM9_SCL    I97 @SCM_LIB.SCM(SCH_1):PAGE27

R261 Q_RES_0402LF-10K,1%,1/16W,CHIPA
     1 P3V3_AUX @SCM_LIB.SCM(SCH_1):P3V3_AUX    I94 @SCM_LIB.SCM(SCH_1):PAGE27
     2 SMB_BMC_MM9_SDA @SCM_LIB.SCM(SCH_1):SMB_BMC_MM9_SDA    I94 @SCM_LIB.SCM(SCH_1):PAGE27

R262 Q_RES_0402LF-10K,1%,1/16W,CHIPA
     1 P3V3_AUX @SCM_LIB.SCM(SCH_1):P3V3_AUX    I93 @SCM_LIB.SCM(SCH_1):PAGE27
     2 SMB_BMC_MM10_SCL @SCM_LIB.SCM(SCH_1):SMB_BMC_MM10_SCL    I93 @SCM_LIB.SCM(SCH_1):PAGE27

R263 Q_RES_0402LF-33.2,1%,1/16W,CHIA
     1 RST_MB_STBY_N @SCM_LIB.SCM(SCH_1):RST_MB_STBY_N   I141 @SCM_LIB.SCM(SCH_1):PAGE35
     2 RST_MB_STBY_R_N @SCM_LIB.SCM(SCH_1):RST_MB_STBY_R_N   I141 @SCM_LIB.SCM(SCH_1):PAGE35

R264 Q_RES_0402LF-2.2K,5%,1/16W,CHIA
     1 P3V3_AUX @SCM_LIB.SCM(SCH_1):P3V3_AUX    I89 @SCM_LIB.SCM(SCH_1):PAGE27
     2 SMB_BMC_MM16_SCL @SCM_LIB.SCM(SCH_1):SMB_BMC_MM16_SCL    I89 @SCM_LIB.SCM(SCH_1):PAGE27

R265 Q_RES_0402LF-2.2K,5%,1/16W,CHIA
     1 P3V3_AUX @SCM_LIB.SCM(SCH_1):P3V3_AUX    I88 @SCM_LIB.SCM(SCH_1):PAGE27
     2 SMB_BMC_MM16_SDA @SCM_LIB.SCM(SCH_1):SMB_BMC_MM16_SDA    I88 @SCM_LIB.SCM(SCH_1):PAGE27

R266 Q_RES_0402LF-4.7K,1%,1/16W,EMPA
     1 P3V3_AUX @SCM_LIB.SCM(SCH_1):P3V3_AUX    I95 @SCM_LIB.SCM(SCH_1):PAGE27
     2 FM_ME_BT_DONE @SCM_LIB.SCM(SCH_1):FM_ME_BT_DONE    I95 @SCM_LIB.SCM(SCH_1):PAGE27

R267 Q_RES_0402LF-4.7K,1%,1/16W,EMPA
     1 P3V3_AUX @SCM_LIB.SCM(SCH_1):P3V3_AUX    I85 @SCM_LIB.SCM(SCH_1):PAGE27
     2 VOL_SEN_ALERT_R @SCM_LIB.SCM(SCH_1):VOL_SEN_ALERT_R    I85 @SCM_LIB.SCM(SCH_1):PAGE27

R268 Q_RES_0402LF-4.7K,1%,1/16W,CHIA
     1 P3V3_AUX @SCM_LIB.SCM(SCH_1):P3V3_AUX    I86 @SCM_LIB.SCM(SCH_1):PAGE27
     2 SMB_BMC_ALERT3_N @SCM_LIB.SCM(SCH_1):SMB_BMC_ALERT3_N    I86 @SCM_LIB.SCM(SCH_1):PAGE27

R269 Q_RES_0402LF-4.7K,1%,1/16W,CHIA
     1 P3V3_AUX @SCM_LIB.SCM(SCH_1):P3V3_AUX    I84 @SCM_LIB.SCM(SCH_1):PAGE27
     2 SMB_BMC_ALERT4_N @SCM_LIB.SCM(SCH_1):SMB_BMC_ALERT4_N    I84 @SCM_LIB.SCM(SCH_1):PAGE27

R270 Q_RES_0402LF-33.2,1%,1/16W,CHIA
     1 FM_CPU_MSMI_CATERR_LVT3_PLD_N @SCM_LIB.SCM(SCH_1):FM_CPU_MSMI_CATERR_LVT3_PLD_N   I164 @SCM_LIB.SCM(SCH_1):PAGE34
     2 FM_CPU_MSMI_CATERR_LVT3_N @SCM_LIB.SCM(SCH_1):FM_CPU_MSMI_CATERR_LVT3_N   I164 @SCM_LIB.SCM(SCH_1):PAGE34

R271 Q_RES_0402LF-0,5%,1/16W,CHIP,CA
     1 RST_BMC_SELF_HW @SCM_LIB.SCM(SCH_1):RST_BMC_SELF_HW    I88 @SCM_LIB.SCM(SCH_1):PAGE35
     2 RST_BMC_SELF_HW_R2 @SCM_LIB.SCM(SCH_1):RST_BMC_SELF_HW_R2    I88 @SCM_LIB.SCM(SCH_1):PAGE35

R272 Q_RES_0402LF-0,5%,1/16W,CHIP,CA
     1 SMB_BMC_MM16_R3_SCL @SCM_LIB.SCM(SCH_1):SMB_BMC_MM16_R3_SCL   I165 @SCM_LIB.SCM(SCH_1):PAGE34
     2 SMB_BMC_MM16_R5_SCL @SCM_LIB.SCM(SCH_1):SMB_BMC_MM16_R5_SCL   I165 @SCM_LIB.SCM(SCH_1):PAGE34

R273 Q_RES_0402LF-100K,1%,1/16W,CHIA
     1 PD_CLK_125M_PHY_BMC_RGMII @SCM_LIB.SCM(SCH_1):PD_CLK_125M_PHY_BMC_RGMII   I340 @SCM_LIB.SCM(SCH_1):PAGE13
     2    GND @SCM_LIB.SCM(SCH_1):GND   I340 @SCM_LIB.SCM(SCH_1):PAGE13

R274 Q_RES_0402LF-100K,1%,1/16W,EMPA
     1 P3V3_AUX @SCM_LIB.SCM(SCH_1):P3V3_AUX   I157 @SCM_LIB.SCM(SCH_1):PAGE29
     2 DEBUG_PORT_UART_RX @SCM_LIB.SCM(SCH_1):DEBUG_PORT_UART_RX   I157 @SCM_LIB.SCM(SCH_1):PAGE29

R275 Q_RES_0402LF-0,5%,1/16W,CHIP,CA
     1 PWRGD_P1V8_AUX @SCM_LIB.SCM(SCH_1):PWRGD_P1V8_AUX    I99 @SCM_LIB.SCM(SCH_1):PAGE54
     2 PWRGD_P1V8_AUX_R @SCM_LIB.SCM(SCH_1):PWRGD_P1V8_AUX_R    I99 @SCM_LIB.SCM(SCH_1):PAGE54

R276 Q_RES_0402LF-0,5%,1/16W,CHIP,CA
     1 PWRGD_P1V2_AUX_R @SCM_LIB.SCM(SCH_1):PWRGD_P1V2_AUX_R    I50 @SCM_LIB.SCM(SCH_1):PAGE55
     2 PWRGD_P1V2_AUX @SCM_LIB.SCM(SCH_1):PWRGD_P1V2_AUX    I50 @SCM_LIB.SCM(SCH_1):PAGE55

R277 Q_RES_0402LF-0,5%,1/16W,CHIP,CA
     1 PWRGD_P1V0_AUX_R @SCM_LIB.SCM(SCH_1):PWRGD_P1V0_AUX_R    I54 @SCM_LIB.SCM(SCH_1):PAGE56
     2 PWRGD_P1V0_AUX @SCM_LIB.SCM(SCH_1):PWRGD_P1V0_AUX    I54 @SCM_LIB.SCM(SCH_1):PAGE56

R278 Q_RES_0402LF-0,5%,1/16W,EMPTY,A
     1 P1V2_AUX @SCM_LIB.SCM(SCH_1):P1V2_AUX   I101 @SCM_LIB.SCM(SCH_1):PAGE17
     2 P1V2_P1V0_I3C_VDDL1 @SCM_LIB.SCM(SCH_1):P1V2_P1V0_I3C_VDDL1   I101 @SCM_LIB.SCM(SCH_1):PAGE17

R279 Q_RES_0402LF-0,5%,1/16W,CHIP,CA
     1 P1V0_AUX @SCM_LIB.SCM(SCH_1):P1V0_AUX    I95 @SCM_LIB.SCM(SCH_1):PAGE17
     2 P1V2_P1V0_I3C_VDDL1 @SCM_LIB.SCM(SCH_1):P1V2_P1V0_I3C_VDDL1    I95 @SCM_LIB.SCM(SCH_1):PAGE17

R280 Q_RES_0402LF-0,5%,1/16W,EMPTY,A
     1 P1V2_AUX @SCM_LIB.SCM(SCH_1):P1V2_AUX    I94 @SCM_LIB.SCM(SCH_1):PAGE17
     2 P1V2_P1V0_I3C_VDDL2 @SCM_LIB.SCM(SCH_1):P1V2_P1V0_I3C_VDDL2    I94 @SCM_LIB.SCM(SCH_1):PAGE17

R281 Q_RES_0402LF-0,5%,1/16W,CHIP,CA
     1 P1V0_AUX @SCM_LIB.SCM(SCH_1):P1V0_AUX    I92 @SCM_LIB.SCM(SCH_1):PAGE17
     2 P1V2_P1V0_I3C_VDDL2 @SCM_LIB.SCM(SCH_1):P1V2_P1V0_I3C_VDDL2    I92 @SCM_LIB.SCM(SCH_1):PAGE17

R282 Q_RES_0402LF-0,5%,1/16W,CHIP,CA
     1 RST_BMC_HW_R1 @SCM_LIB.SCM(SCH_1):RST_BMC_HW_R1   I100 @SCM_LIB.SCM(SCH_1):PAGE22
     2 RST_BMC_HW @SCM_LIB.SCM(SCH_1):RST_BMC_HW   I100 @SCM_LIB.SCM(SCH_1):PAGE22

R283 Q_RES_0402LF-75,1%,1/16W,CHIP,A
     1 FM_UARTSW_LSB_N @SCM_LIB.SCM(SCH_1):FM_UARTSW_LSB_N    I88 @SCM_LIB.SCM(SCH_1):PAGE49
     2 FM_UARTSW_LSB_R1_N @SCM_LIB.SCM(SCH_1):FM_UARTSW_LSB_R1_N    I88 @SCM_LIB.SCM(SCH_1):PAGE49

R284 Q_RES_0402LF-75,1%,1/16W,CHIP,A
     1 FM_UARTSW_MSB_N @SCM_LIB.SCM(SCH_1):FM_UARTSW_MSB_N    I89 @SCM_LIB.SCM(SCH_1):PAGE49
     2 FM_UARTSW_MSB_R1_N @SCM_LIB.SCM(SCH_1):FM_UARTSW_MSB_R1_N    I89 @SCM_LIB.SCM(SCH_1):PAGE49

R285 Q_RES_0402LF-4.7K,1%,1/16W,CHIA
     1 JTAG_SCM_PLD_TCK @SCM_LIB.SCM(SCH_1):JTAG_SCM_PLD_TCK   I141 @SCM_LIB.SCM(SCH_1):PAGE32
     2    GND @SCM_LIB.SCM(SCH_1):GND   I141 @SCM_LIB.SCM(SCH_1):PAGE32

R286 Q_RES_0402LF-316,1%,1/16W,CHIPA
     1 LED_D21_R2 @SCM_LIB.SCM(SCH_1):LED_D21_R2   I224 @SCM_LIB.SCM(SCH_1):PAGE50
     2 LED_D21_R1 @SCM_LIB.SCM(SCH_1):LED_D21_R1   I224 @SCM_LIB.SCM(SCH_1):PAGE50

R287 Q_RES_0402LF-499,1%,1/16W,CHIPA
     1 P3V3_RGM @SCM_LIB.SCM(SCH_1):P3V3_RGM     I5 @SCM_LIB.SCM(SCH_1):PAGE22
     2 RST_BMC_EXTRST_R2_N @SCM_LIB.SCM(SCH_1):RST_BMC_EXTRST_R2_N     I5 @SCM_LIB.SCM(SCH_1):PAGE22

R288 Q_RES_0402LF-10K,1%,1/16W,CHIPA
     1 VCCIO2 @SCM_LIB.SCM(SCH_1):VCCIO2    I50 @SCM_LIB.SCM(SCH_1):PAGE36
     2 PU_PB25A @SCM_LIB.SCM(SCH_1):PU_PB25A    I50 @SCM_LIB.SCM(SCH_1):PAGE36

R289 Q_RES_0402LF-10K,1%,1/16W,CHIPA
     1 P3V3_RGM @SCM_LIB.SCM(SCH_1):P3V3_RGM     I7 @SCM_LIB.SCM(SCH_1):PAGE22
     2 BJT_Q3_C @SCM_LIB.SCM(SCH_1):BJT_Q3_C     I7 @SCM_LIB.SCM(SCH_1):PAGE22

R290 Q_RES_0402LF-47K,1%,1/16W,CHIPA
     1 BJT_Q3_B @SCM_LIB.SCM(SCH_1):BJT_Q3_B     I8 @SCM_LIB.SCM(SCH_1):PAGE22
     2 RST_BMC_EXTRST_R1_N @SCM_LIB.SCM(SCH_1):RST_BMC_EXTRST_R1_N     I8 @SCM_LIB.SCM(SCH_1):PAGE22

R291 Q_RES_0402LF-4.7K,1%,1/16W,CHIA
     1 P3V3_RGM @SCM_LIB.SCM(SCH_1):P3V3_RGM     I9 @SCM_LIB.SCM(SCH_1):PAGE22
     2 RST_BMC_EXTRST_R1_N @SCM_LIB.SCM(SCH_1):RST_BMC_EXTRST_R1_N     I9 @SCM_LIB.SCM(SCH_1):PAGE22

R292 Q_RES_0402LF-0,5%,1/16W,CHIP,CA
     1 PWRGD_P5V_AUX_R @SCM_LIB.SCM(SCH_1):PWRGD_P5V_AUX_R    I51 @SCM_LIB.SCM(SCH_1):PAGE51
     2 PWRGD_P5V_AUX @SCM_LIB.SCM(SCH_1):PWRGD_P5V_AUX    I51 @SCM_LIB.SCM(SCH_1):PAGE51

R293 Q_RES_0402LF-0,5%,1/16W,CHIP,CA
     1 PWRGD_P3V3_AUX_R @SCM_LIB.SCM(SCH_1):PWRGD_P3V3_AUX_R    I95 @SCM_LIB.SCM(SCH_1):PAGE52
     2 PWRGD_P3V3_AUX @SCM_LIB.SCM(SCH_1):PWRGD_P3V3_AUX    I95 @SCM_LIB.SCM(SCH_1):PAGE52

R294 Q_RES_0402LF-0,5%,1/16W,CHIP,CA
     1 SMB_BMC_MM15_SDA @SCM_LIB.SCM(SCH_1):SMB_BMC_MM15_SDA   I108 @SCM_LIB.SCM(SCH_1):PAGE28
     2 SMB_BMC_MM15_R1_SDA @SCM_LIB.SCM(SCH_1):SMB_BMC_MM15_R1_SDA   I108 @SCM_LIB.SCM(SCH_1):PAGE28

R295 Q_RES_0402LF-10K,1%,1/16W,CHIPA
     1 P3V3_AUX @SCM_LIB.SCM(SCH_1):P3V3_AUX   I113 @SCM_LIB.SCM(SCH_1):PAGE28
     2 DEBUG_PORT_PRSNT_BUF_R_EN @SCM_LIB.SCM(SCH_1):DEBUG_PORT_PRSNT_BUF_R_EN   I113 @SCM_LIB.SCM(SCH_1):PAGE28

R296 Q_RES_0402LF-100K,1%,1/16W,EMPA
     1 DEBUG_PORT_PRSNT_BUF_R_EN @SCM_LIB.SCM(SCH_1):DEBUG_PORT_PRSNT_BUF_R_EN   I105 @SCM_LIB.SCM(SCH_1):PAGE28
     2    GND @SCM_LIB.SCM(SCH_1):GND   I105 @SCM_LIB.SCM(SCH_1):PAGE28

R297 Q_RES_0402LF-10K,1%,1/16W,CHIPA
     1 PU_PT20D @SCM_LIB.SCM(SCH_1):PU_PT20D   I137 @SCM_LIB.SCM(SCH_1):PAGE34
     2 VCCIO2 @SCM_LIB.SCM(SCH_1):VCCIO2   I137 @SCM_LIB.SCM(SCH_1):PAGE34

R298 Q_RES_0402LF-4.7K,1%,1/16W,CHIA
     1 P3V3_AUX @SCM_LIB.SCM(SCH_1):P3V3_AUX    I96 @SCM_LIB.SCM(SCH_1):PAGE28
     2 SMB_DEBUG_AUX_LVC3_USB_R1_SCL @SCM_LIB.SCM(SCH_1):SMB_DEBUG_AUX_LVC3_USB_R1_SCL    I96 @SCM_LIB.SCM(SCH_1):PAGE28

R299 Q_RES_0402LF-4.7K,1%,1/16W,CHIA
     1 P3V3_AUX @SCM_LIB.SCM(SCH_1):P3V3_AUX    I91 @SCM_LIB.SCM(SCH_1):PAGE28
     2 SMB_DEBUG_AUX_LVC3_USB_R1_SDA @SCM_LIB.SCM(SCH_1):SMB_DEBUG_AUX_LVC3_USB_R1_SDA    I91 @SCM_LIB.SCM(SCH_1):PAGE28

R300 Q_RES_0402LF-33.2,1%,1/16W,CHIA
     1 SMB_DEBUG_AUX_LVC3_USB_R1_SCL @SCM_LIB.SCM(SCH_1):SMB_DEBUG_AUX_LVC3_USB_R1_SCL   I183 @SCM_LIB.SCM(SCH_1):PAGE28
     2 SMB_DEBUG_AUX_LVC3_USB_SCL @SCM_LIB.SCM(SCH_1):SMB_DEBUG_AUX_LVC3_USB_SCL   I183 @SCM_LIB.SCM(SCH_1):PAGE28

R301 Q_RES_0402LF-0,5%,1/16W,CHIP,CA
     1 P3V3_AUX @SCM_LIB.SCM(SCH_1):P3V3_AUX    I75 @SCM_LIB.SCM(SCH_1):PAGE41
     2 VCCIO5 @SCM_LIB.SCM(SCH_1):VCCIO5    I75 @SCM_LIB.SCM(SCH_1):PAGE41

R302 Q_RES_0402LF-33.2,1%,1/16W,CHIA
     1 SMB_DEBUG_AUX_LVC3_USB_R1_SDA @SCM_LIB.SCM(SCH_1):SMB_DEBUG_AUX_LVC3_USB_R1_SDA   I184 @SCM_LIB.SCM(SCH_1):PAGE28
     2 SMB_DEBUG_AUX_LVC3_USB_SDA @SCM_LIB.SCM(SCH_1):SMB_DEBUG_AUX_LVC3_USB_SDA   I184 @SCM_LIB.SCM(SCH_1):PAGE28

R303 Q_RES_0402LF-0,5%,1/16W,CHIP,CA
     1 SMB_BMC_MM16_R3_SDA @SCM_LIB.SCM(SCH_1):SMB_BMC_MM16_R3_SDA   I166 @SCM_LIB.SCM(SCH_1):PAGE34
     2 SMB_BMC_MM16_R5_SDA @SCM_LIB.SCM(SCH_1):SMB_BMC_MM16_R5_SDA   I166 @SCM_LIB.SCM(SCH_1):PAGE34

R304 Q_RES_0402LF-0,5%,1/16W,CHIP,CA
     1 P3V3_AUX @SCM_LIB.SCM(SCH_1):P3V3_AUX    I73 @SCM_LIB.SCM(SCH_1):PAGE41
     2 VCCIO2 @SCM_LIB.SCM(SCH_1):VCCIO2    I73 @SCM_LIB.SCM(SCH_1):PAGE41

R305 Q_RES_0402LF-0,5%,1/16W,CHIP,CA
     1 P3V3_AUX @SCM_LIB.SCM(SCH_1):P3V3_AUX    I71 @SCM_LIB.SCM(SCH_1):PAGE41
     2 VCCIO0 @SCM_LIB.SCM(SCH_1):VCCIO0    I71 @SCM_LIB.SCM(SCH_1):PAGE41

R306 Q_RES_0402LF-10K,1%,1/16W,CHIPA
     1 BEEP_LED @SCM_LIB.SCM(SCH_1):BEEP_LED     I8 @SCM_LIB.SCM(SCH_1):PAGE49
     2    GND @SCM_LIB.SCM(SCH_1):GND     I8 @SCM_LIB.SCM(SCH_1):PAGE49

R307 Q_RES_0402LF-0,5%,1/16W,CHIP,CA
     1 P3V3_AUX @SCM_LIB.SCM(SCH_1):P3V3_AUX    I76 @SCM_LIB.SCM(SCH_1):PAGE41
     2 VCCIO4 @SCM_LIB.SCM(SCH_1):VCCIO4    I76 @SCM_LIB.SCM(SCH_1):PAGE41

R308 Q_RES_0402LF-0,5%,1/16W,CHIP,CA
     1 P3V3_AUX @SCM_LIB.SCM(SCH_1):P3V3_AUX    I74 @SCM_LIB.SCM(SCH_1):PAGE41
     2 VCCIO3 @SCM_LIB.SCM(SCH_1):VCCIO3    I74 @SCM_LIB.SCM(SCH_1):PAGE41

R309 Q_RES_0402LF-33.2,1%,1/16W,CHIA
     1 SPI_BMC_TPM_MOSI_R1 @SCM_LIB.SCM(SCH_1):SPI_BMC_TPM_MOSI_R1   I360 @SCM_LIB.SCM(SCH_1):PAGE13
     2 SPI_BMC_TPM_MOSI @SCM_LIB.SCM(SCH_1):SPI_BMC_TPM_MOSI   I360 @SCM_LIB.SCM(SCH_1):PAGE13

R310 Q_RES_0402LF-33.2,1%,1/16W,CHIA
     1 ESPI_HOST_LPC_BMC_CLK @SCM_LIB.SCM(SCH_1):ESPI_HOST_LPC_BMC_CLK   I441 @SCM_LIB.SCM(SCH_1):PAGE12
     2 ESPI_HOST_LPC_BMC_CLK_R @SCM_LIB.SCM(SCH_1):ESPI_HOST_LPC_BMC_CLK_R   I441 @SCM_LIB.SCM(SCH_1):PAGE12

R311 Q_RES_0402LF-33.2,1%,1/16W,CHIA
     1 ESPI_HOST_LPC_BMC_LFRAME_N @SCM_LIB.SCM(SCH_1):ESPI_HOST_LPC_BMC_LFRAME_N   I447 @SCM_LIB.SCM(SCH_1):PAGE12
     2 ESPI_HOST_LPC_BMC_LFRAME_N_R @SCM_LIB.SCM(SCH_1):ESPI_HOST_LPC_BMC_LFRAME_N_R   I447 @SCM_LIB.SCM(SCH_1):PAGE12

R312 Q_RES_0402LF-47K,1%,1/16W,CHIPA
     1 RST_BMC_LPC_ESPI_N @SCM_LIB.SCM(SCH_1):RST_BMC_LPC_ESPI_N   I456 @SCM_LIB.SCM(SCH_1):PAGE12
     2    GND @SCM_LIB.SCM(SCH_1):GND   I456 @SCM_LIB.SCM(SCH_1):PAGE12

R313 Q_RES_0402LF-470K,1%,1/16W,CHIA
     1 RST_BMC_SELF_HW_D @SCM_LIB.SCM(SCH_1):RST_BMC_SELF_HW_D    I30 @SCM_LIB.SCM(SCH_1):PAGE22
     2    GND @SCM_LIB.SCM(SCH_1):GND    I30 @SCM_LIB.SCM(SCH_1):PAGE22

R314 Q_RES_0402LF-100K,1%,1/16W,CHIA
     1 RST_BMC_SELF_HW_D_C @SCM_LIB.SCM(SCH_1):RST_BMC_SELF_HW_D_C    I26 @SCM_LIB.SCM(SCH_1):PAGE22
     2    GND @SCM_LIB.SCM(SCH_1):GND    I26 @SCM_LIB.SCM(SCH_1):PAGE22

R315 Q_RES_0402LF-0,5%,1/16W,EMPTY,A
     1 RST_BMC_SRST_BUF_R_N @SCM_LIB.SCM(SCH_1):RST_BMC_SRST_BUF_R_N    I71 @SCM_LIB.SCM(SCH_1):PAGE22
     2 RST_BMC_SRST_BUF_R1_N @SCM_LIB.SCM(SCH_1):RST_BMC_SRST_BUF_R1_N    I71 @SCM_LIB.SCM(SCH_1):PAGE22

R316 Q_RES_0402LF-0,5%,1/16W,CHIP,CA
     1 BMC_PWR_LED @SCM_LIB.SCM(SCH_1):BMC_PWR_LED   I318 @SCM_LIB.SCM(SCH_1):PAGE15
     2 PWR_LED @SCM_LIB.SCM(SCH_1):PWR_LED   I318 @SCM_LIB.SCM(SCH_1):PAGE15

R317 Q_RES_0402LF-0,5%,1/16W,CHIP,CA
     1 PWR_LED_CPLD @SCM_LIB.SCM(SCH_1):PWR_LED_CPLD    I99 @SCM_LIB.SCM(SCH_1):PAGE35
     2 PWR_LED @SCM_LIB.SCM(SCH_1):PWR_LED    I99 @SCM_LIB.SCM(SCH_1):PAGE35

R318 Q_RES_0402LF-0,5%,1/16W,CHIP,CA
     1 PWRGD_P3V3_AUX_R1 @SCM_LIB.SCM(SCH_1):PWRGD_P3V3_AUX_R1    I98 @SCM_LIB.SCM(SCH_1):PAGE35
     2 PWRGD_P3V3_AUX @SCM_LIB.SCM(SCH_1):PWRGD_P3V3_AUX    I98 @SCM_LIB.SCM(SCH_1):PAGE35

R319 Q_RES_0402LF-4.7K,1%,1/16W,CHIA
     1 P3V3_AUX @SCM_LIB.SCM(SCH_1):P3V3_AUX    I65 @SCM_LIB.SCM(SCH_1):PAGE42
     2 BMC_ID_BEEP_SEL @SCM_LIB.SCM(SCH_1):BMC_ID_BEEP_SEL    I65 @SCM_LIB.SCM(SCH_1):PAGE42

R320 Q_RES_0402LF-0,5%,1/16W,CHIP,CA
     1 PWRGD_P2V5_AUX_R1 @SCM_LIB.SCM(SCH_1):PWRGD_P2V5_AUX_R1    I95 @SCM_LIB.SCM(SCH_1):PAGE35
     2 PWRGD_P2V5_AUX @SCM_LIB.SCM(SCH_1):PWRGD_P2V5_AUX    I95 @SCM_LIB.SCM(SCH_1):PAGE35

R321 Q_RES_0402LF-0,5%,1/16W,CHIP,CA
     1 PWRGD_P1V8_AUX_R1 @SCM_LIB.SCM(SCH_1):PWRGD_P1V8_AUX_R1    I33 @SCM_LIB.SCM(SCH_1):PAGE36
     2 PWRGD_P1V8_AUX @SCM_LIB.SCM(SCH_1):PWRGD_P1V8_AUX    I33 @SCM_LIB.SCM(SCH_1):PAGE36

R322 Q_RES_0402LF-0,5%,1/16W,CHIP,CA
     1 PWRGD_P3V3_RGM_R1 @SCM_LIB.SCM(SCH_1):PWRGD_P3V3_RGM_R1    I35 @SCM_LIB.SCM(SCH_1):PAGE36
     2 PWRGD_P3V3_RGM @SCM_LIB.SCM(SCH_1):PWRGD_P3V3_RGM    I35 @SCM_LIB.SCM(SCH_1):PAGE36

R323 Q_RES_0402LF-0,5%,1/16W,CHIP,CA
     1 PWRGD_P1V2_AUX_R1 @SCM_LIB.SCM(SCH_1):PWRGD_P1V2_AUX_R1    I34 @SCM_LIB.SCM(SCH_1):PAGE36
     2 PWRGD_P1V2_AUX @SCM_LIB.SCM(SCH_1):PWRGD_P1V2_AUX    I34 @SCM_LIB.SCM(SCH_1):PAGE36

R324 Q_RES_0402LF-1K,1%,1/16W,CHIP,A
     1 P1V2_AUX @SCM_LIB.SCM(SCH_1):P1V2_AUX    I28 @SCM_LIB.SCM(SCH_1):PAGE20
     2 P0V6_DDR_VREF_AUX @SCM_LIB.SCM(SCH_1):P0V6_DDR_VREF_AUX    I28 @SCM_LIB.SCM(SCH_1):PAGE20

R325 Q_RES_0402LF-1K,1%,1/16W,CHIP,A
     1 P0V6_DDR_VREF_AUX @SCM_LIB.SCM(SCH_1):P0V6_DDR_VREF_AUX    I27 @SCM_LIB.SCM(SCH_1):PAGE20
     2    GND @SCM_LIB.SCM(SCH_1):GND    I27 @SCM_LIB.SCM(SCH_1):PAGE20

R326 Q_RES_0402LF-120,1%,1/16W,CHIPA
     1    GND @SCM_LIB.SCM(SCH_1):GND   I193 @SCM_LIB.SCM(SCH_1):PAGE20
     2 M_BMC_DDR4_MA<0> @SCM_LIB.SCM(SCH_1):M_BMC_DDR4_MA(0)   I193 @SCM_LIB.SCM(SCH_1):PAGE20

R327 Q_RES_0402LF-120,1%,1/16W,CHIPA
     1    GND @SCM_LIB.SCM(SCH_1):GND   I177 @SCM_LIB.SCM(SCH_1):PAGE20
     2 M_BMC_DDR4_MA<1> @SCM_LIB.SCM(SCH_1):M_BMC_DDR4_MA(1)   I177 @SCM_LIB.SCM(SCH_1):PAGE20

R328 Q_RES_0402LF-120,1%,1/16W,CHIPA
     1    GND @SCM_LIB.SCM(SCH_1):GND   I176 @SCM_LIB.SCM(SCH_1):PAGE20
     2 M_BMC_DDR4_MA<2> @SCM_LIB.SCM(SCH_1):M_BMC_DDR4_MA(2)   I176 @SCM_LIB.SCM(SCH_1):PAGE20

R329 Q_RES_0402LF-120,1%,1/16W,CHIPA
     1    GND @SCM_LIB.SCM(SCH_1):GND   I175 @SCM_LIB.SCM(SCH_1):PAGE20
     2 M_BMC_DDR4_MA<3> @SCM_LIB.SCM(SCH_1):M_BMC_DDR4_MA(3)   I175 @SCM_LIB.SCM(SCH_1):PAGE20

R330 Q_RES_0402LF-120,1%,1/16W,CHIPA
     1    GND @SCM_LIB.SCM(SCH_1):GND   I174 @SCM_LIB.SCM(SCH_1):PAGE20
     2 M_BMC_DDR4_MA<4> @SCM_LIB.SCM(SCH_1):M_BMC_DDR4_MA(4)   I174 @SCM_LIB.SCM(SCH_1):PAGE20

R331 Q_RES_0402LF-120,1%,1/16W,CHIPA
     1    GND @SCM_LIB.SCM(SCH_1):GND   I173 @SCM_LIB.SCM(SCH_1):PAGE20
     2 M_BMC_DDR4_MA<5> @SCM_LIB.SCM(SCH_1):M_BMC_DDR4_MA(5)   I173 @SCM_LIB.SCM(SCH_1):PAGE20

R332 Q_RES_0402LF-120,1%,1/16W,CHIPA
     1    GND @SCM_LIB.SCM(SCH_1):GND   I171 @SCM_LIB.SCM(SCH_1):PAGE20
     2 M_BMC_DDR4_MA<6> @SCM_LIB.SCM(SCH_1):M_BMC_DDR4_MA(6)   I171 @SCM_LIB.SCM(SCH_1):PAGE20

R333 Q_RES_0402LF-120,1%,1/16W,CHIPA
     1    GND @SCM_LIB.SCM(SCH_1):GND   I172 @SCM_LIB.SCM(SCH_1):PAGE20
     2 M_BMC_DDR4_MA<7> @SCM_LIB.SCM(SCH_1):M_BMC_DDR4_MA(7)   I172 @SCM_LIB.SCM(SCH_1):PAGE20

R334 Q_RES_0402LF-120,1%,1/16W,CHIPA
     1    GND @SCM_LIB.SCM(SCH_1):GND   I164 @SCM_LIB.SCM(SCH_1):PAGE20
     2 M_BMC_DDR4_MA<8> @SCM_LIB.SCM(SCH_1):M_BMC_DDR4_MA(8)   I164 @SCM_LIB.SCM(SCH_1):PAGE20

R335 Q_RES_0402LF-120,1%,1/16W,CHIPA
     1    GND @SCM_LIB.SCM(SCH_1):GND   I163 @SCM_LIB.SCM(SCH_1):PAGE20
     2 M_BMC_DDR4_MA<9> @SCM_LIB.SCM(SCH_1):M_BMC_DDR4_MA(9)   I163 @SCM_LIB.SCM(SCH_1):PAGE20

R336 Q_RES_0402LF-120,1%,1/16W,CHIPA
     1    GND @SCM_LIB.SCM(SCH_1):GND   I162 @SCM_LIB.SCM(SCH_1):PAGE20
     2 M_BMC_DDR4_MA<10> @SCM_LIB.SCM(SCH_1):M_BMC_DDR4_MA(10)   I162 @SCM_LIB.SCM(SCH_1):PAGE20

R337 Q_RES_0402LF-120,1%,1/16W,CHIPA
     1    GND @SCM_LIB.SCM(SCH_1):GND   I161 @SCM_LIB.SCM(SCH_1):PAGE20
     2 M_BMC_DDR4_MA<11> @SCM_LIB.SCM(SCH_1):M_BMC_DDR4_MA(11)   I161 @SCM_LIB.SCM(SCH_1):PAGE20

R338 Q_RES_0402LF-120,1%,1/16W,CHIPA
     1    GND @SCM_LIB.SCM(SCH_1):GND   I160 @SCM_LIB.SCM(SCH_1):PAGE20
     2 M_BMC_DDR4_MA<12> @SCM_LIB.SCM(SCH_1):M_BMC_DDR4_MA(12)   I160 @SCM_LIB.SCM(SCH_1):PAGE20

R339 Q_RES_0402LF-120,1%,1/16W,CHIPA
     1    GND @SCM_LIB.SCM(SCH_1):GND   I159 @SCM_LIB.SCM(SCH_1):PAGE20
     2 M_BMC_DDR4_MA<13> @SCM_LIB.SCM(SCH_1):M_BMC_DDR4_MA(13)   I159 @SCM_LIB.SCM(SCH_1):PAGE20

R340 Q_RES_0402LF-120,1%,1/16W,CHIPA
     1    GND @SCM_LIB.SCM(SCH_1):GND   I124 @SCM_LIB.SCM(SCH_1):PAGE20
     2 M_BMC_DDR4_MWE_N @SCM_LIB.SCM(SCH_1):M_BMC_DDR4_MWE_N   I124 @SCM_LIB.SCM(SCH_1):PAGE20

R341 Q_RES_0402LF-120,1%,1/16W,CHIPA
     1    GND @SCM_LIB.SCM(SCH_1):GND   I125 @SCM_LIB.SCM(SCH_1):PAGE20
     2 M_BMC_DDR4_MCAS_N @SCM_LIB.SCM(SCH_1):M_BMC_DDR4_MCAS_N   I125 @SCM_LIB.SCM(SCH_1):PAGE20

R342 Q_RES_0402LF-120,1%,1/16W,CHIPA
     1    GND @SCM_LIB.SCM(SCH_1):GND   I122 @SCM_LIB.SCM(SCH_1):PAGE20
     2 M_BMC_DDR4_MRAS_N @SCM_LIB.SCM(SCH_1):M_BMC_DDR4_MRAS_N   I122 @SCM_LIB.SCM(SCH_1):PAGE20

R343 Q_RES_0402LF-120,1%,1/16W,CHIPA
     1    GND @SCM_LIB.SCM(SCH_1):GND   I123 @SCM_LIB.SCM(SCH_1):PAGE20
     2 M_BMC_DDR4_MCS_N @SCM_LIB.SCM(SCH_1):M_BMC_DDR4_MCS_N   I123 @SCM_LIB.SCM(SCH_1):PAGE20

R344 Q_RES_0402LF-120,1%,1/16W,CHIPA
     1    GND @SCM_LIB.SCM(SCH_1):GND   I121 @SCM_LIB.SCM(SCH_1):PAGE20
     2 M_BMC_DDR4_MACT_N @SCM_LIB.SCM(SCH_1):M_BMC_DDR4_MACT_N   I121 @SCM_LIB.SCM(SCH_1):PAGE20

R345 Q_RES_0402LF-120,1%,1/16W,CHIPA
     1    GND @SCM_LIB.SCM(SCH_1):GND   I119 @SCM_LIB.SCM(SCH_1):PAGE20
     2 M_BMC_DDR4_MBG0 @SCM_LIB.SCM(SCH_1):M_BMC_DDR4_MBG0   I119 @SCM_LIB.SCM(SCH_1):PAGE20

R346 Q_RES_0402LF-120,1%,1/16W,CHIPA
     1    GND @SCM_LIB.SCM(SCH_1):GND   I120 @SCM_LIB.SCM(SCH_1):PAGE20
     2 M_BMC_DDR4_MBA0 @SCM_LIB.SCM(SCH_1):M_BMC_DDR4_MBA0   I120 @SCM_LIB.SCM(SCH_1):PAGE20

R347 Q_RES_0402LF-120,1%,1/16W,CHIPA
     1    GND @SCM_LIB.SCM(SCH_1):GND   I117 @SCM_LIB.SCM(SCH_1):PAGE20
     2 M_BMC_DDR4_MBA1 @SCM_LIB.SCM(SCH_1):M_BMC_DDR4_MBA1   I117 @SCM_LIB.SCM(SCH_1):PAGE20

R348 Q_RES_0402LF-120,1%,1/16W,CHIPA
     1    GND @SCM_LIB.SCM(SCH_1):GND   I118 @SCM_LIB.SCM(SCH_1):PAGE20
     2 M_BMC_DDR4_MODT @SCM_LIB.SCM(SCH_1):M_BMC_DDR4_MODT   I118 @SCM_LIB.SCM(SCH_1):PAGE20

R349 Q_RES_0402LF-120,1%,1/16W,CHIPA
     1    GND @SCM_LIB.SCM(SCH_1):GND   I116 @SCM_LIB.SCM(SCH_1):PAGE20
     2 M_BMC_DDR4_MCKE @SCM_LIB.SCM(SCH_1):M_BMC_DDR4_MCKE   I116 @SCM_LIB.SCM(SCH_1):PAGE20

R350 Q_RES_0402LF-120,1%,1/16W,EMPTA
     1    GND @SCM_LIB.SCM(SCH_1):GND   I114 @SCM_LIB.SCM(SCH_1):PAGE20
     2 M_BMC_DDR4_MBG1 @SCM_LIB.SCM(SCH_1):M_BMC_DDR4_MBG1   I114 @SCM_LIB.SCM(SCH_1):PAGE20

R351 Q_RES_0402LF-120,1%,1/16W,CHIPA
     1 M_BMC_DDR4_MA<0> @SCM_LIB.SCM(SCH_1):M_BMC_DDR4_MA(0)   I194 @SCM_LIB.SCM(SCH_1):PAGE20
     2 P1V2_AUX @SCM_LIB.SCM(SCH_1):P1V2_AUX   I194 @SCM_LIB.SCM(SCH_1):PAGE20

R352 Q_RES_0402LF-120,1%,1/16W,CHIPA
     1 M_BMC_DDR4_MA<1> @SCM_LIB.SCM(SCH_1):M_BMC_DDR4_MA(1)   I184 @SCM_LIB.SCM(SCH_1):PAGE20
     2 P1V2_AUX @SCM_LIB.SCM(SCH_1):P1V2_AUX   I184 @SCM_LIB.SCM(SCH_1):PAGE20

R353 Q_RES_0402LF-120,1%,1/16W,CHIPA
     1 M_BMC_DDR4_MA<2> @SCM_LIB.SCM(SCH_1):M_BMC_DDR4_MA(2)   I183 @SCM_LIB.SCM(SCH_1):PAGE20
     2 P1V2_AUX @SCM_LIB.SCM(SCH_1):P1V2_AUX   I183 @SCM_LIB.SCM(SCH_1):PAGE20

R354 Q_RES_0402LF-120,1%,1/16W,CHIPA
     1 M_BMC_DDR4_MA<3> @SCM_LIB.SCM(SCH_1):M_BMC_DDR4_MA(3)   I181 @SCM_LIB.SCM(SCH_1):PAGE20
     2 P1V2_AUX @SCM_LIB.SCM(SCH_1):P1V2_AUX   I181 @SCM_LIB.SCM(SCH_1):PAGE20

R355 Q_RES_0402LF-120,1%,1/16W,CHIPA
     1 M_BMC_DDR4_MA<4> @SCM_LIB.SCM(SCH_1):M_BMC_DDR4_MA(4)   I182 @SCM_LIB.SCM(SCH_1):PAGE20
     2 P1V2_AUX @SCM_LIB.SCM(SCH_1):P1V2_AUX   I182 @SCM_LIB.SCM(SCH_1):PAGE20

R356 Q_RES_0402LF-120,1%,1/16W,CHIPA
     1 M_BMC_DDR4_MA<5> @SCM_LIB.SCM(SCH_1):M_BMC_DDR4_MA(5)   I180 @SCM_LIB.SCM(SCH_1):PAGE20
     2 P1V2_AUX @SCM_LIB.SCM(SCH_1):P1V2_AUX   I180 @SCM_LIB.SCM(SCH_1):PAGE20

R357 Q_RES_0402LF-120,1%,1/16W,CHIPA
     1 M_BMC_DDR4_MA<6> @SCM_LIB.SCM(SCH_1):M_BMC_DDR4_MA(6)   I179 @SCM_LIB.SCM(SCH_1):PAGE20
     2 P1V2_AUX @SCM_LIB.SCM(SCH_1):P1V2_AUX   I179 @SCM_LIB.SCM(SCH_1):PAGE20

R358 Q_RES_0402LF-120,1%,1/16W,CHIPA
     1 M_BMC_DDR4_MA<7> @SCM_LIB.SCM(SCH_1):M_BMC_DDR4_MA(7)   I178 @SCM_LIB.SCM(SCH_1):PAGE20
     2 P1V2_AUX @SCM_LIB.SCM(SCH_1):P1V2_AUX   I178 @SCM_LIB.SCM(SCH_1):PAGE20

R359 Q_RES_0402LF-120,1%,1/16W,CHIPA
     1 M_BMC_DDR4_MA<8> @SCM_LIB.SCM(SCH_1):M_BMC_DDR4_MA(8)   I170 @SCM_LIB.SCM(SCH_1):PAGE20
     2 P1V2_AUX @SCM_LIB.SCM(SCH_1):P1V2_AUX   I170 @SCM_LIB.SCM(SCH_1):PAGE20

R360 Q_RES_0402LF-120,1%,1/16W,CHIPA
     1 M_BMC_DDR4_MA<9> @SCM_LIB.SCM(SCH_1):M_BMC_DDR4_MA(9)   I169 @SCM_LIB.SCM(SCH_1):PAGE20
     2 P1V2_AUX @SCM_LIB.SCM(SCH_1):P1V2_AUX   I169 @SCM_LIB.SCM(SCH_1):PAGE20

R361 Q_RES_0402LF-120,1%,1/16W,CHIPA
     1 M_BMC_DDR4_MA<10> @SCM_LIB.SCM(SCH_1):M_BMC_DDR4_MA(10)   I167 @SCM_LIB.SCM(SCH_1):PAGE20
     2 P1V2_AUX @SCM_LIB.SCM(SCH_1):P1V2_AUX   I167 @SCM_LIB.SCM(SCH_1):PAGE20

R362 Q_RES_0402LF-120,1%,1/16W,CHIPA
     1 M_BMC_DDR4_MA<11> @SCM_LIB.SCM(SCH_1):M_BMC_DDR4_MA(11)   I168 @SCM_LIB.SCM(SCH_1):PAGE20
     2 P1V2_AUX @SCM_LIB.SCM(SCH_1):P1V2_AUX   I168 @SCM_LIB.SCM(SCH_1):PAGE20

R363 Q_RES_0402LF-120,1%,1/16W,CHIPA
     1 M_BMC_DDR4_MA<12> @SCM_LIB.SCM(SCH_1):M_BMC_DDR4_MA(12)   I166 @SCM_LIB.SCM(SCH_1):PAGE20
     2 P1V2_AUX @SCM_LIB.SCM(SCH_1):P1V2_AUX   I166 @SCM_LIB.SCM(SCH_1):PAGE20

R364 Q_RES_0402LF-120,1%,1/16W,CHIPA
     1 M_BMC_DDR4_MA<13> @SCM_LIB.SCM(SCH_1):M_BMC_DDR4_MA(13)   I165 @SCM_LIB.SCM(SCH_1):PAGE20
     2 P1V2_AUX @SCM_LIB.SCM(SCH_1):P1V2_AUX   I165 @SCM_LIB.SCM(SCH_1):PAGE20

R365 Q_RES_0402LF-120,1%,1/16W,CHIPA
     1 M_BMC_DDR4_MWE_N @SCM_LIB.SCM(SCH_1):M_BMC_DDR4_MWE_N   I138 @SCM_LIB.SCM(SCH_1):PAGE20
     2 P1V2_AUX @SCM_LIB.SCM(SCH_1):P1V2_AUX   I138 @SCM_LIB.SCM(SCH_1):PAGE20

R366 Q_RES_0402LF-120,1%,1/16W,CHIPA
     1 M_BMC_DDR4_MCAS_N @SCM_LIB.SCM(SCH_1):M_BMC_DDR4_MCAS_N   I137 @SCM_LIB.SCM(SCH_1):PAGE20
     2 P1V2_AUX @SCM_LIB.SCM(SCH_1):P1V2_AUX   I137 @SCM_LIB.SCM(SCH_1):PAGE20

R367 Q_RES_0402LF-120,1%,1/16W,CHIPA
     1 M_BMC_DDR4_MRAS_N @SCM_LIB.SCM(SCH_1):M_BMC_DDR4_MRAS_N   I136 @SCM_LIB.SCM(SCH_1):PAGE20
     2 P1V2_AUX @SCM_LIB.SCM(SCH_1):P1V2_AUX   I136 @SCM_LIB.SCM(SCH_1):PAGE20

R368 Q_RES_0402LF-120,1%,1/16W,CHIPA
     1 M_BMC_DDR4_MCS_N @SCM_LIB.SCM(SCH_1):M_BMC_DDR4_MCS_N   I135 @SCM_LIB.SCM(SCH_1):PAGE20
     2 P1V2_AUX @SCM_LIB.SCM(SCH_1):P1V2_AUX   I135 @SCM_LIB.SCM(SCH_1):PAGE20

R369 Q_RES_0402LF-120,1%,1/16W,CHIPA
     1 M_BMC_DDR4_MACT_N @SCM_LIB.SCM(SCH_1):M_BMC_DDR4_MACT_N   I132 @SCM_LIB.SCM(SCH_1):PAGE20
     2 P1V2_AUX @SCM_LIB.SCM(SCH_1):P1V2_AUX   I132 @SCM_LIB.SCM(SCH_1):PAGE20

R370 Q_RES_0402LF-120,1%,1/16W,CHIPA
     1 M_BMC_DDR4_MBG0 @SCM_LIB.SCM(SCH_1):M_BMC_DDR4_MBG0   I131 @SCM_LIB.SCM(SCH_1):PAGE20
     2 P1V2_AUX @SCM_LIB.SCM(SCH_1):P1V2_AUX   I131 @SCM_LIB.SCM(SCH_1):PAGE20

R371 Q_RES_0402LF-120,1%,1/16W,CHIPA
     1 M_BMC_DDR4_MBA0 @SCM_LIB.SCM(SCH_1):M_BMC_DDR4_MBA0   I130 @SCM_LIB.SCM(SCH_1):PAGE20
     2 P1V2_AUX @SCM_LIB.SCM(SCH_1):P1V2_AUX   I130 @SCM_LIB.SCM(SCH_1):PAGE20

R372 Q_RES_0402LF-120,1%,1/16W,CHIPA
     1 M_BMC_DDR4_MBA1 @SCM_LIB.SCM(SCH_1):M_BMC_DDR4_MBA1   I129 @SCM_LIB.SCM(SCH_1):PAGE20
     2 P1V2_AUX @SCM_LIB.SCM(SCH_1):P1V2_AUX   I129 @SCM_LIB.SCM(SCH_1):PAGE20

R373 Q_RES_0402LF-120,1%,1/16W,CHIPA
     1 M_BMC_DDR4_MODT @SCM_LIB.SCM(SCH_1):M_BMC_DDR4_MODT   I128 @SCM_LIB.SCM(SCH_1):PAGE20
     2 P1V2_AUX @SCM_LIB.SCM(SCH_1):P1V2_AUX   I128 @SCM_LIB.SCM(SCH_1):PAGE20

R374 Q_RES_0402LF-120,1%,1/16W,CHIPA
     1 M_BMC_DDR4_MCKE @SCM_LIB.SCM(SCH_1):M_BMC_DDR4_MCKE   I127 @SCM_LIB.SCM(SCH_1):PAGE20
     2 P1V2_AUX @SCM_LIB.SCM(SCH_1):P1V2_AUX   I127 @SCM_LIB.SCM(SCH_1):PAGE20

R375 Q_RES_0402LF-120,1%,1/16W,EMPTA
     1 M_BMC_DDR4_MBG1 @SCM_LIB.SCM(SCH_1):M_BMC_DDR4_MBG1   I115 @SCM_LIB.SCM(SCH_1):PAGE20
     2 P1V2_AUX @SCM_LIB.SCM(SCH_1):P1V2_AUX   I115 @SCM_LIB.SCM(SCH_1):PAGE20

R376 Q_RES_0402LF-4.7K,1%,1/16W,CHIA
     1 P5V_AUX @SCM_LIB.SCM(SCH_1):P5V_AUX    I62 @SCM_LIB.SCM(SCH_1):PAGE28
     2 USB_OC0_EN @SCM_LIB.SCM(SCH_1):USB_OC0_EN    I62 @SCM_LIB.SCM(SCH_1):PAGE28

R377 Q_RES_0402LF-10K,1%,1/16W,EMPTA
     1 USB_OC0_EN @SCM_LIB.SCM(SCH_1):USB_OC0_EN    I63 @SCM_LIB.SCM(SCH_1):PAGE28
     2    GND @SCM_LIB.SCM(SCH_1):GND    I63 @SCM_LIB.SCM(SCH_1):PAGE28

R378 Q_RES_0402LF-20K,1%,1/16W,CHIPA
     1 USB_OC0_ILIM @SCM_LIB.SCM(SCH_1):USB_OC0_ILIM    I54 @SCM_LIB.SCM(SCH_1):PAGE28
     2    GND @SCM_LIB.SCM(SCH_1):GND    I54 @SCM_LIB.SCM(SCH_1):PAGE28

R379 Q_RES_0402LF-0,5%,1/16W,CHIP,CA
     1 PWRGD_P1V0_AUX_R1 @SCM_LIB.SCM(SCH_1):PWRGD_P1V0_AUX_R1    I36 @SCM_LIB.SCM(SCH_1):PAGE36
     2 PWRGD_P1V0_AUX @SCM_LIB.SCM(SCH_1):PWRGD_P1V0_AUX    I36 @SCM_LIB.SCM(SCH_1):PAGE36

R380 Q_RES_0402LF-100,1%,1/16W,CHIPA
     1 EN_P3V3_RGM @SCM_LIB.SCM(SCH_1):EN_P3V3_RGM   I147 @SCM_LIB.SCM(SCH_1):PAGE52
     2 EN_P3V3_RGM_R @SCM_LIB.SCM(SCH_1):EN_P3V3_RGM_R   I147 @SCM_LIB.SCM(SCH_1):PAGE52

R381 Q_RES_0402LF-0,5%,1/16W,CHIP,CA
     1 EN_P3V3 @SCM_LIB.SCM(SCH_1):EN_P3V3    I97 @SCM_LIB.SCM(SCH_1):PAGE52
     2 PWRGD_EN_P3V3_R @SCM_LIB.SCM(SCH_1):PWRGD_EN_P3V3_R    I97 @SCM_LIB.SCM(SCH_1):PAGE52

R382 Q_RES_0402LF-0,5%,1/16W,CHIP,CA
     1 PWRGD_P3V3_AUX @SCM_LIB.SCM(SCH_1):PWRGD_P3V3_AUX    I65 @SCM_LIB.SCM(SCH_1):PAGE53
     2 PWRGD_P3V3_AUX_R2 @SCM_LIB.SCM(SCH_1):PWRGD_P3V3_AUX_R2    I65 @SCM_LIB.SCM(SCH_1):PAGE53

R383 Q_RES_0402LF-10K,1%,1/16W,CHIPA
     1 P3V3_AUX @SCM_LIB.SCM(SCH_1):P3V3_AUX    I42 @SCM_LIB.SCM(SCH_1):PAGE28
     2 USB_OC0_REAR_N @SCM_LIB.SCM(SCH_1):USB_OC0_REAR_N    I42 @SCM_LIB.SCM(SCH_1):PAGE28

R384 Q_RES_0402LF-100,1%,1/16W,CHIPA
     1 USB_OC0_REAR_N @SCM_LIB.SCM(SCH_1):USB_OC0_REAR_N   I185 @SCM_LIB.SCM(SCH_1):PAGE28
     2 USB_OC0_REAR_R_N @SCM_LIB.SCM(SCH_1):USB_OC0_REAR_R_N   I185 @SCM_LIB.SCM(SCH_1):PAGE28

R385 Q_RES_0402LF-0,5%,1/16W,CHIP,CA
     1 USB_FPNL_DN @SCM_LIB.SCM(SCH_1):USB_FPNL_DN    I96 @SCM_LIB.SCM(SCH_1):PAGE29
     2 USB2_01_F_DN @SCM_LIB.SCM(SCH_1):USB2_01_F_DN    I96 @SCM_LIB.SCM(SCH_1):PAGE29

R386 Q_RES_0402LF-0,5%,1/16W,CHIP,CA
     1 USB_FPNL_DP @SCM_LIB.SCM(SCH_1):USB_FPNL_DP   I101 @SCM_LIB.SCM(SCH_1):PAGE29
     2 USB2_01_F_DP @SCM_LIB.SCM(SCH_1):USB2_01_F_DP   I101 @SCM_LIB.SCM(SCH_1):PAGE29

R387 Q_RES_0402LF-100K,1%,1/16W,CHIA
     1    GND @SCM_LIB.SCM(SCH_1):GND   I508 @SCM_LIB.SCM(SCH_1):PAGE12
     2 DP_BMC_HPD_3V3_BUF @SCM_LIB.SCM(SCH_1):DP_BMC_HPD_3V3_BUF   I508 @SCM_LIB.SCM(SCH_1):PAGE12

R388 Q_RES_0402LF-33.2,1%,1/16W,CHIA
     1 RST_SRST_PLD_BMC_R_N @SCM_LIB.SCM(SCH_1):RST_SRST_PLD_BMC_R_N    I92 @SCM_LIB.SCM(SCH_1):PAGE22
     2 RST_SRST_PLD_BMC_R1_N @SCM_LIB.SCM(SCH_1):RST_SRST_PLD_BMC_R1_N    I92 @SCM_LIB.SCM(SCH_1):PAGE22

R389 Q_RES_0402LF-316,1%,1/16W,CHIPA
     1 LED_D21_R1 @SCM_LIB.SCM(SCH_1):LED_D21_R1   I225 @SCM_LIB.SCM(SCH_1):PAGE50
     2 P12V_AUX @SCM_LIB.SCM(SCH_1):P12V_AUX   I225 @SCM_LIB.SCM(SCH_1):PAGE50

R390 Q_RES_0402LF-33.2,1%,1/16W,CHIA
     1 FM_ID_LED @SCM_LIB.SCM(SCH_1):FM_ID_LED    I92 @SCM_LIB.SCM(SCH_1):PAGE49
     2 FM_ID_R_LED @SCM_LIB.SCM(SCH_1):FM_ID_R_LED    I92 @SCM_LIB.SCM(SCH_1):PAGE49

R391 Q_RES_0402LF-8.2K,5%,1/16W,EMPA
     1 P3V3_AUX @SCM_LIB.SCM(SCH_1):P3V3_AUX   I235 @SCM_LIB.SCM(SCH_1):PAGE50
     2 REAR_AC_PWR_BTN_N @SCM_LIB.SCM(SCH_1):REAR_AC_PWR_BTN_N   I235 @SCM_LIB.SCM(SCH_1):PAGE50

R392 Q_RES_0402LF-0,5%,1/16W,CHIP,CA
     1 RMII_OCP_RCLKI_ISO @SCM_LIB.SCM(SCH_1):RMII_OCP_RCLKI_ISO   I447 @SCM_LIB.SCM(SCH_1):PAGE13
     2 RMII_OCP_RCLKI_R_ISO @SCM_LIB.SCM(SCH_1):RMII_OCP_RCLKI_R_ISO   I447 @SCM_LIB.SCM(SCH_1):PAGE13

R393 Q_RES_0402LF-0,5%,1/16W,CHIP,CA
     1 EN_P1V8 @SCM_LIB.SCM(SCH_1):EN_P1V8   I102 @SCM_LIB.SCM(SCH_1):PAGE54
     2 EN_P1V8_R @SCM_LIB.SCM(SCH_1):EN_P1V8_R   I102 @SCM_LIB.SCM(SCH_1):PAGE54

R394 Q_RES_0402LF-33.2,1%,1/16W,CHIA
     1 SMB_BMC_MM2_R_SDA @SCM_LIB.SCM(SCH_1):SMB_BMC_MM2_R_SDA   I314 @SCM_LIB.SCM(SCH_1):PAGE12
     2 SMB_BMC_MM2_SDA @SCM_LIB.SCM(SCH_1):SMB_BMC_MM2_SDA   I314 @SCM_LIB.SCM(SCH_1):PAGE12

R395 Q_RES_0402LF-0,5%,1/16W,CHIP,CA
     1 PWRGD_P1V0_AUX_DELAY_R @SCM_LIB.SCM(SCH_1):PWRGD_P1V0_AUX_DELAY_R   I448 @SCM_LIB.SCM(SCH_1):PAGE13
     2 PWRGD_P1V0_AUX_DELAY @SCM_LIB.SCM(SCH_1):PWRGD_P1V0_AUX_DELAY   I448 @SCM_LIB.SCM(SCH_1):PAGE13

R396 Q_RES_0402LF-100K,1%,1/16W,CHIA
     1 P3V3_AUX @SCM_LIB.SCM(SCH_1):P3V3_AUX    I80 @SCM_LIB.SCM(SCH_1):PAGE31
     2 UART_BIC_GF_RXD @SCM_LIB.SCM(SCH_1):UART_BIC_GF_RXD    I80 @SCM_LIB.SCM(SCH_1):PAGE31

R397 Q_RES_0402LF-0,5%,1/16W,CHIP,CA
     1 JTAG_SCM_PLD_R_JTAGEN @SCM_LIB.SCM(SCH_1):JTAG_SCM_PLD_R_JTAGEN   I167 @SCM_LIB.SCM(SCH_1):PAGE34
     2 JTAG_SCM_PLD_JTAGEN @SCM_LIB.SCM(SCH_1):JTAG_SCM_PLD_JTAGEN   I167 @SCM_LIB.SCM(SCH_1):PAGE34

R398 Q_RES_0402LF-0,5%,1/16W,CHIP,CA
     1 JTAG_1_BMC_TDO @SCM_LIB.SCM(SCH_1):JTAG_1_BMC_TDO   I351 @SCM_LIB.SCM(SCH_1):PAGE15
     2 JTAG_1_BMC_TDO_R @SCM_LIB.SCM(SCH_1):JTAG_1_BMC_TDO_R   I351 @SCM_LIB.SCM(SCH_1):PAGE15

R399 Q_RES_0402LF-0,5%,1/16W,CHIP,CA
     1 EN_P1V0_AUX @SCM_LIB.SCM(SCH_1):EN_P1V0_AUX    I55 @SCM_LIB.SCM(SCH_1):PAGE56
     2 EN_P1V0_AUX_R @SCM_LIB.SCM(SCH_1):EN_P1V0_AUX_R    I55 @SCM_LIB.SCM(SCH_1):PAGE56

R400 Q_RES_0402LF-4.7K,1%,1/16W,EMPA
     1 P3V3_AUX @SCM_LIB.SCM(SCH_1):P3V3_AUX   I454 @SCM_LIB.SCM(SCH_1):PAGE12
     2 FM_THERMTRIP_DLY_LVC1_R_N @SCM_LIB.SCM(SCH_1):FM_THERMTRIP_DLY_LVC1_R_N   I454 @SCM_LIB.SCM(SCH_1):PAGE12

R401 Q_RES_0402LF-33.2,1%,1/16W,CHIA
     1 PU_BMC_FWSPIABR_N @SCM_LIB.SCM(SCH_1):PU_BMC_FWSPIABR_N   I374 @SCM_LIB.SCM(SCH_1):PAGE13
     2 PU_BMC_FWSPIABR_N_R @SCM_LIB.SCM(SCH_1):PU_BMC_FWSPIABR_N_R   I374 @SCM_LIB.SCM(SCH_1):PAGE13

R402 Q_RES_0402LF-33.2,1%,1/16W,CHIA
     1 PU_FWSPIWP_N @SCM_LIB.SCM(SCH_1):PU_FWSPIWP_N   I373 @SCM_LIB.SCM(SCH_1):PAGE13
     2 PU_FWSPIWP_N_R @SCM_LIB.SCM(SCH_1):PU_FWSPIWP_N_R   I373 @SCM_LIB.SCM(SCH_1):PAGE13

R403 Q_RES_0402LF-10K,1%,1/16W,CHIPA
     1 P3V3_AUX @SCM_LIB.SCM(SCH_1):P3V3_AUX    I68 @SCM_LIB.SCM(SCH_1):PAGE53
     2 PWRGD_P2V5_AUX_R @SCM_LIB.SCM(SCH_1):PWRGD_P2V5_AUX_R    I68 @SCM_LIB.SCM(SCH_1):PAGE53

R404 Q_RES_0402LF-10K,1%,1/16W,CHIPA
     1 P3V3_AUX @SCM_LIB.SCM(SCH_1):P3V3_AUX   I166 @SCM_LIB.SCM(SCH_1):PAGE21
     2 BSM_PRSNT_N @SCM_LIB.SCM(SCH_1):BSM_PRSNT_N   I166 @SCM_LIB.SCM(SCH_1):PAGE21

R405 Q_RES_0402LF-33.2,1%,1/16W,CHIA
     1 PD_BIOS_MUX_EN_R_N @SCM_LIB.SCM(SCH_1):PD_BIOS_MUX_EN_R_N   I430 @SCM_LIB.SCM(SCH_1):PAGE13
     2 PD_BIOS_MUX_EN_N @SCM_LIB.SCM(SCH_1):PD_BIOS_MUX_EN_N   I430 @SCM_LIB.SCM(SCH_1):PAGE13

R406 Q_RES_0402LF-10K,1%,1/16W,CHIPA
     1 P3V3_AUX @SCM_LIB.SCM(SCH_1):P3V3_AUX   I108 @SCM_LIB.SCM(SCH_1):PAGE54
     2 PWRGD_P1V8_AUX_R @SCM_LIB.SCM(SCH_1):PWRGD_P1V8_AUX_R   I108 @SCM_LIB.SCM(SCH_1):PAGE54

R407 Q_RES_0402LF-33.2,1%,1/16W,CHIA
     1 FM_BMC_SUSACK_R1_N @SCM_LIB.SCM(SCH_1):FM_BMC_SUSACK_R1_N   I349 @SCM_LIB.SCM(SCH_1):PAGE13
     2 FM_BMC_SUSACK_N @SCM_LIB.SCM(SCH_1):FM_BMC_SUSACK_N   I349 @SCM_LIB.SCM(SCH_1):PAGE13

R408 Q_RES_0402LF-4.7K,1%,1/16W,EMPB
     1 P3V3_AUX @SCM_LIB.SCM(SCH_1):P3V3_AUX   I139 @SCM_LIB.SCM(SCH_1):PAGE46
     2 SPI_BMC_TPM_CLK @SCM_LIB.SCM(SCH_1):SPI_BMC_TPM_CLK   I139 @SCM_LIB.SCM(SCH_1):PAGE46

R409 Q_RES_0402LF-49.9,1%,1/16W,CHIA
     1 SMB_TMP421_BMC_MM2_SDA @SCM_LIB.SCM(SCH_1):SMB_TMP421_BMC_MM2_SDA    I57 @SCM_LIB.SCM(SCH_1):PAGE26
     2 SMB_BMC_MM2_SDA @SCM_LIB.SCM(SCH_1):SMB_BMC_MM2_SDA    I57 @SCM_LIB.SCM(SCH_1):PAGE26

R410 Q_RES_0402LF-49.9,1%,1/16W,CHIA
     1 SMB_TMP421_BMC_MM2_SCL @SCM_LIB.SCM(SCH_1):SMB_TMP421_BMC_MM2_SCL    I56 @SCM_LIB.SCM(SCH_1):PAGE26
     2 SMB_BMC_MM2_SCL @SCM_LIB.SCM(SCH_1):SMB_BMC_MM2_SCL    I56 @SCM_LIB.SCM(SCH_1):PAGE26

R411 Q_RES_0402LF-100,1%,1/16W,CHIPA
     1 FRU_E0 @SCM_LIB.SCM(SCH_1):FRU_E0     I6 @SCM_LIB.SCM(SCH_1):PAGE26
     2    GND @SCM_LIB.SCM(SCH_1):GND     I6 @SCM_LIB.SCM(SCH_1):PAGE26

R412 Q_RES_0402LF-100,1%,1/16W,CHIPA
     1 FRU_E1 @SCM_LIB.SCM(SCH_1):FRU_E1     I8 @SCM_LIB.SCM(SCH_1):PAGE26
     2    GND @SCM_LIB.SCM(SCH_1):GND     I8 @SCM_LIB.SCM(SCH_1):PAGE26

R413 Q_RES_0402LF-100,1%,1/16W,CHIPA
     1 FRU_E2 @SCM_LIB.SCM(SCH_1):FRU_E2    I12 @SCM_LIB.SCM(SCH_1):PAGE26
     2    GND @SCM_LIB.SCM(SCH_1):GND    I12 @SCM_LIB.SCM(SCH_1):PAGE26

R414 Q_RES_0402LF-4.7K,1%,1/16W,EMPB
     1 P3V3_AUX @SCM_LIB.SCM(SCH_1):P3V3_AUX   I140 @SCM_LIB.SCM(SCH_1):PAGE46
     2 SPI_BMC_TPM_MISO @SCM_LIB.SCM(SCH_1):SPI_BMC_TPM_MISO   I140 @SCM_LIB.SCM(SCH_1):PAGE46

R415 Q_RES_0402LF-2.2,1%,1/16W,CHIPA
     1 SW_P3V3_AUX_BST_R @SCM_LIB.SCM(SCH_1):SW_P3V3_AUX_BST_R   I146 @SCM_LIB.SCM(SCH_1):PAGE52
     2 SW_P3V3_AUX_BST @SCM_LIB.SCM(SCH_1):SW_P3V3_AUX_BST   I146 @SCM_LIB.SCM(SCH_1):PAGE52

R416 Q_RES_0402LF-4.7K,1%,1/16W,CHIA
     1 P3V3_AUX @SCM_LIB.SCM(SCH_1):P3V3_AUX    I41 @SCM_LIB.SCM(SCH_1):PAGE26
     2 TMC75_A0 @SCM_LIB.SCM(SCH_1):TMC75_A0    I41 @SCM_LIB.SCM(SCH_1):PAGE26

R417 Q_RES_0402LF-1K,1%,1/16W,EMPTYA
     1 TMC75_A0 @SCM_LIB.SCM(SCH_1):TMC75_A0    I39 @SCM_LIB.SCM(SCH_1):PAGE26
     2    GND @SCM_LIB.SCM(SCH_1):GND    I39 @SCM_LIB.SCM(SCH_1):PAGE26

R418 Q_RES_0402LF-4.7K,1%,1/16W,EMPA
     1 P3V3_AUX @SCM_LIB.SCM(SCH_1):P3V3_AUX    I40 @SCM_LIB.SCM(SCH_1):PAGE26
     2 TMC75_A2 @SCM_LIB.SCM(SCH_1):TMC75_A2    I40 @SCM_LIB.SCM(SCH_1):PAGE26

R419 Q_RES_0402LF-1K,1%,1/16W,CHIP,A
     1 TMC75_A2 @SCM_LIB.SCM(SCH_1):TMC75_A2    I37 @SCM_LIB.SCM(SCH_1):PAGE26
     2    GND @SCM_LIB.SCM(SCH_1):GND    I37 @SCM_LIB.SCM(SCH_1):PAGE26

R420 Q_RES_0402LF-150,1%,1/16W,CHIPA
     1 SMB_BMC_MM16_R2_SCL @SCM_LIB.SCM(SCH_1):SMB_BMC_MM16_R2_SCL    I69 @SCM_LIB.SCM(SCH_1):PAGE26
     2 SMB_BMC_MM16_SCL @SCM_LIB.SCM(SCH_1):SMB_BMC_MM16_SCL    I69 @SCM_LIB.SCM(SCH_1):PAGE26

R421 Q_RES_0402LF-33.2,1%,1/16W,CHIA
     1 SMB_BMC_MM16_R2_SDA @SCM_LIB.SCM(SCH_1):SMB_BMC_MM16_R2_SDA    I33 @SCM_LIB.SCM(SCH_1):PAGE26
     2 SMB_BMC_MM16_SDA @SCM_LIB.SCM(SCH_1):SMB_BMC_MM16_SDA    I33 @SCM_LIB.SCM(SCH_1):PAGE26

R422 Q_RES_0402LF-2.2K,5%,1/16W,CHIA
     1 P3V3_AUX @SCM_LIB.SCM(SCH_1):P3V3_AUX   I239 @SCM_LIB.SCM(SCH_1):PAGE27
     2 SMB_BMC_MM13_SCL @SCM_LIB.SCM(SCH_1):SMB_BMC_MM13_SCL   I239 @SCM_LIB.SCM(SCH_1):PAGE27

R423 Q_RES_0402LF-33.2,1%,1/16W,CHIA
     1 SMB_BMC_MM13_R_SCL @SCM_LIB.SCM(SCH_1):SMB_BMC_MM13_R_SCL   I252 @SCM_LIB.SCM(SCH_1):PAGE12
     2 SMB_BMC_MM13_SCL @SCM_LIB.SCM(SCH_1):SMB_BMC_MM13_SCL   I252 @SCM_LIB.SCM(SCH_1):PAGE12

R424 Q_RES_0402LF-33.2,1%,1/16W,CHIA
     1 SMB_BMC_MM13_R_SDA @SCM_LIB.SCM(SCH_1):SMB_BMC_MM13_R_SDA   I253 @SCM_LIB.SCM(SCH_1):PAGE12
     2 SMB_BMC_MM13_SDA @SCM_LIB.SCM(SCH_1):SMB_BMC_MM13_SDA   I253 @SCM_LIB.SCM(SCH_1):PAGE12

R425 Q_RES_0402LF-33.2,1%,1/16W,CHIA
     1 SMB_BMC_MM14_R_SCL @SCM_LIB.SCM(SCH_1):SMB_BMC_MM14_R_SCL   I254 @SCM_LIB.SCM(SCH_1):PAGE12
     2 SMB_BMC_MM14_SCL @SCM_LIB.SCM(SCH_1):SMB_BMC_MM14_SCL   I254 @SCM_LIB.SCM(SCH_1):PAGE12

R426 Q_RES_0402LF-33.2,1%,1/16W,CHIA
     1 SMB_BMC_MM14_R_SDA @SCM_LIB.SCM(SCH_1):SMB_BMC_MM14_R_SDA   I255 @SCM_LIB.SCM(SCH_1):PAGE12
     2 SMB_BMC_MM14_SDA @SCM_LIB.SCM(SCH_1):SMB_BMC_MM14_SDA   I255 @SCM_LIB.SCM(SCH_1):PAGE12

R427 Q_RES_0402LF-33.2,1%,1/16W,CHIA
     1 UART_BMC_1_RXD_R @SCM_LIB.SCM(SCH_1):UART_BMC_1_RXD_R   I198 @SCM_LIB.SCM(SCH_1):PAGE13
     2 UART_BMC_1_RXD @SCM_LIB.SCM(SCH_1):UART_BMC_1_RXD   I198 @SCM_LIB.SCM(SCH_1):PAGE13

R428 Q_RES_0402LF-2.2K,5%,1/16W,CHIA
     1 P3V3_AUX @SCM_LIB.SCM(SCH_1):P3V3_AUX   I240 @SCM_LIB.SCM(SCH_1):PAGE27
     2 SMB_BMC_MM13_SDA @SCM_LIB.SCM(SCH_1):SMB_BMC_MM13_SDA   I240 @SCM_LIB.SCM(SCH_1):PAGE27

R429 Q_RES_0402LF-2.2K,5%,1/16W,CHIA
     1 P3V3_AUX @SCM_LIB.SCM(SCH_1):P3V3_AUX   I241 @SCM_LIB.SCM(SCH_1):PAGE27
     2 SMB_BMC_MM14_SCL @SCM_LIB.SCM(SCH_1):SMB_BMC_MM14_SCL   I241 @SCM_LIB.SCM(SCH_1):PAGE27

R430 Q_RES_0402LF-4.7K,1%,1/16W,CHIA
     1 P3V3_AUX @SCM_LIB.SCM(SCH_1):P3V3_AUX   I188 @SCM_LIB.SCM(SCH_1):PAGE27
     2 FM_BMC_ONCTL_R_N @SCM_LIB.SCM(SCH_1):FM_BMC_ONCTL_R_N   I188 @SCM_LIB.SCM(SCH_1):PAGE27

R431 Q_RES_0402LF-100,1%,1/16W,EMPTA
     1 FM_BMC_DISABLE @SCM_LIB.SCM(SCH_1):FM_BMC_DISABLE    I56 @SCM_LIB.SCM(SCH_1):PAGE48
     2    GND @SCM_LIB.SCM(SCH_1):GND    I56 @SCM_LIB.SCM(SCH_1):PAGE48

R432 Q_RES_0402LF-0,5%,1/16W,CHIP,CA
     1 FM_PWR_R_BTN @SCM_LIB.SCM(SCH_1):FM_PWR_R_BTN   I100 @SCM_LIB.SCM(SCH_1):PAGE35
     2 FM_PWR_BTN @SCM_LIB.SCM(SCH_1):FM_PWR_BTN   I100 @SCM_LIB.SCM(SCH_1):PAGE35

R433 Q_RES_0402LF-33.2,1%,1/16W,CHIA
     1 SGPIO_DI_1 @SCM_LIB.SCM(SCH_1):SGPIO_DI_1   I382 @SCM_LIB.SCM(SCH_1):PAGE12
     2 SGPIO_BMC_M1_DI @SCM_LIB.SCM(SCH_1):SGPIO_BMC_M1_DI   I382 @SCM_LIB.SCM(SCH_1):PAGE12

R434 Q_RES_0402LF-33.2,1%,1/16W,CHIA
     1 SGPIO_CLK_PLD_0 @SCM_LIB.SCM(SCH_1):SGPIO_CLK_PLD_0   I160 @SCM_LIB.SCM(SCH_1):PAGE34
     2 SGPIO_CLK_0 @SCM_LIB.SCM(SCH_1):SGPIO_CLK_0   I160 @SCM_LIB.SCM(SCH_1):PAGE34

R435 Q_RES_0402LF-33.2,1%,1/16W,CHIA
     1 SGPIO_PLD_DO_0 @SCM_LIB.SCM(SCH_1):SGPIO_PLD_DO_0   I161 @SCM_LIB.SCM(SCH_1):PAGE34
     2 SGPIO_DO_0 @SCM_LIB.SCM(SCH_1):SGPIO_DO_0   I161 @SCM_LIB.SCM(SCH_1):PAGE34

R436 Q_RES_0402LF-33.2,1%,1/16W,CHIA
     1 SGPIO_PLD_LD_0 @SCM_LIB.SCM(SCH_1):SGPIO_PLD_LD_0   I162 @SCM_LIB.SCM(SCH_1):PAGE34
     2 SGPIO_LD_0 @SCM_LIB.SCM(SCH_1):SGPIO_LD_0   I162 @SCM_LIB.SCM(SCH_1):PAGE34

R437 Q_RES_0402LF-33.2,1%,1/16W,CHIA
     1 SGPIO_PLD_DI_0 @SCM_LIB.SCM(SCH_1):SGPIO_PLD_DI_0   I163 @SCM_LIB.SCM(SCH_1):PAGE34
     2 SGPIO_DI_0 @SCM_LIB.SCM(SCH_1):SGPIO_DI_0   I163 @SCM_LIB.SCM(SCH_1):PAGE34

R438 Q_RES_0402LF-2.2K,5%,1/16W,CHIA
     1 P3V3_AUX @SCM_LIB.SCM(SCH_1):P3V3_AUX   I242 @SCM_LIB.SCM(SCH_1):PAGE27
     2 SMB_BMC_MM14_SDA @SCM_LIB.SCM(SCH_1):SMB_BMC_MM14_SDA   I242 @SCM_LIB.SCM(SCH_1):PAGE27

R439 Q_RES_0402LF-33.2,1%,1/16W,CHIA
     1 FM_PECI_SEL_N @SCM_LIB.SCM(SCH_1):FM_PECI_SEL_N   I227 @SCM_LIB.SCM(SCH_1):PAGE13
     2 FM_PECI_SEL_R_N @SCM_LIB.SCM(SCH_1):FM_PECI_SEL_R_N   I227 @SCM_LIB.SCM(SCH_1):PAGE13

R440 Q_RES_0402LF-49.9,1%,1/16W,EMPA
     1 USB_HOST_BMC_A_DP @SCM_LIB.SCM(SCH_1):USB_HOST_BMC_A_DP   I354 @SCM_LIB.SCM(SCH_1):PAGE15
     2    GND @SCM_LIB.SCM(SCH_1):GND   I354 @SCM_LIB.SCM(SCH_1):PAGE15

R441 Q_RES_0402LF-49.9,1%,1/16W,EMPA
     1 USB_HOST_BMC_A_DN @SCM_LIB.SCM(SCH_1):USB_HOST_BMC_A_DN   I353 @SCM_LIB.SCM(SCH_1):PAGE15
     2    GND @SCM_LIB.SCM(SCH_1):GND   I353 @SCM_LIB.SCM(SCH_1):PAGE15

R442 Q_RES_0402LF-33.2,1%,1/16W,CHIA
     1 SMB_BMC_ALERT3_N @SCM_LIB.SCM(SCH_1):SMB_BMC_ALERT3_N   I301 @SCM_LIB.SCM(SCH_1):PAGE13
     2 SMB_BMC_ALERT3_R_N @SCM_LIB.SCM(SCH_1):SMB_BMC_ALERT3_R_N   I301 @SCM_LIB.SCM(SCH_1):PAGE13

R443 Q_RES_0402LF-33.2,1%,1/16W,CHIA
     1 SMB_BMC_ALERT4_N @SCM_LIB.SCM(SCH_1):SMB_BMC_ALERT4_N   I300 @SCM_LIB.SCM(SCH_1):PAGE13
     2 SMB_BMC_ALERT4_R_N @SCM_LIB.SCM(SCH_1):SMB_BMC_ALERT4_R_N   I300 @SCM_LIB.SCM(SCH_1):PAGE13

R444 Q_RES_0402LF-33.2,1%,1/16W,CHIA
     1 FM_ESPI_PLD_EN @SCM_LIB.SCM(SCH_1):FM_ESPI_PLD_EN   I306 @SCM_LIB.SCM(SCH_1):PAGE13
     2 FM_ESPI_PLD_R1_EN @SCM_LIB.SCM(SCH_1):FM_ESPI_PLD_R1_EN   I306 @SCM_LIB.SCM(SCH_1):PAGE13

R445 Q_RES_0402LF-33.2,1%,1/16W,CHIA
     1 FM_BMC_SUSACK_N @SCM_LIB.SCM(SCH_1):FM_BMC_SUSACK_N    I81 @SCM_LIB.SCM(SCH_1):PAGE36
     2 FM_BMC_SUSACK_R2_N @SCM_LIB.SCM(SCH_1):FM_BMC_SUSACK_R2_N    I81 @SCM_LIB.SCM(SCH_1):PAGE36

R446 Q_RES_0402LF-4.7K,1%,1/16W,CHIA
     1 P3V3_AUX @SCM_LIB.SCM(SCH_1):P3V3_AUX   I299 @SCM_LIB.SCM(SCH_1):PAGE13
     2 FM_PECI_SEL_N @SCM_LIB.SCM(SCH_1):FM_PECI_SEL_N   I299 @SCM_LIB.SCM(SCH_1):PAGE13

R447 Q_RES_0402LF-0,5%,1/16W,CHIP,CA
     1 RST_EXTRST_R_N @SCM_LIB.SCM(SCH_1):RST_EXTRST_R_N   I168 @SCM_LIB.SCM(SCH_1):PAGE34
     2 RST_EXTRST_N @SCM_LIB.SCM(SCH_1):RST_EXTRST_N   I168 @SCM_LIB.SCM(SCH_1):PAGE34

R448 Q_RES_0402LF-33.2,1%,1/16W,CHIA
     1 SMB_BMC_ALERT9_N @SCM_LIB.SCM(SCH_1):SMB_BMC_ALERT9_N   I320 @SCM_LIB.SCM(SCH_1):PAGE15
     2 SMB_BMC_ALERT9_R_N @SCM_LIB.SCM(SCH_1):SMB_BMC_ALERT9_R_N   I320 @SCM_LIB.SCM(SCH_1):PAGE15

R449 Q_RES_0402LF-33.2,1%,1/16W,CHIA
     1 SMB_BMC_ALERT10_N @SCM_LIB.SCM(SCH_1):SMB_BMC_ALERT10_N   I321 @SCM_LIB.SCM(SCH_1):PAGE15
     2 SMB_BMC_ALERT10_R_N @SCM_LIB.SCM(SCH_1):SMB_BMC_ALERT10_R_N   I321 @SCM_LIB.SCM(SCH_1):PAGE15

R450 Q_RES_0402LF-0,5%,1/16W,CHIP,CA
     1 RST_BMC_SELF_HW @SCM_LIB.SCM(SCH_1):RST_BMC_SELF_HW   I101 @SCM_LIB.SCM(SCH_1):PAGE22
     2 RST_BMC_SELF_HW_R3 @SCM_LIB.SCM(SCH_1):RST_BMC_SELF_HW_R3   I101 @SCM_LIB.SCM(SCH_1):PAGE22

R451 Q_RES_0402LF-0,5%,1/16W,CHIP,CA
     1 PWRGD_P1V0_AUX_DELAY @SCM_LIB.SCM(SCH_1):PWRGD_P1V0_AUX_DELAY    I74 @SCM_LIB.SCM(SCH_1):PAGE22
     2 PWRGD_P1V0_AUX_DELAY_R1 @SCM_LIB.SCM(SCH_1):PWRGD_P1V0_AUX_DELAY_R1    I74 @SCM_LIB.SCM(SCH_1):PAGE22

R452 Q_RES_0402LF-4.7K,1%,1/16W,CHIA
     1 P3V3_AUX @SCM_LIB.SCM(SCH_1):P3V3_AUX   I339 @SCM_LIB.SCM(SCH_1):PAGE13
     2 RST_WDTRST_PLD_N @SCM_LIB.SCM(SCH_1):RST_WDTRST_PLD_N   I339 @SCM_LIB.SCM(SCH_1):PAGE13

R453 Q_RES_0402LF-0,5%,1/16W,CHIP,CA
     1 SMB_BMC_ALERT3_N @SCM_LIB.SCM(SCH_1):SMB_BMC_ALERT3_N     I2 @SCM_LIB.SCM(SCH_1):PAGE35
     2 SMB_BMC_ALERT3_R1_N @SCM_LIB.SCM(SCH_1):SMB_BMC_ALERT3_R1_N     I2 @SCM_LIB.SCM(SCH_1):PAGE35

R454 Q_RES_0402LF-0,5%,1/16W,CHIP,CA
     1 SMB_BMC_ALERT4_N @SCM_LIB.SCM(SCH_1):SMB_BMC_ALERT4_N     I3 @SCM_LIB.SCM(SCH_1):PAGE35
     2 SMB_BMC_ALERT4_R1_N @SCM_LIB.SCM(SCH_1):SMB_BMC_ALERT4_R1_N     I3 @SCM_LIB.SCM(SCH_1):PAGE35

R455 Q_RES_0402LF-33.2,1%,1/16W,CHIA
     1 SMB_BMC_MM2_SCL @SCM_LIB.SCM(SCH_1):SMB_BMC_MM2_SCL   I557 @SCM_LIB.SCM(SCH_1):PAGE10
     2 SMB_BMC_MM2_SCL_R1 @SCM_LIB.SCM(SCH_1):SMB_BMC_MM2_SCL_R1   I557 @SCM_LIB.SCM(SCH_1):PAGE10

R456 Q_RES_0402LF-0,5%,1/16W,CHIP,CA
     1 SMB_BMC_ALERT9_N @SCM_LIB.SCM(SCH_1):SMB_BMC_ALERT9_N     I4 @SCM_LIB.SCM(SCH_1):PAGE35
     2 SMB_BMC_ALERT9_R1_N @SCM_LIB.SCM(SCH_1):SMB_BMC_ALERT9_R1_N     I4 @SCM_LIB.SCM(SCH_1):PAGE35

R457 Q_RES_0402LF-0,5%,1/16W,CHIP,CA
     1 SMB_BMC_ALERT10_N @SCM_LIB.SCM(SCH_1):SMB_BMC_ALERT10_N     I5 @SCM_LIB.SCM(SCH_1):PAGE35
     2 SMB_BMC_ALERT10_R1_N @SCM_LIB.SCM(SCH_1):SMB_BMC_ALERT10_R1_N     I5 @SCM_LIB.SCM(SCH_1):PAGE35

R458 Q_RES_0402LF-33.2,1%,1/16W,CHIA
     1 FM_DEBUG_PORT_PRSNT_R1_N @SCM_LIB.SCM(SCH_1):FM_DEBUG_PORT_PRSNT_R1_N   I407 @SCM_LIB.SCM(SCH_1):PAGE13
     2 FM_DEBUG_PORT_PRSNT_N @SCM_LIB.SCM(SCH_1):FM_DEBUG_PORT_PRSNT_N   I407 @SCM_LIB.SCM(SCH_1):PAGE13

R459 Q_RES_0402LF-33.2,1%,1/16W,CHIA
     1 BSM_PRSNT_R_N @SCM_LIB.SCM(SCH_1):BSM_PRSNT_R_N   I159 @SCM_LIB.SCM(SCH_1):PAGE34
     2 BSM_PRSNT_R1_N @SCM_LIB.SCM(SCH_1):BSM_PRSNT_R1_N   I159 @SCM_LIB.SCM(SCH_1):PAGE34

R460 Q_RES_0402LF-33.2,1%,1/16W,CHIA
     1 SPI_BMC_TPM_CS2_R_N @SCM_LIB.SCM(SCH_1):SPI_BMC_TPM_CS2_R_N   I312 @SCM_LIB.SCM(SCH_1):PAGE13
     2 SPI_BMC_TPM_CS2_R1_N @SCM_LIB.SCM(SCH_1):SPI_BMC_TPM_CS2_R1_N   I312 @SCM_LIB.SCM(SCH_1):PAGE13

R461 Q_RES_0402LF-33.2,1%,1/16W,CHIA
     1 BMC_ID_BEEP_SEL @SCM_LIB.SCM(SCH_1):BMC_ID_BEEP_SEL   I365 @SCM_LIB.SCM(SCH_1):PAGE13
     2 BMC_ID_BEEP_SEL_R1 @SCM_LIB.SCM(SCH_1):BMC_ID_BEEP_SEL_R1   I365 @SCM_LIB.SCM(SCH_1):PAGE13

R462 Q_RES_0402LF-4.7K,1%,1/16W,CHIA
     1 P3V3_AUX @SCM_LIB.SCM(SCH_1):P3V3_AUX   I391 @SCM_LIB.SCM(SCH_1):PAGE15
     2 SYS_BMC_PWRBTN_R1_N @SCM_LIB.SCM(SCH_1):SYS_BMC_PWRBTN_R1_N   I391 @SCM_LIB.SCM(SCH_1):PAGE15

R463 Q_RES_0402LF-0,5%,1/16W,EMPTY,A
     1 AC_PWR_BTN_R1_N @SCM_LIB.SCM(SCH_1):AC_PWR_BTN_R1_N   I131 @SCM_LIB.SCM(SCH_1):PAGE35
     2 AC_PWR_BTN_R2_N @SCM_LIB.SCM(SCH_1):AC_PWR_BTN_R2_N   I131 @SCM_LIB.SCM(SCH_1):PAGE35

R464 Q_RES_0402LF-10K,1%,1/16W,CHIPA
     1 P3V3_AUX @SCM_LIB.SCM(SCH_1):P3V3_AUX    I75 @SCM_LIB.SCM(SCH_1):PAGE46
     2 FM_TPM_PRSNT_0_N @SCM_LIB.SCM(SCH_1):FM_TPM_PRSNT_0_N    I75 @SCM_LIB.SCM(SCH_1):PAGE46

R465 Q_RES_0402LF-33.2,1%,1/16W,CHIA
     1 FM_FLASH_LATCH_N_R1 @SCM_LIB.SCM(SCH_1):FM_FLASH_LATCH_N_R1   I432 @SCM_LIB.SCM(SCH_1):PAGE13
     2 FM_FLASH_LATCH_N @SCM_LIB.SCM(SCH_1):FM_FLASH_LATCH_N   I432 @SCM_LIB.SCM(SCH_1):PAGE13

R466 Q_RES_0402LF-33.2,1%,1/16W,CHIA
     1 FLASH_WP_STATUS_R1 @SCM_LIB.SCM(SCH_1):FLASH_WP_STATUS_R1   I431 @SCM_LIB.SCM(SCH_1):PAGE13
     2 FLASH_WP_STATUS @SCM_LIB.SCM(SCH_1):FLASH_WP_STATUS   I431 @SCM_LIB.SCM(SCH_1):PAGE13

R467 Q_RES_0402LF-2K,1%,1/16W,CHIP,A
     1 PD_BIOS_MUX_EN_N @SCM_LIB.SCM(SCH_1):PD_BIOS_MUX_EN_N   I313 @SCM_LIB.SCM(SCH_1):PAGE44
     2    GND @SCM_LIB.SCM(SCH_1):GND   I313 @SCM_LIB.SCM(SCH_1):PAGE44

R468 Q_RES_0402LF-90.9,1%,1/16W,CHIA
     1 SPI_BMC_TPM_CLK_R1 @SCM_LIB.SCM(SCH_1):SPI_BMC_TPM_CLK_R1   I449 @SCM_LIB.SCM(SCH_1):PAGE13
     2 SPI_BMC_TPM_CLK @SCM_LIB.SCM(SCH_1):SPI_BMC_TPM_CLK   I449 @SCM_LIB.SCM(SCH_1):PAGE13

R469 Q_RES_0402LF-33.2,1%,1/16W,CHIA
     1 SPI_BMC_TPM_MISO_R1 @SCM_LIB.SCM(SCH_1):SPI_BMC_TPM_MISO_R1   I319 @SCM_LIB.SCM(SCH_1):PAGE13
     2 SPI_BMC_TPM_MISO @SCM_LIB.SCM(SCH_1):SPI_BMC_TPM_MISO   I319 @SCM_LIB.SCM(SCH_1):PAGE13

R470 Q_RES_0402LF-0,5%,1/16W,EMPTY,A
     1 REAR_AC_PWR_BTN @SCM_LIB.SCM(SCH_1):REAR_AC_PWR_BTN   I241 @SCM_LIB.SCM(SCH_1):PAGE50
     2 REAR_AC_PWR_BTN_N @SCM_LIB.SCM(SCH_1):REAR_AC_PWR_BTN_N   I241 @SCM_LIB.SCM(SCH_1):PAGE50

R471 Q_RES_0402LF-0,5%,1/16W,CHIP,CA
     1 REAR_AC_PWR_BTN @SCM_LIB.SCM(SCH_1):REAR_AC_PWR_BTN   I242 @SCM_LIB.SCM(SCH_1):PAGE50
     2 AC_PWR_BTN_N @SCM_LIB.SCM(SCH_1):AC_PWR_BTN_N   I242 @SCM_LIB.SCM(SCH_1):PAGE50

R472 Q_RES_0402LF-4.7K,1%,1/16W,EMPA
     1 P3V3_AUX @SCM_LIB.SCM(SCH_1):P3V3_AUX   I136 @SCM_LIB.SCM(SCH_1):PAGE35
     2 AC_PWR_BTN_R1_N @SCM_LIB.SCM(SCH_1):AC_PWR_BTN_R1_N   I136 @SCM_LIB.SCM(SCH_1):PAGE35

R479 Q_RES_0402LF-33.2,1%,1/16W,CHIA
     1 FM_P12V_HSC_ENABLE @SCM_LIB.SCM(SCH_1):FM_P12V_HSC_ENABLE   I330 @SCM_LIB.SCM(SCH_1):PAGE15
     2 FM_P12V_HSC_ENABLE_R1 @SCM_LIB.SCM(SCH_1):FM_P12V_HSC_ENABLE_R1   I330 @SCM_LIB.SCM(SCH_1):PAGE15

R481 Q_RES_0402LF-33.2,1%,1/16W,CHIA
     1 SPI_PCH_MUXED_CLK @SCM_LIB.SCM(SCH_1):SPI_PCH_MUXED_CLK    I24 @SCM_LIB.SCM(SCH_1):PAGE45
     2 SPI_PCH_CLK_FLASH_R1 @SCM_LIB.SCM(SCH_1):SPI_PCH_CLK_FLASH_R1    I24 @SCM_LIB.SCM(SCH_1):PAGE45

R482 Q_RES_0402LF-33.2,1%,1/16W,CHIA
     1 SPI_PCH_MUXED_IO0 @SCM_LIB.SCM(SCH_1):SPI_PCH_MUXED_IO0    I22 @SCM_LIB.SCM(SCH_1):PAGE45
     2 SPI_PCH_IO0_FLASH_R1 @SCM_LIB.SCM(SCH_1):SPI_PCH_IO0_FLASH_R1    I22 @SCM_LIB.SCM(SCH_1):PAGE45

R483 Q_RES_0402LF-33.2,1%,1/16W,CHIA
     1 SPI_PCH_MUXED_IO2 @SCM_LIB.SCM(SCH_1):SPI_PCH_MUXED_IO2    I23 @SCM_LIB.SCM(SCH_1):PAGE45
     2 SPI_PCH_IO2_FLASH_R1 @SCM_LIB.SCM(SCH_1):SPI_PCH_IO2_FLASH_R1    I23 @SCM_LIB.SCM(SCH_1):PAGE45

R484 Q_RES_0402LF-33.2,1%,1/16W,CHIA
     1 SPI_PCH_MUXED_IO1 @SCM_LIB.SCM(SCH_1):SPI_PCH_MUXED_IO1    I21 @SCM_LIB.SCM(SCH_1):PAGE45
     2 SPI_PCH_IO1_FLASH_R1 @SCM_LIB.SCM(SCH_1):SPI_PCH_IO1_FLASH_R1    I21 @SCM_LIB.SCM(SCH_1):PAGE45

R485 Q_RES_0402LF-33.2,1%,1/16W,CHIA
     1 SPI_PCH_MUXED_CS0_N @SCM_LIB.SCM(SCH_1):SPI_PCH_MUXED_CS0_N    I20 @SCM_LIB.SCM(SCH_1):PAGE45
     2 SPI_PCH_CS0_FLASH_R1_N @SCM_LIB.SCM(SCH_1):SPI_PCH_CS0_FLASH_R1_N    I20 @SCM_LIB.SCM(SCH_1):PAGE45

R486 Q_RES_0402LF-33.2,1%,1/16W,CHIA
     1 SPI_PCH_MUXED_IO3 @SCM_LIB.SCM(SCH_1):SPI_PCH_MUXED_IO3    I19 @SCM_LIB.SCM(SCH_1):PAGE45
     2 SPI_PCH_IO3_FLASH_R1 @SCM_LIB.SCM(SCH_1):SPI_PCH_IO3_FLASH_R1    I19 @SCM_LIB.SCM(SCH_1):PAGE45

R487 Q_RES_0402LF-4.7K,1%,1/16W,EMPA
     1 SPI_PCH_CS0_FLASH_R1_N @SCM_LIB.SCM(SCH_1):SPI_PCH_CS0_FLASH_R1_N    I51 @SCM_LIB.SCM(SCH_1):PAGE45
     2    GND @SCM_LIB.SCM(SCH_1):GND    I51 @SCM_LIB.SCM(SCH_1):PAGE45

R488 Q_RES_0402LF-4.7K,1%,1/16W,CHIA
     1 P3V3_AUX @SCM_LIB.SCM(SCH_1):P3V3_AUX    I33 @SCM_LIB.SCM(SCH_1):PAGE45
     2 SPI_PCH_IO2_FLASH_R1 @SCM_LIB.SCM(SCH_1):SPI_PCH_IO2_FLASH_R1    I33 @SCM_LIB.SCM(SCH_1):PAGE45

R489 Q_RES_0402LF-33.2,1%,1/16W,CHIA
     1 FM_SOL_UART_CH_SEL @SCM_LIB.SCM(SCH_1):FM_SOL_UART_CH_SEL   I326 @SCM_LIB.SCM(SCH_1):PAGE15
     2 FM_SOL_UART_CH_SEL_R1 @SCM_LIB.SCM(SCH_1):FM_SOL_UART_CH_SEL_R1   I326 @SCM_LIB.SCM(SCH_1):PAGE15

R490 Q_RES_0402LF-4.7K,1%,1/16W,CHIA
     1 P3V3_AUX @SCM_LIB.SCM(SCH_1):P3V3_AUX    I34 @SCM_LIB.SCM(SCH_1):PAGE45
     2 SPI_PCH_CS0_FLASH_R1_N @SCM_LIB.SCM(SCH_1):SPI_PCH_CS0_FLASH_R1_N    I34 @SCM_LIB.SCM(SCH_1):PAGE45

R491 Q_RES_0402LF-4.7K,1%,1/16W,EMPA
     1 P3V3_RGM @SCM_LIB.SCM(SCH_1):P3V3_RGM   I346 @SCM_LIB.SCM(SCH_1):PAGE15
     2 RST_BMC_SRST_N @SCM_LIB.SCM(SCH_1):RST_BMC_SRST_N   I346 @SCM_LIB.SCM(SCH_1):PAGE15

R492 Q_RES_0402LF-4.7K,1%,1/16W,CHIA
     1 P3V3_AUX @SCM_LIB.SCM(SCH_1):P3V3_AUX    I35 @SCM_LIB.SCM(SCH_1):PAGE45
     2 SPI_PCH_IO3_FLASH_R1 @SCM_LIB.SCM(SCH_1):SPI_PCH_IO3_FLASH_R1    I35 @SCM_LIB.SCM(SCH_1):PAGE45

R493 Q_RES_0402LF-150K,1%,1/16W,EMPA
     1 LPC_ESPI_SEL_N @SCM_LIB.SCM(SCH_1):LPC_ESPI_SEL_N   I284 @SCM_LIB.SCM(SCH_1):PAGE17
     2    GND @SCM_LIB.SCM(SCH_1):GND   I284 @SCM_LIB.SCM(SCH_1):PAGE17

R494 Q_RES_0402LF-33.2,1%,1/16W,CHIA
     1 RST_BMC_SELF_HW_R1 @SCM_LIB.SCM(SCH_1):RST_BMC_SELF_HW_R1   I335 @SCM_LIB.SCM(SCH_1):PAGE13
     2 RST_BMC_SELF_HW @SCM_LIB.SCM(SCH_1):RST_BMC_SELF_HW   I335 @SCM_LIB.SCM(SCH_1):PAGE13

R496 Q_RES_0402LF-4.7K,1%,1/16W,EMPA
     1 P3V3_AUX @SCM_LIB.SCM(SCH_1):P3V3_AUX    I48 @SCM_LIB.SCM(SCH_1):PAGE45
     2 RST_SPI_PCH_FLASH_R1_N @SCM_LIB.SCM(SCH_1):RST_SPI_PCH_FLASH_R1_N    I48 @SCM_LIB.SCM(SCH_1):PAGE45

R497 Q_RES_0402LF-10K,1%,1/16W,CHIPA
     1 P3V3_AUX @SCM_LIB.SCM(SCH_1):P3V3_AUX    I78 @SCM_LIB.SCM(SCH_1):PAGE46
     2 IRQ_PCH_TPM_SPI_N @SCM_LIB.SCM(SCH_1):IRQ_PCH_TPM_SPI_N    I78 @SCM_LIB.SCM(SCH_1):PAGE46

R498 Q_RES_0402LF-22,1%,1/16W,CHIP,A
     1 SPI_SYS_R_MOSI @SCM_LIB.SCM(SCH_1):SPI_SYS_R_MOSI   I137 @SCM_LIB.SCM(SCH_1):PAGE46
     2 SPI_SYS_R1_MOSI @SCM_LIB.SCM(SCH_1):SPI_SYS_R1_MOSI   I137 @SCM_LIB.SCM(SCH_1):PAGE46

R499 Q_RES_0402LF-22,1%,1/16W,CHIP,A
     1 SPI_SYS_R_MISO @SCM_LIB.SCM(SCH_1):SPI_SYS_R_MISO   I136 @SCM_LIB.SCM(SCH_1):PAGE46
     2 SPI_SYS_R1_MISO @SCM_LIB.SCM(SCH_1):SPI_SYS_R1_MISO   I136 @SCM_LIB.SCM(SCH_1):PAGE46

R500 Q_RES_0402LF-0,5%,1/16W,CHIP,CA
     1 SPI_TPM_CS_N_R @SCM_LIB.SCM(SCH_1):SPI_TPM_CS_N_R    I65 @SCM_LIB.SCM(SCH_1):PAGE46
     2 SPI_TPM_CS_R_N @SCM_LIB.SCM(SCH_1):SPI_TPM_CS_R_N    I65 @SCM_LIB.SCM(SCH_1):PAGE46

R501 Q_RES_0402LF-33.2,1%,1/16W,CHIA
     1 SPI_SYS_R1_CLK @SCM_LIB.SCM(SCH_1):SPI_SYS_R1_CLK    I58 @SCM_LIB.SCM(SCH_1):PAGE46
     2 SPI_SYS_R_CLK @SCM_LIB.SCM(SCH_1):SPI_SYS_R_CLK    I58 @SCM_LIB.SCM(SCH_1):PAGE46

R503 Q_RES_0402LF-0,5%,1/16W,CHIP,CA
     1 RST_PLTRST_TPM_N @SCM_LIB.SCM(SCH_1):RST_PLTRST_TPM_N    I60 @SCM_LIB.SCM(SCH_1):PAGE46
     2 RST_PLTRST_N @SCM_LIB.SCM(SCH_1):RST_PLTRST_N    I60 @SCM_LIB.SCM(SCH_1):PAGE46

R504 Q_RES_0402LF-8.2K,5%,1/16W,CHIA
     1 P3V3_AUX @SCM_LIB.SCM(SCH_1):P3V3_AUX    I82 @SCM_LIB.SCM(SCH_1):PAGE50
     2 REAR_ID_RST_BTN_N @SCM_LIB.SCM(SCH_1):REAR_ID_RST_BTN_N    I82 @SCM_LIB.SCM(SCH_1):PAGE50

R505 Q_RES_0402LF-0,5%,1/16W,CHIP,CA
     1 IRQ_PCH_TPM_SPI_N @SCM_LIB.SCM(SCH_1):IRQ_PCH_TPM_SPI_N    I74 @SCM_LIB.SCM(SCH_1):PAGE46
     2 IRQ_PCH_TPM_SPI_R_N @SCM_LIB.SCM(SCH_1):IRQ_PCH_TPM_SPI_R_N    I74 @SCM_LIB.SCM(SCH_1):PAGE46

R506 Q_RES_0402LF-100,1%,1/16W,EMPTA
     1 FM_BMC_DEBUG_SW_N @SCM_LIB.SCM(SCH_1):FM_BMC_DEBUG_SW_N    I53 @SCM_LIB.SCM(SCH_1):PAGE48
     2    GND @SCM_LIB.SCM(SCH_1):GND    I53 @SCM_LIB.SCM(SCH_1):PAGE48

R507 Q_RES_0402LF-100,1%,1/16W,EMPTA
     1 MB_JTAG_PLD_R_JTAGEN @SCM_LIB.SCM(SCH_1):MB_JTAG_PLD_R_JTAGEN    I52 @SCM_LIB.SCM(SCH_1):PAGE48
     2    GND @SCM_LIB.SCM(SCH_1):GND    I52 @SCM_LIB.SCM(SCH_1):PAGE48

R508 Q_RES_0402LF-10K,1%,1/16W,CHIPA
     1 P3V3_AUX @SCM_LIB.SCM(SCH_1):P3V3_AUX    I51 @SCM_LIB.SCM(SCH_1):PAGE48
     2 MB_JTAG_PLD_R_JTAGEN @SCM_LIB.SCM(SCH_1):MB_JTAG_PLD_R_JTAGEN    I51 @SCM_LIB.SCM(SCH_1):PAGE48

R509 Q_RES_0402LF-33.2,1%,1/16W,CHIA
     1 MB_JTAG_PLD_R_JTAGEN @SCM_LIB.SCM(SCH_1):MB_JTAG_PLD_R_JTAGEN    I50 @SCM_LIB.SCM(SCH_1):PAGE48
     2 JTAG_SCM_PLD_JTAGEN @SCM_LIB.SCM(SCH_1):JTAG_SCM_PLD_JTAGEN    I50 @SCM_LIB.SCM(SCH_1):PAGE48

R510 Q_RES_0402LF-33.2,1%,1/16W,CHIA
     1 JTAG_SCM_TCK @SCM_LIB.SCM(SCH_1):JTAG_SCM_TCK   I126 @SCM_LIB.SCM(SCH_1):PAGE32
     2 JTAG_SCM_PLD_TCK @SCM_LIB.SCM(SCH_1):JTAG_SCM_PLD_TCK   I126 @SCM_LIB.SCM(SCH_1):PAGE32

R511 Q_RES_0402LF-33.2,1%,1/16W,CHIA
     1 JTAG_SCM_TMS @SCM_LIB.SCM(SCH_1):JTAG_SCM_TMS   I127 @SCM_LIB.SCM(SCH_1):PAGE32
     2 JTAG_SCM_PLD_TMS @SCM_LIB.SCM(SCH_1):JTAG_SCM_PLD_TMS   I127 @SCM_LIB.SCM(SCH_1):PAGE32

R512 Q_RES_0402LF-33.2,1%,1/16W,CHIA
     1 JTAG_SCM_TDI @SCM_LIB.SCM(SCH_1):JTAG_SCM_TDI   I129 @SCM_LIB.SCM(SCH_1):PAGE32
     2 JTAG_SCM_PLD_TDI @SCM_LIB.SCM(SCH_1):JTAG_SCM_PLD_TDI   I129 @SCM_LIB.SCM(SCH_1):PAGE32

R513 Q_RES_0402LF-33.2,1%,1/16W,CHIA
     1 JTAG_SCM_TDO @SCM_LIB.SCM(SCH_1):JTAG_SCM_TDO   I128 @SCM_LIB.SCM(SCH_1):PAGE32
     2 JTAG_SCM_PLD_TDO @SCM_LIB.SCM(SCH_1):JTAG_SCM_PLD_TDO   I128 @SCM_LIB.SCM(SCH_1):PAGE32

R514 Q_RES_0402LF-33.2,1%,1/16W,CHIA
     1 JTAG_SCM_PLD_TCK @SCM_LIB.SCM(SCH_1):JTAG_SCM_PLD_TCK    I94 @SCM_LIB.SCM(SCH_1):PAGE32
     2 JTAG_SCM_CONN_TCK @SCM_LIB.SCM(SCH_1):JTAG_SCM_CONN_TCK    I94 @SCM_LIB.SCM(SCH_1):PAGE32

R515 Q_RES_0402LF-33.2,1%,1/16W,CHIA
     1 JTAG_SCM_PLD_TMS @SCM_LIB.SCM(SCH_1):JTAG_SCM_PLD_TMS    I96 @SCM_LIB.SCM(SCH_1):PAGE32
     2 JTAG_SCM_CONN_TMS @SCM_LIB.SCM(SCH_1):JTAG_SCM_CONN_TMS    I96 @SCM_LIB.SCM(SCH_1):PAGE32

R516 Q_RES_0402LF-33.2,1%,1/16W,CHIA
     1 JTAG_SCM_PLD_TDI @SCM_LIB.SCM(SCH_1):JTAG_SCM_PLD_TDI    I95 @SCM_LIB.SCM(SCH_1):PAGE32
     2 JTAG_SCM_CONN_TDI @SCM_LIB.SCM(SCH_1):JTAG_SCM_CONN_TDI    I95 @SCM_LIB.SCM(SCH_1):PAGE32

R517 Q_RES_0402LF-33.2,1%,1/16W,CHIA
     1 JTAG_SCM_PLD_TDO @SCM_LIB.SCM(SCH_1):JTAG_SCM_PLD_TDO    I97 @SCM_LIB.SCM(SCH_1):PAGE32
     2 JTAG_SCM_CONN_TDO @SCM_LIB.SCM(SCH_1):JTAG_SCM_CONN_TDO    I97 @SCM_LIB.SCM(SCH_1):PAGE32

R518 Q_RES_0402LF-33.2,1%,1/16W,CHIA
     1 JTAG_SCM_PLD_R1_JTAGEN @SCM_LIB.SCM(SCH_1):JTAG_SCM_PLD_R1_JTAGEN    I23 @SCM_LIB.SCM(SCH_1):PAGE32
     2 JTAG_SCM_PLD_JTAGEN @SCM_LIB.SCM(SCH_1):JTAG_SCM_PLD_JTAGEN    I23 @SCM_LIB.SCM(SCH_1):PAGE32

R519 Q_RES_0402LF-0,5%,1/16W,CHIP,CA
     1 BMC_CPLD_GPIO_2 @SCM_LIB.SCM(SCH_1):BMC_CPLD_GPIO_2   I147 @SCM_LIB.SCM(SCH_1):PAGE34
     2 BMC_CPLD_GPIO_2_R2 @SCM_LIB.SCM(SCH_1):BMC_CPLD_GPIO_2_R2   I147 @SCM_LIB.SCM(SCH_1):PAGE34

R521 Q_RES_0402LF-10K,1%,1/16W,CHIPA
     1 P3V3_AUX @SCM_LIB.SCM(SCH_1):P3V3_AUX   I234 @SCM_LIB.SCM(SCH_1):PAGE27
     2 SMB_BMC_MM10_SDA @SCM_LIB.SCM(SCH_1):SMB_BMC_MM10_SDA   I234 @SCM_LIB.SCM(SCH_1):PAGE27

R523 Q_RES_0402LF-10K,1%,1/16W,CHIPA
     1 P3V3_RGM @SCM_LIB.SCM(SCH_1):P3V3_RGM   I119 @SCM_LIB.SCM(SCH_1):PAGE32
     2 JTAG_SCM_TDO @SCM_LIB.SCM(SCH_1):JTAG_SCM_TDO   I119 @SCM_LIB.SCM(SCH_1):PAGE32

R525 Q_RES_0402LF-0,5%,1/16W,CHIP,CA
     1 P3V3_AUX @SCM_LIB.SCM(SCH_1):P3V3_AUX    I72 @SCM_LIB.SCM(SCH_1):PAGE41
     2 VCCIO1 @SCM_LIB.SCM(SCH_1):VCCIO1    I72 @SCM_LIB.SCM(SCH_1):PAGE41

R526 Q_RES_0402LF-33.2,1%,1/16W,EMPA
     1 BMC_CPLD_GPIO_7_R2 @SCM_LIB.SCM(SCH_1):BMC_CPLD_GPIO_7_R2   I147 @SCM_LIB.SCM(SCH_1):PAGE35
     2 BMC_CPLD_GPIO_7 @SCM_LIB.SCM(SCH_1):BMC_CPLD_GPIO_7   I147 @SCM_LIB.SCM(SCH_1):PAGE35

R527 Q_RES_0402LF-0,5%,1/16W,CHIP,CA
     1 USB_HOST_BMC_B_R_DP @SCM_LIB.SCM(SCH_1):USB_HOST_BMC_B_R_DP   I169 @SCM_LIB.SCM(SCH_1):PAGE15
     2 USB_HOST_BMC_B_DP @SCM_LIB.SCM(SCH_1):USB_HOST_BMC_B_DP   I169 @SCM_LIB.SCM(SCH_1):PAGE15

R528 Q_RES_0402LF-0,5%,1/16W,CHIP,CA
     1 USB_HOST_BMC_B_R_DN @SCM_LIB.SCM(SCH_1):USB_HOST_BMC_B_R_DN   I168 @SCM_LIB.SCM(SCH_1):PAGE15
     2 USB_HOST_BMC_B_DN @SCM_LIB.SCM(SCH_1):USB_HOST_BMC_B_DN   I168 @SCM_LIB.SCM(SCH_1):PAGE15

R529 Q_RES_0402LF-100,1%,1/16W,CHIPA
     1 PWRGD_P1V8_AUX @SCM_LIB.SCM(SCH_1):PWRGD_P1V8_AUX   I127 @SCM_LIB.SCM(SCH_1):PAGE52
     2 PWRGD_P1V8_AUX_R2 @SCM_LIB.SCM(SCH_1):PWRGD_P1V8_AUX_R2   I127 @SCM_LIB.SCM(SCH_1):PAGE52

R530 Q_RES_0402LF-100,1%,1/16W,CHIPA
     1 PWRGD_P3V3_RGM @SCM_LIB.SCM(SCH_1):PWRGD_P3V3_RGM   I132 @SCM_LIB.SCM(SCH_1):PAGE54
     2 PWRGD_P3V3_RGM_R2 @SCM_LIB.SCM(SCH_1):PWRGD_P3V3_RGM_R2   I132 @SCM_LIB.SCM(SCH_1):PAGE54

R531 Q_RES_0402LF-33.2,1%,1/16W,EMPA
     1 BMC_CPLD_GPIO_8_R2 @SCM_LIB.SCM(SCH_1):BMC_CPLD_GPIO_8_R2   I146 @SCM_LIB.SCM(SCH_1):PAGE35
     2 BMC_CPLD_GPIO_8 @SCM_LIB.SCM(SCH_1):BMC_CPLD_GPIO_8   I146 @SCM_LIB.SCM(SCH_1):PAGE35

R532 Q_RES_0402LF-33.2,1%,1/16W,EMPA
     1 EMMC_DT3_R @SCM_LIB.SCM(SCH_1):EMMC_DT3_R    I46 @SCM_LIB.SCM(SCH_1):PAGE21
     2 BMC_EMMC_DT3 @SCM_LIB.SCM(SCH_1):BMC_EMMC_DT3    I46 @SCM_LIB.SCM(SCH_1):PAGE21

R536 Q_RES_0402LF-33.2,1%,1/16W,CHIA
     1 BMC_CPLD_GPIO_12_R2 @SCM_LIB.SCM(SCH_1):BMC_CPLD_GPIO_12_R2   I144 @SCM_LIB.SCM(SCH_1):PAGE35
     2 BMC_CPLD_GPIO_12 @SCM_LIB.SCM(SCH_1):BMC_CPLD_GPIO_12   I144 @SCM_LIB.SCM(SCH_1):PAGE35

R537 Q_RES_0402LF-33.2,1%,1/16W,CHIA
     1 BMC_CPLD_GPIO_13_R2 @SCM_LIB.SCM(SCH_1):BMC_CPLD_GPIO_13_R2   I145 @SCM_LIB.SCM(SCH_1):PAGE35
     2 BMC_CPLD_GPIO_13 @SCM_LIB.SCM(SCH_1):BMC_CPLD_GPIO_13   I145 @SCM_LIB.SCM(SCH_1):PAGE35

R538 Q_RES_0402LF-100K,1%,1/16W,CHIA
     1 P3V3_AUX @SCM_LIB.SCM(SCH_1):P3V3_AUX    I25 @SCM_LIB.SCM(SCH_1):PAGE31
     2 UART_6_BMC_RXD_R @SCM_LIB.SCM(SCH_1):UART_6_BMC_RXD_R    I25 @SCM_LIB.SCM(SCH_1):PAGE31

R543 Q_RES_0402LF-4.7K,1%,1/16W,EMPB
     1 P3V3_AUX @SCM_LIB.SCM(SCH_1):P3V3_AUX   I147 @SCM_LIB.SCM(SCH_1):PAGE21
     2 SPI_BMC_HOLD1_N @SCM_LIB.SCM(SCH_1):SPI_BMC_HOLD1_N   I147 @SCM_LIB.SCM(SCH_1):PAGE21

R544 Q_RES_0402LF-0,5%,1/16W,CHIP,CA
     1 UART_SYS_DBG_TX @SCM_LIB.SCM(SCH_1):UART_SYS_DBG_TX    I74 @SCM_LIB.SCM(SCH_1):PAGE31
     2 UART_SYS_DBG_TX_R @SCM_LIB.SCM(SCH_1):UART_SYS_DBG_TX_R    I74 @SCM_LIB.SCM(SCH_1):PAGE31

R545 Q_RES_0402LF-0,5%,1/16W,CHIP,CA
     1    GND @SCM_LIB.SCM(SCH_1):GND   I143 @SCM_LIB.SCM(SCH_1):PAGE25
     2 FLASH_LATCH_CP @SCM_LIB.SCM(SCH_1):FLASH_LATCH_CP   I143 @SCM_LIB.SCM(SCH_1):PAGE25

R546 Q_RES_0402LF-0,5%,1/16W,CHIP,CA
     1 SPA_SOUT_SW_DBG @SCM_LIB.SCM(SCH_1):SPA_SOUT_SW_DBG    I75 @SCM_LIB.SCM(SCH_1):PAGE31
     2 SPA_SOUT_SW_DBG_R @SCM_LIB.SCM(SCH_1):SPA_SOUT_SW_DBG_R    I75 @SCM_LIB.SCM(SCH_1):PAGE31

R547 Q_RES_0402LF-33.2,1%,1/16W,CHIA
     1 SPI_BMC_CS1_FLASH_R_N @SCM_LIB.SCM(SCH_1):SPI_BMC_CS1_FLASH_R_N   I176 @SCM_LIB.SCM(SCH_1):PAGE21
     2 SPI_BMC_BOOT_CS1_R_N @SCM_LIB.SCM(SCH_1):SPI_BMC_BOOT_CS1_R_N   I176 @SCM_LIB.SCM(SCH_1):PAGE21

R548 Q_RES_0402LF-33.2,1%,1/16W,CHIA
     1 BMC_RSTIND_N @SCM_LIB.SCM(SCH_1):BMC_RSTIND_N   I172 @SCM_LIB.SCM(SCH_1):PAGE25
     2   RD_N @SCM_LIB.SCM(SCH_1):RD_N   I172 @SCM_LIB.SCM(SCH_1):PAGE25

R549 Q_RES_0402LF-33.2,1%,1/16W,CHIA
     1 SPI_BMC_CLK_FLASH_R @SCM_LIB.SCM(SCH_1):SPI_BMC_CLK_FLASH_R   I177 @SCM_LIB.SCM(SCH_1):PAGE21
     2 SPI_BMC_BOOT_CLK @SCM_LIB.SCM(SCH_1):SPI_BMC_BOOT_CLK   I177 @SCM_LIB.SCM(SCH_1):PAGE21

R550 Q_RES_0402LF-33.2,1%,1/16W,CHIA
     1 SPI_BMC_IO0_FLASH_R @SCM_LIB.SCM(SCH_1):SPI_BMC_IO0_FLASH_R   I178 @SCM_LIB.SCM(SCH_1):PAGE21
     2 SPI_BMC_BOOT_MOSI @SCM_LIB.SCM(SCH_1):SPI_BMC_BOOT_MOSI   I178 @SCM_LIB.SCM(SCH_1):PAGE21

R551 Q_RES_0402LF-33.2,1%,1/16W,CHIA
     1 FLASH_WP_STATUS @SCM_LIB.SCM(SCH_1):FLASH_WP_STATUS   I173 @SCM_LIB.SCM(SCH_1):PAGE25
     2 FLASH_R_WP_STATUS @SCM_LIB.SCM(SCH_1):FLASH_R_WP_STATUS   I173 @SCM_LIB.SCM(SCH_1):PAGE25

R552 Q_RES_0402LF-33.2,1%,1/16W,CHIA
     1 SPI_BMC_IO1_FLASH_R @SCM_LIB.SCM(SCH_1):SPI_BMC_IO1_FLASH_R   I179 @SCM_LIB.SCM(SCH_1):PAGE21
     2 SPI_BMC_BOOT_MISO @SCM_LIB.SCM(SCH_1):SPI_BMC_BOOT_MISO   I179 @SCM_LIB.SCM(SCH_1):PAGE21

R553 Q_RES_0402LF-33.2,1%,1/16W,CHIA
     1 SPI_BMC_CS0_FLASH_R_N @SCM_LIB.SCM(SCH_1):SPI_BMC_CS0_FLASH_R_N   I175 @SCM_LIB.SCM(SCH_1):PAGE21
     2 SPI_BMC_BOOT_CS0_R_N @SCM_LIB.SCM(SCH_1):SPI_BMC_BOOT_CS0_R_N   I175 @SCM_LIB.SCM(SCH_1):PAGE21

R554 Q_RES_0402LF-4.7K,1%,1/16W,EMPB
     1 P3V3_AUX @SCM_LIB.SCM(SCH_1):P3V3_AUX   I156 @SCM_LIB.SCM(SCH_1):PAGE25
     2 FLASH_R_WP_STATUS @SCM_LIB.SCM(SCH_1):FLASH_R_WP_STATUS   I156 @SCM_LIB.SCM(SCH_1):PAGE25

R555 Q_RES_0402LF-33.2,1%,1/16W,CHIA
     1 FLASH_LATCH_Q_N_R @SCM_LIB.SCM(SCH_1):FLASH_LATCH_Q_N_R   I174 @SCM_LIB.SCM(SCH_1):PAGE25
     2 FLASH_LATCH_Q_N_R1 @SCM_LIB.SCM(SCH_1):FLASH_LATCH_Q_N_R1   I174 @SCM_LIB.SCM(SCH_1):PAGE25

R556 Q_RES_0402LF-33.2,1%,1/16W,CHIA
     1 SPI_BMC_BT_WP1_N_R @SCM_LIB.SCM(SCH_1):SPI_BMC_BT_WP1_N_R   I175 @SCM_LIB.SCM(SCH_1):PAGE25
     2 FLASH_LATCH_Q_N_R2 @SCM_LIB.SCM(SCH_1):FLASH_LATCH_Q_N_R2   I175 @SCM_LIB.SCM(SCH_1):PAGE25

R557 Q_RES_0402LF-4.7K,1%,1/16W,CHIA
     1 P3V3_AUX @SCM_LIB.SCM(SCH_1):P3V3_AUX   I173 @SCM_LIB.SCM(SCH_1):PAGE21
     2 SPI_BMC_CS0_FLASH_R_N @SCM_LIB.SCM(SCH_1):SPI_BMC_CS0_FLASH_R_N   I173 @SCM_LIB.SCM(SCH_1):PAGE21

R558 Q_RES_0402LF-4.7K,1%,1/16W,CHIA
     1 P3V3_AUX @SCM_LIB.SCM(SCH_1):P3V3_AUX   I174 @SCM_LIB.SCM(SCH_1):PAGE21
     2 SPI_BMC_CS1_FLASH_R_N @SCM_LIB.SCM(SCH_1):SPI_BMC_CS1_FLASH_R_N   I174 @SCM_LIB.SCM(SCH_1):PAGE21

R559 Q_RES_0402LF-33.2,1%,1/16W,CHIA
     1 SPI_BMC_BT_WP0_N_R @SCM_LIB.SCM(SCH_1):SPI_BMC_BT_WP0_N_R   I176 @SCM_LIB.SCM(SCH_1):PAGE25
     2 FLASH_LATCH_Q_N_R2 @SCM_LIB.SCM(SCH_1):FLASH_LATCH_Q_N_R2   I176 @SCM_LIB.SCM(SCH_1):PAGE25

R560 Q_RES_0402LF-0,5%,1/16W,CHIP,CA
     1 FLASH_LATCH_Q_N_R1 @SCM_LIB.SCM(SCH_1):FLASH_LATCH_Q_N_R1   I149 @SCM_LIB.SCM(SCH_1):PAGE25
     2 FLASH_LATCH_Q_N_R2 @SCM_LIB.SCM(SCH_1):FLASH_LATCH_Q_N_R2   I149 @SCM_LIB.SCM(SCH_1):PAGE25

R561 Q_RES_0402LF-33.2,1%,1/16W,EMPA
     1 RST_SPI_BMC_FLASH_R2_N @SCM_LIB.SCM(SCH_1):RST_SPI_BMC_FLASH_R2_N   I181 @SCM_LIB.SCM(SCH_1):PAGE21
     2 RST_SPI_FLASH_BUF_N @SCM_LIB.SCM(SCH_1):RST_SPI_FLASH_BUF_N   I181 @SCM_LIB.SCM(SCH_1):PAGE21

R562 Q_RES_0402LF-33.2,1%,1/16W,CHIA
     1 RST_SPI_BMC_FLASH_R1_N @SCM_LIB.SCM(SCH_1):RST_SPI_BMC_FLASH_R1_N   I180 @SCM_LIB.SCM(SCH_1):PAGE21
     2 RST_SPI_FLASH_BUF_N @SCM_LIB.SCM(SCH_1):RST_SPI_FLASH_BUF_N   I180 @SCM_LIB.SCM(SCH_1):PAGE21

R563 Q_RES_0402LF-4.7K,1%,1/16W,CHIA
     1 P3V3_AUX @SCM_LIB.SCM(SCH_1):P3V3_AUX     I3 @SCM_LIB.SCM(SCH_1):PAGE25
     2 RST_SPI_FLASH_BUF_N @SCM_LIB.SCM(SCH_1):RST_SPI_FLASH_BUF_N     I3 @SCM_LIB.SCM(SCH_1):PAGE25

R564 Q_RES_0402LF-0,5%,1/16W,EMPTY,A
     1 HDD_LED_N @SCM_LIB.SCM(SCH_1):HDD_LED_N   I562 @SCM_LIB.SCM(SCH_1):PAGE10
     2 HDD_LED_R_N @SCM_LIB.SCM(SCH_1):HDD_LED_R_N   I562 @SCM_LIB.SCM(SCH_1):PAGE10

R565 Q_RES_0402LF-100,1%,1/16W,CHIPA
     1 ID_RST_BTN_BMC_R_N @SCM_LIB.SCM(SCH_1):ID_RST_BTN_BMC_R_N   I406 @SCM_LIB.SCM(SCH_1):PAGE15
     2 ID_RST_BTN_BMC_N @SCM_LIB.SCM(SCH_1):ID_RST_BTN_BMC_N   I406 @SCM_LIB.SCM(SCH_1):PAGE15

R566 Q_RES_0402LF-0,5%,1/16W,CHIP,CA
     1 RST_BMC_RSTBTN_OUT_R_N @SCM_LIB.SCM(SCH_1):RST_BMC_RSTBTN_OUT_R_N   I128 @SCM_LIB.SCM(SCH_1):PAGE15
     2 RST_BMC_RSTBTN_OUT_N @SCM_LIB.SCM(SCH_1):RST_BMC_RSTBTN_OUT_N   I128 @SCM_LIB.SCM(SCH_1):PAGE15

R567 Q_RES_0402LF-33.2,1%,1/16W,CHIA
     1 SMB_BMC_MM7_R_SCL @SCM_LIB.SCM(SCH_1):SMB_BMC_MM7_R_SCL   I274 @SCM_LIB.SCM(SCH_1):PAGE12
     2 SMB_BMC_MM7_SCL @SCM_LIB.SCM(SCH_1):SMB_BMC_MM7_SCL   I274 @SCM_LIB.SCM(SCH_1):PAGE12

R568 Q_RES_0402LF-220,1%,1/16W,CHIPA
     1 PWR_LED_P5V_AUX @SCM_LIB.SCM(SCH_1):PWR_LED_P5V_AUX    I59 @SCM_LIB.SCM(SCH_1):PAGE49
     2 P5V_AUX @SCM_LIB.SCM(SCH_1):P5V_AUX    I59 @SCM_LIB.SCM(SCH_1):PAGE49

R569 Q_RES_0402LF-220,1%,1/16W,CHIPA
     1 HDD_LED_P5V_AUX @SCM_LIB.SCM(SCH_1):HDD_LED_P5V_AUX    I60 @SCM_LIB.SCM(SCH_1):PAGE49
     2 P5V_AUX @SCM_LIB.SCM(SCH_1):P5V_AUX    I60 @SCM_LIB.SCM(SCH_1):PAGE49

R570 Q_RES_0402LF-33.2,1%,1/16W,CHIA
     1 SMB_BMC_MM7_R_SDA @SCM_LIB.SCM(SCH_1):SMB_BMC_MM7_R_SDA   I275 @SCM_LIB.SCM(SCH_1):PAGE12
     2 SMB_BMC_MM7_SDA @SCM_LIB.SCM(SCH_1):SMB_BMC_MM7_SDA   I275 @SCM_LIB.SCM(SCH_1):PAGE12

R571 Q_RES_0402LF-0,5%,1/16W,CHIP,CA
     1 IRQ_BMC_PCH_NMI_N @SCM_LIB.SCM(SCH_1):IRQ_BMC_PCH_NMI_N    I35 @SCM_LIB.SCM(SCH_1):PAGE34
     2 IRQ_BMC_PCH_NMI_R_N @SCM_LIB.SCM(SCH_1):IRQ_BMC_PCH_NMI_R_N    I35 @SCM_LIB.SCM(SCH_1):PAGE34

R574 Q_RES_0402LF-0,5%,1/16W,CHIP,CA
     1 SMB_BMC_ALERT16_N @SCM_LIB.SCM(SCH_1):SMB_BMC_ALERT16_N    I76 @SCM_LIB.SCM(SCH_1):PAGE35
     2 SMB_BMC_ALERT16_R2_N @SCM_LIB.SCM(SCH_1):SMB_BMC_ALERT16_R2_N    I76 @SCM_LIB.SCM(SCH_1):PAGE35

R575 Q_RES_0402LF-0,5%,1/16W,CHIP,CA
     1 FM_P12V_HSC_ENABLE @SCM_LIB.SCM(SCH_1):FM_P12V_HSC_ENABLE     I2 @SCM_LIB.SCM(SCH_1):PAGE36
     2 FM_P12V_HSC_ENABLE_R2 @SCM_LIB.SCM(SCH_1):FM_P12V_HSC_ENABLE_R2     I2 @SCM_LIB.SCM(SCH_1):PAGE36

R577 Q_RES_0402LF-0,5%,1/16W,CHIP,CA
     1 FM_SOL_UART_CH_SEL @SCM_LIB.SCM(SCH_1):FM_SOL_UART_CH_SEL     I3 @SCM_LIB.SCM(SCH_1):PAGE36
     2 FM_SOL_UART_CH_SEL_R2 @SCM_LIB.SCM(SCH_1):FM_SOL_UART_CH_SEL_R2     I3 @SCM_LIB.SCM(SCH_1):PAGE36

R578 Q_RES_0402LF-0,5%,1/16W,CHIP,CA
     1 PWRGD_DSW_PWROK @SCM_LIB.SCM(SCH_1):PWRGD_DSW_PWROK     I8 @SCM_LIB.SCM(SCH_1):PAGE36
     2 PWRGD_DSW_PWROK_R2 @SCM_LIB.SCM(SCH_1):PWRGD_DSW_PWROK_R2     I8 @SCM_LIB.SCM(SCH_1):PAGE36

R579 Q_RES_0402LF-0,5%,1/16W,CHIP,CA
     1 FM_DEBUG_PORT_PRSNT_N @SCM_LIB.SCM(SCH_1):FM_DEBUG_PORT_PRSNT_N     I7 @SCM_LIB.SCM(SCH_1):PAGE36
     2 FM_DEBUG_PORT_R2_PRSNT_N @SCM_LIB.SCM(SCH_1):FM_DEBUG_PORT_R2_PRSNT_N     I7 @SCM_LIB.SCM(SCH_1):PAGE36

R580 Q_RES_0402LF-33.2,1%,1/16W,CHIA
     1 SMB_BMC_MM9_R_SCL @SCM_LIB.SCM(SCH_1):SMB_BMC_MM9_R_SCL   I321 @SCM_LIB.SCM(SCH_1):PAGE12
     2 SMB_BMC_MM9_SCL @SCM_LIB.SCM(SCH_1):SMB_BMC_MM9_SCL   I321 @SCM_LIB.SCM(SCH_1):PAGE12

R582 Q_RES_0402LF-33.2,1%,1/16W,CHIA
     1 SMB_BMC_MM9_R_SDA @SCM_LIB.SCM(SCH_1):SMB_BMC_MM9_R_SDA   I318 @SCM_LIB.SCM(SCH_1):PAGE12
     2 SMB_BMC_MM9_SDA @SCM_LIB.SCM(SCH_1):SMB_BMC_MM9_SDA   I318 @SCM_LIB.SCM(SCH_1):PAGE12

R583 Q_RES_0402LF-33.2,1%,1/16W,CHIA
     1 SMB_BMC_MM10_R_SCL @SCM_LIB.SCM(SCH_1):SMB_BMC_MM10_R_SCL   I319 @SCM_LIB.SCM(SCH_1):PAGE12
     2 SMB_BMC_MM10_SCL @SCM_LIB.SCM(SCH_1):SMB_BMC_MM10_SCL   I319 @SCM_LIB.SCM(SCH_1):PAGE12

R584 Q_RES_0402LF-33.2,1%,1/16W,CHIA
     1 SMB_BMC_MM10_R_SDA @SCM_LIB.SCM(SCH_1):SMB_BMC_MM10_R_SDA   I320 @SCM_LIB.SCM(SCH_1):PAGE12
     2 SMB_BMC_MM10_SDA @SCM_LIB.SCM(SCH_1):SMB_BMC_MM10_SDA   I320 @SCM_LIB.SCM(SCH_1):PAGE12

R585 Q_RES_0402LF-33.2,1%,1/16W,CHIA
     1 BMC_RSTIND_N @SCM_LIB.SCM(SCH_1):BMC_RSTIND_N   I404 @SCM_LIB.SCM(SCH_1):PAGE15
     2 RST_SPI_FLASH_N @SCM_LIB.SCM(SCH_1):RST_SPI_FLASH_N   I404 @SCM_LIB.SCM(SCH_1):PAGE15

R586 Q_RES_0402LF-4.7K,1%,1/16W,CHIA
     1 P3V3_AUX @SCM_LIB.SCM(SCH_1):P3V3_AUX    I67 @SCM_LIB.SCM(SCH_1):PAGE42
     2 BMC_CPLD_GPIO_2 @SCM_LIB.SCM(SCH_1):BMC_CPLD_GPIO_2    I67 @SCM_LIB.SCM(SCH_1):PAGE42

R589 Q_RES_0402LF-33.2,1%,1/16W,CHIA
     1 SMB_BMC_MM3_R_SCL @SCM_LIB.SCM(SCH_1):SMB_BMC_MM3_R_SCL   I316 @SCM_LIB.SCM(SCH_1):PAGE12
     2 SMB_BMC_MM3_SCL @SCM_LIB.SCM(SCH_1):SMB_BMC_MM3_SCL   I316 @SCM_LIB.SCM(SCH_1):PAGE12

R590 Q_RES_0402LF-33.2,1%,1/16W,CHIA
     1 SMB_BMC_MM3_R_SDA @SCM_LIB.SCM(SCH_1):SMB_BMC_MM3_R_SDA   I317 @SCM_LIB.SCM(SCH_1):PAGE12
     2 SMB_BMC_MM3_SDA @SCM_LIB.SCM(SCH_1):SMB_BMC_MM3_SDA   I317 @SCM_LIB.SCM(SCH_1):PAGE12

R592 Q_RES_0402LF-4.7K,1%,1/16W,CHIA
     1 P3V3_AUX @SCM_LIB.SCM(SCH_1):P3V3_AUX   I171 @SCM_LIB.SCM(SCH_1):PAGE25
     2 PU_J1_P1 @SCM_LIB.SCM(SCH_1):PU_J1_P1   I171 @SCM_LIB.SCM(SCH_1):PAGE25

R593 Q_RES_0402LF-4.7K,1%,1/16W,EMPA
     1 P3V3_AUX @SCM_LIB.SCM(SCH_1):P3V3_AUX    I39 @SCM_LIB.SCM(SCH_1):PAGE42
     2 BMC_CPLD_GPIO_7 @SCM_LIB.SCM(SCH_1):BMC_CPLD_GPIO_7    I39 @SCM_LIB.SCM(SCH_1):PAGE42

R594 Q_RES_0402LF-33.2,1%,1/16W,CHIA
     1 SPI_TPM_CS_N @SCM_LIB.SCM(SCH_1):SPI_TPM_CS_N   I360 @SCM_LIB.SCM(SCH_1):PAGE44
     2 SPI_TPM_CS_R_N @SCM_LIB.SCM(SCH_1):SPI_TPM_CS_R_N   I360 @SCM_LIB.SCM(SCH_1):PAGE44

R595 Q_RES_0402LF-4.7K,1%,1/16W,EMPA
     1 P3V3_AUX @SCM_LIB.SCM(SCH_1):P3V3_AUX    I37 @SCM_LIB.SCM(SCH_1):PAGE42
     2 BMC_CPLD_GPIO_8 @SCM_LIB.SCM(SCH_1):BMC_CPLD_GPIO_8    I37 @SCM_LIB.SCM(SCH_1):PAGE42

R597 Q_RES_0402LF-750,1%,1/16W,CHIPA
     1 LED_POSTCODE_7 @SCM_LIB.SCM(SCH_1):LED_POSTCODE_7    I18 @SCM_LIB.SCM(SCH_1):PAGE47
     2 LED_POSTCODE_7_R @SCM_LIB.SCM(SCH_1):LED_POSTCODE_7_R    I18 @SCM_LIB.SCM(SCH_1):PAGE47

R598 Q_RES_0402LF-750,1%,1/16W,CHIPA
     1 LED_POSTCODE_6 @SCM_LIB.SCM(SCH_1):LED_POSTCODE_6    I20 @SCM_LIB.SCM(SCH_1):PAGE47
     2 LED_POSTCODE_6_R @SCM_LIB.SCM(SCH_1):LED_POSTCODE_6_R    I20 @SCM_LIB.SCM(SCH_1):PAGE47

R599 Q_RES_0402LF-750,1%,1/16W,CHIPA
     1 LED_POSTCODE_5 @SCM_LIB.SCM(SCH_1):LED_POSTCODE_5    I23 @SCM_LIB.SCM(SCH_1):PAGE47
     2 LED_POSTCODE_5_R @SCM_LIB.SCM(SCH_1):LED_POSTCODE_5_R    I23 @SCM_LIB.SCM(SCH_1):PAGE47

R600 Q_RES_0402LF-750,1%,1/16W,CHIPA
     1 LED_POSTCODE_4 @SCM_LIB.SCM(SCH_1):LED_POSTCODE_4    I25 @SCM_LIB.SCM(SCH_1):PAGE47
     2 LED_POSTCODE_4_R @SCM_LIB.SCM(SCH_1):LED_POSTCODE_4_R    I25 @SCM_LIB.SCM(SCH_1):PAGE47

R601 Q_RES_0402LF-750,1%,1/16W,CHIPA
     1 LED_POSTCODE_3 @SCM_LIB.SCM(SCH_1):LED_POSTCODE_3    I31 @SCM_LIB.SCM(SCH_1):PAGE47
     2 LED_POSTCODE_3_R @SCM_LIB.SCM(SCH_1):LED_POSTCODE_3_R    I31 @SCM_LIB.SCM(SCH_1):PAGE47

R602 Q_RES_0402LF-750,1%,1/16W,CHIPA
     1 LED_POSTCODE_2 @SCM_LIB.SCM(SCH_1):LED_POSTCODE_2    I33 @SCM_LIB.SCM(SCH_1):PAGE47
     2 LED_POSTCODE_2_R @SCM_LIB.SCM(SCH_1):LED_POSTCODE_2_R    I33 @SCM_LIB.SCM(SCH_1):PAGE47

R603 Q_RES_0402LF-750,1%,1/16W,CHIPA
     1 LED_POSTCODE_1 @SCM_LIB.SCM(SCH_1):LED_POSTCODE_1    I35 @SCM_LIB.SCM(SCH_1):PAGE47
     2 LED_POSTCODE_1_R @SCM_LIB.SCM(SCH_1):LED_POSTCODE_1_R    I35 @SCM_LIB.SCM(SCH_1):PAGE47

R604 Q_RES_0402LF-750,1%,1/16W,CHIPA
     1 LED_POSTCODE_0 @SCM_LIB.SCM(SCH_1):LED_POSTCODE_0    I37 @SCM_LIB.SCM(SCH_1):PAGE47
     2 LED_POSTCODE_0_R @SCM_LIB.SCM(SCH_1):LED_POSTCODE_0_R    I37 @SCM_LIB.SCM(SCH_1):PAGE47

R607 Q_RES_0402LF-4.7K,1%,1/16W,CHIA
     1 P3V3_AUX @SCM_LIB.SCM(SCH_1):P3V3_AUX    I29 @SCM_LIB.SCM(SCH_1):PAGE42
     2 BMC_CPLD_GPIO_12 @SCM_LIB.SCM(SCH_1):BMC_CPLD_GPIO_12    I29 @SCM_LIB.SCM(SCH_1):PAGE42

R608 Q_RES_0402LF-4.7K,1%,1/16W,CHIA
     1 P3V3_AUX @SCM_LIB.SCM(SCH_1):P3V3_AUX    I27 @SCM_LIB.SCM(SCH_1):PAGE42
     2 BMC_CPLD_GPIO_13 @SCM_LIB.SCM(SCH_1):BMC_CPLD_GPIO_13    I27 @SCM_LIB.SCM(SCH_1):PAGE42

R610 Q_RES_0402LF-2.2K,5%,1/16W,CHIA
     1 P3V3_AUX @SCM_LIB.SCM(SCH_1):P3V3_AUX   I237 @SCM_LIB.SCM(SCH_1):PAGE27
     2 SMB_BMC_MM15_SCL @SCM_LIB.SCM(SCH_1):SMB_BMC_MM15_SCL   I237 @SCM_LIB.SCM(SCH_1):PAGE27

R614 Q_RES_0402LF-100K,1%,1/16W,CHIA
     1 RST_SRST_PLD_BMC_R1_N @SCM_LIB.SCM(SCH_1):RST_SRST_PLD_BMC_R1_N    I35 @SCM_LIB.SCM(SCH_1):PAGE22
     2    GND @SCM_LIB.SCM(SCH_1):GND    I35 @SCM_LIB.SCM(SCH_1):PAGE22

R615 Q_RES_0402LF-4.7K,1%,1/16W,EMPB
     1 P3V3_AUX @SCM_LIB.SCM(SCH_1):P3V3_AUX    I33 @SCM_LIB.SCM(SCH_1):PAGE48
     2 FM_BMC_DISABLE @SCM_LIB.SCM(SCH_1):FM_BMC_DISABLE    I33 @SCM_LIB.SCM(SCH_1):PAGE48

R616 Q_RES_0402LF-0,5%,1/16W,CHIP,CA
     1 FM_JTAG_TCK_MUX_BMC_SEL_R @SCM_LIB.SCM(SCH_1):FM_JTAG_TCK_MUX_BMC_SEL_R    I40 @SCM_LIB.SCM(SCH_1):PAGE48
     2 FM_JTAG_TCK_MUX_BMC_SEL @SCM_LIB.SCM(SCH_1):FM_JTAG_TCK_MUX_BMC_SEL    I40 @SCM_LIB.SCM(SCH_1):PAGE48

R618 Q_RES_0402LF-0,5%,1/16W,CHIP,CA
     1 UART_SYS_DBG_RX @SCM_LIB.SCM(SCH_1):UART_SYS_DBG_RX    I76 @SCM_LIB.SCM(SCH_1):PAGE31
     2 UART_SYS_DBG_RX_R @SCM_LIB.SCM(SCH_1):UART_SYS_DBG_RX_R    I76 @SCM_LIB.SCM(SCH_1):PAGE31

R619 Q_RES_0402LF-8.2K,5%,1/16W,EMPA
     1 HDD_LED_N @SCM_LIB.SCM(SCH_1):HDD_LED_N    I26 @SCM_LIB.SCM(SCH_1):PAGE49
     2    GND @SCM_LIB.SCM(SCH_1):GND    I26 @SCM_LIB.SCM(SCH_1):PAGE49

R620 Q_RES_0402LF-100K,1%,1/16W,CHIA
     1 FM_JTAG_TCK_MUX_BMC_SEL @SCM_LIB.SCM(SCH_1):FM_JTAG_TCK_MUX_BMC_SEL    I39 @SCM_LIB.SCM(SCH_1):PAGE48
     2    GND @SCM_LIB.SCM(SCH_1):GND    I39 @SCM_LIB.SCM(SCH_1):PAGE48

R621 Q_RES_0402LF-4.7K,1%,1/16W,CHIA
     1 P3V3_AUX @SCM_LIB.SCM(SCH_1):P3V3_AUX    I13 @SCM_LIB.SCM(SCH_1):PAGE42
     2 FM_P12V_HSC_ENABLE @SCM_LIB.SCM(SCH_1):FM_P12V_HSC_ENABLE    I13 @SCM_LIB.SCM(SCH_1):PAGE42

R623 Q_RES_0402LF-4.7K,1%,1/16W,EMPA
     1 P3V3_RGM @SCM_LIB.SCM(SCH_1):P3V3_RGM   I152 @SCM_LIB.SCM(SCH_1):PAGE15
     2 RST_EXTRST_N @SCM_LIB.SCM(SCH_1):RST_EXTRST_N   I152 @SCM_LIB.SCM(SCH_1):PAGE15

R624 Q_RES_0402LF-4.7K,1%,1/16W,CHIA
     1 P3V3_AUX @SCM_LIB.SCM(SCH_1):P3V3_AUX    I48 @SCM_LIB.SCM(SCH_1):PAGE48
     2 FM_BMC_DEBUG_SW_N @SCM_LIB.SCM(SCH_1):FM_BMC_DEBUG_SW_N    I48 @SCM_LIB.SCM(SCH_1):PAGE48

R625 Q_RES_0402LF-4.7K,1%,1/16W,CHIA
     1 P3V3_AUX @SCM_LIB.SCM(SCH_1):P3V3_AUX    I17 @SCM_LIB.SCM(SCH_1):PAGE34
     2 RST_RSMRST_N @SCM_LIB.SCM(SCH_1):RST_RSMRST_N    I17 @SCM_LIB.SCM(SCH_1):PAGE34

R626 Q_RES_0402LF-0,5%,1/16W,CHIP,CA
     1 FM_SOL_UART_CH_SEL @SCM_LIB.SCM(SCH_1):FM_SOL_UART_CH_SEL   I161 @SCM_LIB.SCM(SCH_1):PAGE28
     2 FM_SOL_UART_CH_SEL_R3 @SCM_LIB.SCM(SCH_1):FM_SOL_UART_CH_SEL_R3   I161 @SCM_LIB.SCM(SCH_1):PAGE28

R627 Q_RES_0402LF-4.7K,1%,1/16W,CHIA
     1 P3V3_AUX @SCM_LIB.SCM(SCH_1):P3V3_AUX     I7 @SCM_LIB.SCM(SCH_1):PAGE42
     2 PWRGD_DSW_PWROK @SCM_LIB.SCM(SCH_1):PWRGD_DSW_PWROK     I7 @SCM_LIB.SCM(SCH_1):PAGE42

R628 Q_RES_0402LF-100,1%,1/16W,CHIPA
     1 SPA_SIN_SW_DBG @SCM_LIB.SCM(SCH_1):SPA_SIN_SW_DBG    I77 @SCM_LIB.SCM(SCH_1):PAGE31
     2 SPA_SIN_SW_DBG_R @SCM_LIB.SCM(SCH_1):SPA_SIN_SW_DBG_R    I77 @SCM_LIB.SCM(SCH_1):PAGE31

R629 Q_RES_0402LF-0,5%,1/16W,CHIP,CA
     1 BMC_CPLD_GPIO_2 @SCM_LIB.SCM(SCH_1):BMC_CPLD_GPIO_2    I78 @SCM_LIB.SCM(SCH_1):PAGE31
     2 FM_DBG_SW_N @SCM_LIB.SCM(SCH_1):FM_DBG_SW_N    I78 @SCM_LIB.SCM(SCH_1):PAGE31

R630 Q_RES_0402LF-4.7K,1%,1/16W,CHIA
     1 P3V3_AUX @SCM_LIB.SCM(SCH_1):P3V3_AUX    I79 @SCM_LIB.SCM(SCH_1):PAGE31
     2 PU_J13_P1 @SCM_LIB.SCM(SCH_1):PU_J13_P1    I79 @SCM_LIB.SCM(SCH_1):PAGE31

R631 Q_RES_0402LF-16.9K,1%,1/16W,CHA
     1 P3V3_LDO @SCM_LIB.SCM(SCH_1):P3V3_LDO    I62 @SCM_LIB.SCM(SCH_1):PAGE51
     2 U56_ADJ_1 @SCM_LIB.SCM(SCH_1):U56_ADJ_1    I62 @SCM_LIB.SCM(SCH_1):PAGE51

R632 Q_RES_0402LF-0,5%,1/16W,CHIP,CA
     1 SMB_DEBUG_AUX_LVC3_USB_SCL @SCM_LIB.SCM(SCH_1):SMB_DEBUG_AUX_LVC3_USB_SCL   I153 @SCM_LIB.SCM(SCH_1):PAGE28
     2 SMB_DEBUG_AUX_LVC3_USB_R3_SCL @SCM_LIB.SCM(SCH_1):SMB_DEBUG_AUX_LVC3_USB_R3_SCL   I153 @SCM_LIB.SCM(SCH_1):PAGE28

R633 Q_RES_0402LF-1K,1%,1/16W,EMPTYA
     1 P3V3_AUX @SCM_LIB.SCM(SCH_1):P3V3_AUX    I81 @SCM_LIB.SCM(SCH_1):PAGE22
     2 RST_BMC_HW_OUT @SCM_LIB.SCM(SCH_1):RST_BMC_HW_OUT    I81 @SCM_LIB.SCM(SCH_1):PAGE22

R634 Q_RES_0402LF-0,5%,1/16W,CHIP,CA
     1 FM_JTAG_BMC_MUX_SEL @SCM_LIB.SCM(SCH_1):FM_JTAG_BMC_MUX_SEL    I37 @SCM_LIB.SCM(SCH_1):PAGE34
     2 FM_JTAG_BMC_MUX_SEL_R2 @SCM_LIB.SCM(SCH_1):FM_JTAG_BMC_MUX_SEL_R2    I37 @SCM_LIB.SCM(SCH_1):PAGE34

R635 Q_RES_0402LF-33.2,1%,1/16W,CHIA
     1 RST_WDTRST_PLD_N @SCM_LIB.SCM(SCH_1):RST_WDTRST_PLD_N    I80 @SCM_LIB.SCM(SCH_1):PAGE36
     2 RST_WDTRST_PLD_R2_N @SCM_LIB.SCM(SCH_1):RST_WDTRST_PLD_R2_N    I80 @SCM_LIB.SCM(SCH_1):PAGE36

R636 Q_RES_0402LF-0,5%,1/16W,CHIP,CA
     1 RST_EXTRST_N @SCM_LIB.SCM(SCH_1):RST_EXTRST_N    I10 @SCM_LIB.SCM(SCH_1):PAGE22
     2 RST_BMC_EXTRST_R2_N @SCM_LIB.SCM(SCH_1):RST_BMC_EXTRST_R2_N    I10 @SCM_LIB.SCM(SCH_1):PAGE22

R637 Q_RES_0402LF-0,5%,1/16W,CHIP,CA
     1 RST_WDTRST_PLD_R1_N @SCM_LIB.SCM(SCH_1):RST_WDTRST_PLD_R1_N   I337 @SCM_LIB.SCM(SCH_1):PAGE13
     2 RST_WDTRST_PLD_N @SCM_LIB.SCM(SCH_1):RST_WDTRST_PLD_N   I337 @SCM_LIB.SCM(SCH_1):PAGE13

R638 Q_RES_0402LF-33.2,1%,1/16W,CHIA
     1 RST_BMC_HW_R @SCM_LIB.SCM(SCH_1):RST_BMC_HW_R   I143 @SCM_LIB.SCM(SCH_1):PAGE35
     2 RST_BMC_HW @SCM_LIB.SCM(SCH_1):RST_BMC_HW   I143 @SCM_LIB.SCM(SCH_1):PAGE35

R639 Q_RES_0402LF-33.2,1%,1/16W,CHIA
     1 JTAG_1_BMC_TDI_R @SCM_LIB.SCM(SCH_1):JTAG_1_BMC_TDI_R    I88 @SCM_LIB.SCM(SCH_1):PAGE32
     2 JTAG_MB_TDI @SCM_LIB.SCM(SCH_1):JTAG_MB_TDI    I88 @SCM_LIB.SCM(SCH_1):PAGE32

R640 Q_RES_0402LF-4.7K,1%,1/16W,EMPA
     1 P3V3_AUX @SCM_LIB.SCM(SCH_1):P3V3_AUX    I56 @SCM_LIB.SCM(SCH_1):PAGE42
     2 FM_JTAG_BMC_MUX_SEL @SCM_LIB.SCM(SCH_1):FM_JTAG_BMC_MUX_SEL    I56 @SCM_LIB.SCM(SCH_1):PAGE42

R641 Q_RES_0402LF-4.7K,1%,1/16W,EMPA
     1 P3V3_AUX @SCM_LIB.SCM(SCH_1):P3V3_AUX    I53 @SCM_LIB.SCM(SCH_1):PAGE42
     2 RST_BMC_SELF_HW_R2 @SCM_LIB.SCM(SCH_1):RST_BMC_SELF_HW_R2    I53 @SCM_LIB.SCM(SCH_1):PAGE42

R642 Q_RES_0402LF-100K,1%,1/16W,CHIA
     1    GND @SCM_LIB.SCM(SCH_1):GND    I58 @SCM_LIB.SCM(SCH_1):PAGE42
     2 FM_JTAG_BMC_MUX_SEL @SCM_LIB.SCM(SCH_1):FM_JTAG_BMC_MUX_SEL    I58 @SCM_LIB.SCM(SCH_1):PAGE42

R643 Q_RES_0402LF-33.2,1%,1/16W,CHIA
     1 PWRGD_DSW_PWROK @SCM_LIB.SCM(SCH_1):PWRGD_DSW_PWROK   I344 @SCM_LIB.SCM(SCH_1):PAGE13
     2 PWRGD_DSW_PWROK_R1 @SCM_LIB.SCM(SCH_1):PWRGD_DSW_PWROK_R1   I344 @SCM_LIB.SCM(SCH_1):PAGE13

R644 Q_RES_0402LF-33.2,1%,1/16W,CHIA
     1 FM_JTAG_BMC_MUX_SEL @SCM_LIB.SCM(SCH_1):FM_JTAG_BMC_MUX_SEL   I345 @SCM_LIB.SCM(SCH_1):PAGE15
     2 FM_JTAG_BMC_MUX_SEL_R1 @SCM_LIB.SCM(SCH_1):FM_JTAG_BMC_MUX_SEL_R1   I345 @SCM_LIB.SCM(SCH_1):PAGE15

R645 Q_RES_0603LF-0,5%,1/10W,EMPTY,A
     1 P1V8_AUX @SCM_LIB.SCM(SCH_1):P1V8_AUX   I278 @SCM_LIB.SCM(SCH_1):PAGE17
     2 PGPPA_BMC_AUX_L @SCM_LIB.SCM(SCH_1):PGPPA_BMC_AUX_L   I278 @SCM_LIB.SCM(SCH_1):PAGE17

R646 Q_RES_0603LF-0,5%,1/10W,EMPTY,A
     1 PGPPA_BMC_AUX_L @SCM_LIB.SCM(SCH_1):PGPPA_BMC_AUX_L   I279 @SCM_LIB.SCM(SCH_1):PAGE17
     2 P3V3_AUX @SCM_LIB.SCM(SCH_1):P3V3_AUX   I279 @SCM_LIB.SCM(SCH_1):PAGE17

R647 Q_RES_0402LF-33.2,1%,1/16W,EMPA
     1 EMMC_DT2_R @SCM_LIB.SCM(SCH_1):EMMC_DT2_R    I45 @SCM_LIB.SCM(SCH_1):PAGE21
     2 BMC_EMMC_DT2 @SCM_LIB.SCM(SCH_1):BMC_EMMC_DT2    I45 @SCM_LIB.SCM(SCH_1):PAGE21

R648 Q_RES_0402LF-33.2,1%,1/16W,EMPA
     1 EMMC_DT1_R @SCM_LIB.SCM(SCH_1):EMMC_DT1_R    I43 @SCM_LIB.SCM(SCH_1):PAGE21
     2 BMC_EMMC_DT1 @SCM_LIB.SCM(SCH_1):BMC_EMMC_DT1    I43 @SCM_LIB.SCM(SCH_1):PAGE21

R649 Q_RES_0402LF-33.2,1%,1/16W,EMPA
     1 EMMC_DT0_R @SCM_LIB.SCM(SCH_1):EMMC_DT0_R    I42 @SCM_LIB.SCM(SCH_1):PAGE21
     2 BMC_EMMC_DT0 @SCM_LIB.SCM(SCH_1):BMC_EMMC_DT0    I42 @SCM_LIB.SCM(SCH_1):PAGE21

R650 Q_RES_0402LF-33.2,1%,1/16W,EMPA
     1 BMC_EMMC_DT7 @SCM_LIB.SCM(SCH_1):BMC_EMMC_DT7    I99 @SCM_LIB.SCM(SCH_1):PAGE21
     2 EMMC_DT7_R @SCM_LIB.SCM(SCH_1):EMMC_DT7_R    I99 @SCM_LIB.SCM(SCH_1):PAGE21

R651 Q_RES_0402LF-33.2,1%,1/16W,EMPA
     1 BMC_EMMC_DT6 @SCM_LIB.SCM(SCH_1):BMC_EMMC_DT6    I98 @SCM_LIB.SCM(SCH_1):PAGE21
     2 EMMC_DT6_R @SCM_LIB.SCM(SCH_1):EMMC_DT6_R    I98 @SCM_LIB.SCM(SCH_1):PAGE21

R652 Q_RES_0402LF-33.2,1%,1/16W,EMPA
     1 BMC_EMMC_DT5 @SCM_LIB.SCM(SCH_1):BMC_EMMC_DT5   I101 @SCM_LIB.SCM(SCH_1):PAGE21
     2 EMMC_DT5_R @SCM_LIB.SCM(SCH_1):EMMC_DT5_R   I101 @SCM_LIB.SCM(SCH_1):PAGE21

R653 Q_RES_0402LF-33.2,1%,1/16W,EMPA
     1 BMC_EMMC_DT4 @SCM_LIB.SCM(SCH_1):BMC_EMMC_DT4   I100 @SCM_LIB.SCM(SCH_1):PAGE21
     2 EMMC_DT4_R @SCM_LIB.SCM(SCH_1):EMMC_DT4_R   I100 @SCM_LIB.SCM(SCH_1):PAGE21

R654 Q_RES_0402LF-33.2,1%,1/16W,EMPA
     1 EMMC_CLK_R @SCM_LIB.SCM(SCH_1):EMMC_CLK_R    I33 @SCM_LIB.SCM(SCH_1):PAGE21
     2 BMC_EMMC_CLK @SCM_LIB.SCM(SCH_1):BMC_EMMC_CLK    I33 @SCM_LIB.SCM(SCH_1):PAGE21

R655 Q_RES_0402LF-10K,1%,1/16W,EMPTB
     1 P3V3_AUX @SCM_LIB.SCM(SCH_1):P3V3_AUX    I67 @SCM_LIB.SCM(SCH_1):PAGE21
     2 EMMC_DT0_R @SCM_LIB.SCM(SCH_1):EMMC_DT0_R    I67 @SCM_LIB.SCM(SCH_1):PAGE21

R656 Q_RES_0402LF-10K,1%,1/16W,EMPTB
     1 P3V3_AUX @SCM_LIB.SCM(SCH_1):P3V3_AUX    I66 @SCM_LIB.SCM(SCH_1):PAGE21
     2 EMMC_DT1_R @SCM_LIB.SCM(SCH_1):EMMC_DT1_R    I66 @SCM_LIB.SCM(SCH_1):PAGE21

R657 Q_RES_0402LF-10K,1%,1/16W,EMPTB
     1 P3V3_AUX @SCM_LIB.SCM(SCH_1):P3V3_AUX    I63 @SCM_LIB.SCM(SCH_1):PAGE21
     2 EMMC_DT2_R @SCM_LIB.SCM(SCH_1):EMMC_DT2_R    I63 @SCM_LIB.SCM(SCH_1):PAGE21

R658 Q_RES_0402LF-10K,1%,1/16W,EMPTB
     1 P3V3_AUX @SCM_LIB.SCM(SCH_1):P3V3_AUX    I62 @SCM_LIB.SCM(SCH_1):PAGE21
     2 EMMC_DT3_R @SCM_LIB.SCM(SCH_1):EMMC_DT3_R    I62 @SCM_LIB.SCM(SCH_1):PAGE21

R659 Q_RES_0402LF-10K,1%,1/16W,EMPTB
     1 P3V3_AUX @SCM_LIB.SCM(SCH_1):P3V3_AUX    I64 @SCM_LIB.SCM(SCH_1):PAGE21
     2 EMMC_DT4_R @SCM_LIB.SCM(SCH_1):EMMC_DT4_R    I64 @SCM_LIB.SCM(SCH_1):PAGE21

R660 Q_RES_0402LF-10K,1%,1/16W,EMPTB
     1 P3V3_AUX @SCM_LIB.SCM(SCH_1):P3V3_AUX    I61 @SCM_LIB.SCM(SCH_1):PAGE21
     2 EMMC_DT5_R @SCM_LIB.SCM(SCH_1):EMMC_DT5_R    I61 @SCM_LIB.SCM(SCH_1):PAGE21

R661 Q_RES_0402LF-10K,1%,1/16W,EMPTB
     1 P3V3_AUX @SCM_LIB.SCM(SCH_1):P3V3_AUX    I60 @SCM_LIB.SCM(SCH_1):PAGE21
     2 EMMC_DT6_R @SCM_LIB.SCM(SCH_1):EMMC_DT6_R    I60 @SCM_LIB.SCM(SCH_1):PAGE21

R662 Q_RES_0402LF-10K,1%,1/16W,EMPTB
     1 P3V3_AUX @SCM_LIB.SCM(SCH_1):P3V3_AUX    I58 @SCM_LIB.SCM(SCH_1):PAGE21
     2 EMMC_DT7_R @SCM_LIB.SCM(SCH_1):EMMC_DT7_R    I58 @SCM_LIB.SCM(SCH_1):PAGE21

R663 Q_RES_0402LF-10K,1%,1/16W,EMPTB
     1 P3V3_AUX @SCM_LIB.SCM(SCH_1):P3V3_AUX    I59 @SCM_LIB.SCM(SCH_1):PAGE21
     2 EMMC_CMD_R @SCM_LIB.SCM(SCH_1):EMMC_CMD_R    I59 @SCM_LIB.SCM(SCH_1):PAGE21

R664 Q_RES_0402LF-1K,1%,1/16W,EMPTYB
     1 SPI_BMC_BT_WP1_N_R @SCM_LIB.SCM(SCH_1):SPI_BMC_BT_WP1_N_R   I128 @SCM_LIB.SCM(SCH_1):PAGE21
     2    GND @SCM_LIB.SCM(SCH_1):GND   I128 @SCM_LIB.SCM(SCH_1):PAGE21

R665 Q_RES_0402LF-1K,1%,1/16W,EMPTYB
     1 SPI_BMC_BT_WP0_N_R @SCM_LIB.SCM(SCH_1):SPI_BMC_BT_WP0_N_R   I125 @SCM_LIB.SCM(SCH_1):PAGE21
     2    GND @SCM_LIB.SCM(SCH_1):GND   I125 @SCM_LIB.SCM(SCH_1):PAGE21

R666 Q_RES_0402LF-0,5%,1/16W,CHIP,CA
     1 USB3_01_MUX_FB_TXN @SCM_LIB.SCM(SCH_1):USB3_01_MUX_FB_TXN   I124 @SCM_LIB.SCM(SCH_1):PAGE29
     2 USB3_01_FB_TXN @SCM_LIB.SCM(SCH_1):USB3_01_FB_TXN   I124 @SCM_LIB.SCM(SCH_1):PAGE29

R667 Q_RES_0402LF-4.7K,1%,1/16W,CHIA
     1 P3V3_AUX @SCM_LIB.SCM(SCH_1):P3V3_AUX   I147 @SCM_LIB.SCM(SCH_1):PAGE28
     2 LED_POSTCODE_INT @SCM_LIB.SCM(SCH_1):LED_POSTCODE_INT   I147 @SCM_LIB.SCM(SCH_1):PAGE28

R668 Q_RES_0402LF-0,5%,1/16W,CHIP,CA
     1 USB3_01_MUX_FB_RXN @SCM_LIB.SCM(SCH_1):USB3_01_MUX_FB_RXN   I111 @SCM_LIB.SCM(SCH_1):PAGE29
     2 USB3_01_FB_RXN @SCM_LIB.SCM(SCH_1):USB3_01_FB_RXN   I111 @SCM_LIB.SCM(SCH_1):PAGE29

R669 Q_RES_0402LF-0,5%,1/16W,CHIP,CA
     1 LED_POSTCODE_7 @SCM_LIB.SCM(SCH_1):LED_POSTCODE_7    I48 @SCM_LIB.SCM(SCH_1):PAGE47
     2 LED_POSTCODE_7_R1 @SCM_LIB.SCM(SCH_1):LED_POSTCODE_7_R1    I48 @SCM_LIB.SCM(SCH_1):PAGE47

R670 Q_RES_0402LF-0,5%,1/16W,CHIP,CA
     1 DEBUG_PORT_PRSNT_BUF_R_EN @SCM_LIB.SCM(SCH_1):DEBUG_PORT_PRSNT_BUF_R_EN   I104 @SCM_LIB.SCM(SCH_1):PAGE28
     2 DEBUG_PORT_PRSNT_BUF_EN @SCM_LIB.SCM(SCH_1):DEBUG_PORT_PRSNT_BUF_EN   I104 @SCM_LIB.SCM(SCH_1):PAGE28

R671 Q_RES_0402LF-0,5%,1/16W,CHIP,CA
     1 USB3_01_TXP_C @SCM_LIB.SCM(SCH_1):USB3_01_TXP_C   I141 @SCM_LIB.SCM(SCH_1):PAGE29
     2 USB3_FPNL_TXP @SCM_LIB.SCM(SCH_1):USB3_FPNL_TXP   I141 @SCM_LIB.SCM(SCH_1):PAGE29

R672 Q_RES_0402LF-0,5%,1/16W,CHIP,CA
     1 USB3_01_TXN_C @SCM_LIB.SCM(SCH_1):USB3_01_TXN_C   I144 @SCM_LIB.SCM(SCH_1):PAGE29
     2 USB3_FPNL_TXN @SCM_LIB.SCM(SCH_1):USB3_FPNL_TXN   I144 @SCM_LIB.SCM(SCH_1):PAGE29

R673 Q_RES_0402LF-0,5%,1/16W,CHIP,CA
     1 USB3_01_MUX_FB_TXP @SCM_LIB.SCM(SCH_1):USB3_01_MUX_FB_TXP   I122 @SCM_LIB.SCM(SCH_1):PAGE29
     2 USB3_01_FB_TXP @SCM_LIB.SCM(SCH_1):USB3_01_FB_TXP   I122 @SCM_LIB.SCM(SCH_1):PAGE29

R674 Q_RES_0402LF-0,5%,1/16W,CHIP,CA
     1 LED_POSTCODE_6 @SCM_LIB.SCM(SCH_1):LED_POSTCODE_6    I50 @SCM_LIB.SCM(SCH_1):PAGE47
     2 LED_POSTCODE_6_R1 @SCM_LIB.SCM(SCH_1):LED_POSTCODE_6_R1    I50 @SCM_LIB.SCM(SCH_1):PAGE47

R675 Q_RES_0402LF-0,5%,1/16W,CHIP,CA
     1 USB3_01_MUX_FB_RXP @SCM_LIB.SCM(SCH_1):USB3_01_MUX_FB_RXP   I109 @SCM_LIB.SCM(SCH_1):PAGE29
     2 USB3_01_FB_RXP @SCM_LIB.SCM(SCH_1):USB3_01_FB_RXP   I109 @SCM_LIB.SCM(SCH_1):PAGE29

R676 Q_RES_0402LF-0,5%,1/16W,CHIP,CA
     1 LED_POSTCODE_5 @SCM_LIB.SCM(SCH_1):LED_POSTCODE_5    I52 @SCM_LIB.SCM(SCH_1):PAGE47
     2 LED_POSTCODE_5_R1 @SCM_LIB.SCM(SCH_1):LED_POSTCODE_5_R1    I52 @SCM_LIB.SCM(SCH_1):PAGE47

R677 Q_RES_0402LF-10K,1%,1/16W,CHIPA
     1 U56_ADJ_1 @SCM_LIB.SCM(SCH_1):U56_ADJ_1    I57 @SCM_LIB.SCM(SCH_1):PAGE51
     2    GND @SCM_LIB.SCM(SCH_1):GND    I57 @SCM_LIB.SCM(SCH_1):PAGE51

R678 Q_RES_0402LF-33.2,1%,1/16W,EMPA
     1 SPI_BMC_CLK_R @SCM_LIB.SCM(SCH_1):SPI_BMC_CLK_R   I239 @SCM_LIB.SCM(SCH_1):PAGE13
     2 QSPI_2_PLD_CLK @SCM_LIB.SCM(SCH_1):QSPI_2_PLD_CLK   I239 @SCM_LIB.SCM(SCH_1):PAGE13

R679 Q_RES_0402LF-33.2,1%,1/16W,EMPA
     1 SPI_BMC_MOSI_IO0_R @SCM_LIB.SCM(SCH_1):SPI_BMC_MOSI_IO0_R   I247 @SCM_LIB.SCM(SCH_1):PAGE13
     2 QSPI_2_PLD_IO0 @SCM_LIB.SCM(SCH_1):QSPI_2_PLD_IO0   I247 @SCM_LIB.SCM(SCH_1):PAGE13

R680 Q_RES_0402LF-33.2,1%,1/16W,EMPA
     1 SPI_BMC_MISO_IO1_R @SCM_LIB.SCM(SCH_1):SPI_BMC_MISO_IO1_R   I248 @SCM_LIB.SCM(SCH_1):PAGE13
     2 QSPI_2_PLD_IO1 @SCM_LIB.SCM(SCH_1):QSPI_2_PLD_IO1   I248 @SCM_LIB.SCM(SCH_1):PAGE13

R681 Q_RES_0402LF-33.2,1%,1/16W,EMPA
     1 SPI_BMC_IO2_R @SCM_LIB.SCM(SCH_1):SPI_BMC_IO2_R   I245 @SCM_LIB.SCM(SCH_1):PAGE13
     2 QSPI_2_PLD_IO2 @SCM_LIB.SCM(SCH_1):QSPI_2_PLD_IO2   I245 @SCM_LIB.SCM(SCH_1):PAGE13

R682 Q_RES_0402LF-33.2,1%,1/16W,EMPA
     1 SPI_BMC_IO3_R @SCM_LIB.SCM(SCH_1):SPI_BMC_IO3_R   I246 @SCM_LIB.SCM(SCH_1):PAGE13
     2 QSPI_2_PLD_IO3 @SCM_LIB.SCM(SCH_1):QSPI_2_PLD_IO3   I246 @SCM_LIB.SCM(SCH_1):PAGE13

R683 Q_RES_0402LF-4.7K,1%,1/16W,CHIA
     1 P3V3_AUX @SCM_LIB.SCM(SCH_1):P3V3_AUX   I188 @SCM_LIB.SCM(SCH_1):PAGE13
     2 PU_SPI1WP_N @SCM_LIB.SCM(SCH_1):PU_SPI1WP_N   I188 @SCM_LIB.SCM(SCH_1):PAGE13

R684 Q_RES_0402LF-1K,1%,1/16W,EMPTYB
     1 BMC_EMMC_WP_N @SCM_LIB.SCM(SCH_1):BMC_EMMC_WP_N   I163 @SCM_LIB.SCM(SCH_1):PAGE14
     2    GND @SCM_LIB.SCM(SCH_1):GND   I163 @SCM_LIB.SCM(SCH_1):PAGE14

R685 Q_RES_0402LF-1K,1%,1/16W,EMPTYB
     1 BMC_EMMC_CD_N @SCM_LIB.SCM(SCH_1):BMC_EMMC_CD_N   I165 @SCM_LIB.SCM(SCH_1):PAGE14
     2    GND @SCM_LIB.SCM(SCH_1):GND   I165 @SCM_LIB.SCM(SCH_1):PAGE14

R686 Q_RES_0402LF-4.7K,1%,1/16W,EMPB
     1 P3V3_AUX @SCM_LIB.SCM(SCH_1):P3V3_AUX   I164 @SCM_LIB.SCM(SCH_1):PAGE14
     2 BMC_EMMC_WP_N @SCM_LIB.SCM(SCH_1):BMC_EMMC_WP_N   I164 @SCM_LIB.SCM(SCH_1):PAGE14

R687 Q_RES_0402LF-4.7K,1%,1/16W,EMPB
     1 P3V3_AUX @SCM_LIB.SCM(SCH_1):P3V3_AUX   I166 @SCM_LIB.SCM(SCH_1):PAGE14
     2 BMC_EMMC_CD_N @SCM_LIB.SCM(SCH_1):BMC_EMMC_CD_N   I166 @SCM_LIB.SCM(SCH_1):PAGE14

R688 Q_RES_0402LF-33.2,1%,1/16W,CHIA
     1 RST_SGPIO_RESET_BMC_N @SCM_LIB.SCM(SCH_1):RST_SGPIO_RESET_BMC_N   I383 @SCM_LIB.SCM(SCH_1):PAGE13
     2 RST_SGPIO_RESET_N @SCM_LIB.SCM(SCH_1):RST_SGPIO_RESET_N   I383 @SCM_LIB.SCM(SCH_1):PAGE13

R689 Q_RES_0402LF-33.2,1%,1/16W,EMPA
     1 IRQ_SGPIO_N @SCM_LIB.SCM(SCH_1):IRQ_SGPIO_N   I398 @SCM_LIB.SCM(SCH_1):PAGE13
     2 IRQ_SGPIO_BMC_N @SCM_LIB.SCM(SCH_1):IRQ_SGPIO_BMC_N   I398 @SCM_LIB.SCM(SCH_1):PAGE13

R690 Q_RES_0402LF-33.2,1%,1/16W,CHIA
     1 IRQ_SGPIO_R_N @SCM_LIB.SCM(SCH_1):IRQ_SGPIO_R_N   I149 @SCM_LIB.SCM(SCH_1):PAGE35
     2 IRQ_SGPIO_N @SCM_LIB.SCM(SCH_1):IRQ_SGPIO_N   I149 @SCM_LIB.SCM(SCH_1):PAGE35

R691 Q_RES_0402LF-33.2,1%,1/16W,CHIA
     1 RST_SGPIO_RESET_R_N @SCM_LIB.SCM(SCH_1):RST_SGPIO_RESET_R_N   I148 @SCM_LIB.SCM(SCH_1):PAGE35
     2 RST_SGPIO_RESET_N @SCM_LIB.SCM(SCH_1):RST_SGPIO_RESET_N   I148 @SCM_LIB.SCM(SCH_1):PAGE35

R692 Q_RES_0402LF-2.2K,5%,1/16W,CHIA
     1 P3V3_AUX @SCM_LIB.SCM(SCH_1):P3V3_AUX   I238 @SCM_LIB.SCM(SCH_1):PAGE27
     2 SMB_BMC_MM15_SDA @SCM_LIB.SCM(SCH_1):SMB_BMC_MM15_SDA   I238 @SCM_LIB.SCM(SCH_1):PAGE27

R693 Q_RES_0402LF-33.2,1%,1/16W,CHIA
     1 DEBUG_PORT_PRSNT @SCM_LIB.SCM(SCH_1):DEBUG_PORT_PRSNT   I222 @SCM_LIB.SCM(SCH_1):PAGE29
     2 DEBUG_PORT_PRSNT_R @SCM_LIB.SCM(SCH_1):DEBUG_PORT_PRSNT_R   I222 @SCM_LIB.SCM(SCH_1):PAGE29

R694 Q_RES_0402LF-100,1%,1/16W,CHIPA
     1 USB3_MUX_PD @SCM_LIB.SCM(SCH_1):USB3_MUX_PD   I155 @SCM_LIB.SCM(SCH_1):PAGE29
     2    GND @SCM_LIB.SCM(SCH_1):GND   I155 @SCM_LIB.SCM(SCH_1):PAGE29

R695 Q_RES_0402LF-0,5%,1/16W,CHIP,CA
     1 LED_POSTCODE_4 @SCM_LIB.SCM(SCH_1):LED_POSTCODE_4    I54 @SCM_LIB.SCM(SCH_1):PAGE47
     2 LED_POSTCODE_4_R1 @SCM_LIB.SCM(SCH_1):LED_POSTCODE_4_R1    I54 @SCM_LIB.SCM(SCH_1):PAGE47

R696 Q_RES_0402LF-0,5%,1/16W,CHIP,CA
     1 LED_POSTCODE_3 @SCM_LIB.SCM(SCH_1):LED_POSTCODE_3    I56 @SCM_LIB.SCM(SCH_1):PAGE47
     2 LED_POSTCODE_3_R1 @SCM_LIB.SCM(SCH_1):LED_POSTCODE_3_R1    I56 @SCM_LIB.SCM(SCH_1):PAGE47

R697 Q_RES_0402LF-0,5%,1/16W,CHIP,CA
     1 LED_POSTCODE_2 @SCM_LIB.SCM(SCH_1):LED_POSTCODE_2    I58 @SCM_LIB.SCM(SCH_1):PAGE47
     2 LED_POSTCODE_2_R1 @SCM_LIB.SCM(SCH_1):LED_POSTCODE_2_R1    I58 @SCM_LIB.SCM(SCH_1):PAGE47

R698 Q_RES_0402LF-0,5%,1/16W,CHIP,CA
     1 LED_POSTCODE_1 @SCM_LIB.SCM(SCH_1):LED_POSTCODE_1    I60 @SCM_LIB.SCM(SCH_1):PAGE47
     2 LED_POSTCODE_1_R1 @SCM_LIB.SCM(SCH_1):LED_POSTCODE_1_R1    I60 @SCM_LIB.SCM(SCH_1):PAGE47

R699 Q_RES_0402LF-4.7K,1%,1/16W,EMPA
     1 P3V3_AUX @SCM_LIB.SCM(SCH_1):P3V3_AUX   I163 @SCM_LIB.SCM(SCH_1):PAGE27
     2 SPI_BMC_BOOT_CLK @SCM_LIB.SCM(SCH_1):SPI_BMC_BOOT_CLK   I163 @SCM_LIB.SCM(SCH_1):PAGE27

R700 Q_RES_0402LF-0,5%,1/16W,CHIP,CA
     1 LED_POSTCODE_0 @SCM_LIB.SCM(SCH_1):LED_POSTCODE_0    I62 @SCM_LIB.SCM(SCH_1):PAGE47
     2 LED_POSTCODE_0_R1 @SCM_LIB.SCM(SCH_1):LED_POSTCODE_0_R1    I62 @SCM_LIB.SCM(SCH_1):PAGE47

R701 Q_RES_0402LF-0,5%,1/16W,CHIP,CA
     1 PWRGD_SYS_PWROK @SCM_LIB.SCM(SCH_1):PWRGD_SYS_PWROK   I125 @SCM_LIB.SCM(SCH_1):PAGE28
     2 PWRGD_SYS_PWROK_R1 @SCM_LIB.SCM(SCH_1):PWRGD_SYS_PWROK_R1   I125 @SCM_LIB.SCM(SCH_1):PAGE28

R702 Q_RES_0402LF-0,5%,1/16W,CHIP,CA
     1 RST_PLTRST_N @SCM_LIB.SCM(SCH_1):RST_PLTRST_N   I126 @SCM_LIB.SCM(SCH_1):PAGE28
     2 RST_PLTRST_R2_N @SCM_LIB.SCM(SCH_1):RST_PLTRST_R2_N   I126 @SCM_LIB.SCM(SCH_1):PAGE28

R703 Q_RES_0402LF-0,5%,1/16W,CHIP,CA
     1 PWRGD_DSW_PWROK @SCM_LIB.SCM(SCH_1):PWRGD_DSW_PWROK   I127 @SCM_LIB.SCM(SCH_1):PAGE28
     2 PWRGD_DSW_PWROK_R3 @SCM_LIB.SCM(SCH_1):PWRGD_DSW_PWROK_R3   I127 @SCM_LIB.SCM(SCH_1):PAGE28

R705 Q_RES_0402LF-33.2,1%,1/16W,CHIA
     1 FM_BMC_DBP_PRESENT_N @SCM_LIB.SCM(SCH_1):FM_BMC_DBP_PRESENT_N   I353 @SCM_LIB.SCM(SCH_1):PAGE12
     2 FM_BMC_DBP_PRESENT_R_N @SCM_LIB.SCM(SCH_1):FM_BMC_DBP_PRESENT_R_N   I353 @SCM_LIB.SCM(SCH_1):PAGE12

R706 Q_RES_0402LF-4.7K,1%,1/16W,CHIA
     1 P3V3_AUX @SCM_LIB.SCM(SCH_1):P3V3_AUX   I354 @SCM_LIB.SCM(SCH_1):PAGE12
     2 FM_BMC_DBP_PRESENT_N @SCM_LIB.SCM(SCH_1):FM_BMC_DBP_PRESENT_N   I354 @SCM_LIB.SCM(SCH_1):PAGE12

R707 Q_RES_0402LF-0,5%,1/16W,CHIP,CA
     1 FM_DEBUG_PORT_R_PRSNT_N @SCM_LIB.SCM(SCH_1):FM_DEBUG_PORT_R_PRSNT_N   I201 @SCM_LIB.SCM(SCH_1):PAGE29
     2 FM_DEBUG_PORT_PRSNT_N @SCM_LIB.SCM(SCH_1):FM_DEBUG_PORT_PRSNT_N   I201 @SCM_LIB.SCM(SCH_1):PAGE29

R708 Q_RES_0402LF-0,5%,1/16W,CHIP,CA
     1 EN_P1V2_AUX @SCM_LIB.SCM(SCH_1):EN_P1V2_AUX    I38 @SCM_LIB.SCM(SCH_1):PAGE55
     2 EN_P1V2_AUX_R @SCM_LIB.SCM(SCH_1):EN_P1V2_AUX_R    I38 @SCM_LIB.SCM(SCH_1):PAGE55

R709 Q_RES_0402LF-2.2K,5%,1/16W,CHIA
     1 P3V3_RGM @SCM_LIB.SCM(SCH_1):P3V3_RGM   I145 @SCM_LIB.SCM(SCH_1):PAGE52
     2 PWRGD_P3V3_RGM_R @SCM_LIB.SCM(SCH_1):PWRGD_P3V3_RGM_R   I145 @SCM_LIB.SCM(SCH_1):PAGE52

R710 Q_RES_0402LF-100K,1%,1/16W,CHIA
     1 P3V3_AUX @SCM_LIB.SCM(SCH_1):P3V3_AUX    I55 @SCM_LIB.SCM(SCH_1):PAGE22
     2 U43_CT @SCM_LIB.SCM(SCH_1):U43_CT    I55 @SCM_LIB.SCM(SCH_1):PAGE22

R711 Q_RES_0402LF-0,5%,1/16W,EMPTY,A
     1 PWRGD_PSU_AC_PWROK @SCM_LIB.SCM(SCH_1):PWRGD_PSU_AC_PWROK    I49 @SCM_LIB.SCM(SCH_1):PAGE22
     2 PWRGD_P1V0_AUX_DELAY @SCM_LIB.SCM(SCH_1):PWRGD_P1V0_AUX_DELAY    I49 @SCM_LIB.SCM(SCH_1):PAGE22

R712 Q_RES_0402LF-10K,1%,1/16W,EMPTA
     1 P3V3_AUX @SCM_LIB.SCM(SCH_1):P3V3_AUX   I153 @SCM_LIB.SCM(SCH_1):PAGE29
     2 USB3_MUX_PD @SCM_LIB.SCM(SCH_1):USB3_MUX_PD   I153 @SCM_LIB.SCM(SCH_1):PAGE29

R713 Q_RES_0402LF-33.2,1%,1/16W,CHIA
     1 LPC_ESPI_SEL_R @SCM_LIB.SCM(SCH_1):LPC_ESPI_SEL_R   I228 @SCM_LIB.SCM(SCH_1):PAGE17
     2 LPC_ESPI_SEL @SCM_LIB.SCM(SCH_1):LPC_ESPI_SEL   I228 @SCM_LIB.SCM(SCH_1):PAGE17

R714 Q_RES_0402LF-2K,1%,1/16W,CHIP,A
     1 LPC_ESPI_SEL @SCM_LIB.SCM(SCH_1):LPC_ESPI_SEL   I165 @SCM_LIB.SCM(SCH_1):PAGE27
     2 LPC_ESPI_SEL_R1 @SCM_LIB.SCM(SCH_1):LPC_ESPI_SEL_R1   I165 @SCM_LIB.SCM(SCH_1):PAGE27

R715 Q_RES_0402LF-33.2,1%,1/16W,CHIA
     1 UART_BMC_5_TXD_BUF1 @SCM_LIB.SCM(SCH_1):UART_BMC_5_TXD_BUF1   I225 @SCM_LIB.SCM(SCH_1):PAGE30
     2 UART_BMC_5_TXD_BUF1_R @SCM_LIB.SCM(SCH_1):UART_BMC_5_TXD_BUF1_R   I225 @SCM_LIB.SCM(SCH_1):PAGE30

R716 Q_RES_0402LF-10K,1%,1/16W,CHIPA
     1 P5V_AUX @SCM_LIB.SCM(SCH_1):P5V_AUX   I230 @SCM_LIB.SCM(SCH_1):PAGE17
     2 LPC_ESPI_SEL_N @SCM_LIB.SCM(SCH_1):LPC_ESPI_SEL_N   I230 @SCM_LIB.SCM(SCH_1):PAGE17

R717 Q_RES_0402LF-4.7K,1%,1/16W,CHIA
     1 P3V3_AUX @SCM_LIB.SCM(SCH_1):P3V3_AUX   I174 @SCM_LIB.SCM(SCH_1):PAGE15
     2 RST_BMC_RSTBTN_OUT_N @SCM_LIB.SCM(SCH_1):RST_BMC_RSTBTN_OUT_N   I174 @SCM_LIB.SCM(SCH_1):PAGE15

R718 Q_RES_0402LF-33.2,1%,1/16W,CHIA
     1 RST_PLTRST_N @SCM_LIB.SCM(SCH_1):RST_PLTRST_N   I157 @SCM_LIB.SCM(SCH_1):PAGE34
     2 RST_PLTRST_R1_N @SCM_LIB.SCM(SCH_1):RST_PLTRST_R1_N   I157 @SCM_LIB.SCM(SCH_1):PAGE34

R719 Q_RES_0402LF-0,5%,1/16W,EMPTY,A
     1 PWRGD_PSU_AC_PWROK @SCM_LIB.SCM(SCH_1):PWRGD_PSU_AC_PWROK   I128 @SCM_LIB.SCM(SCH_1):PAGE28
     2 PWRGD_DSW_PWROK_R3 @SCM_LIB.SCM(SCH_1):PWRGD_DSW_PWROK_R3   I128 @SCM_LIB.SCM(SCH_1):PAGE28

R720 Q_RES_0402LF-0,5%,1/16W,CHIP,CA
     1 FM_CPU_MSMI_CATERR_LVT3_N @SCM_LIB.SCM(SCH_1):FM_CPU_MSMI_CATERR_LVT3_N   I144 @SCM_LIB.SCM(SCH_1):PAGE28
     2 FM_CPU_MSMI_CATERR_LVT3_R3_N @SCM_LIB.SCM(SCH_1):FM_CPU_MSMI_CATERR_LVT3_R3_N   I144 @SCM_LIB.SCM(SCH_1):PAGE28

R721 Q_RES_0402LF-0,5%,1/16W,CHIP,CA
     1 FM_SLPS3_GF_N @SCM_LIB.SCM(SCH_1):FM_SLPS3_GF_N   I145 @SCM_LIB.SCM(SCH_1):PAGE28
     2 FM_SLPS3_GF_R2_N @SCM_LIB.SCM(SCH_1):FM_SLPS3_GF_R2_N   I145 @SCM_LIB.SCM(SCH_1):PAGE28

R722 Q_RES_0402LF-0,5%,1/16W,CHIP,CA
     1 FM_SLPS3_GF_R1_N @SCM_LIB.SCM(SCH_1):FM_SLPS3_GF_R1_N   I350 @SCM_LIB.SCM(SCH_1):PAGE13
     2 FM_SLPS3_GF_N @SCM_LIB.SCM(SCH_1):FM_SLPS3_GF_N   I350 @SCM_LIB.SCM(SCH_1):PAGE13

R724 Q_RES_0402LF-33.2,1%,1/16W,CHIA
     1 SPI_BMC_BIOS_ROM_IO2 @SCM_LIB.SCM(SCH_1):SPI_BMC_BIOS_ROM_IO2   I333 @SCM_LIB.SCM(SCH_1):PAGE44
     2 SPI_BMC_BIOS_ROM_R_IO2 @SCM_LIB.SCM(SCH_1):SPI_BMC_BIOS_ROM_R_IO2   I333 @SCM_LIB.SCM(SCH_1):PAGE44

R725 Q_RES_0402LF-33.2,1%,1/16W,CHIA
     1 SPI_BMC_BIOS_ROM_IO3 @SCM_LIB.SCM(SCH_1):SPI_BMC_BIOS_ROM_IO3   I334 @SCM_LIB.SCM(SCH_1):PAGE44
     2 SPI_BMC_BIOS_ROM_R_IO3 @SCM_LIB.SCM(SCH_1):SPI_BMC_BIOS_ROM_R_IO3   I334 @SCM_LIB.SCM(SCH_1):PAGE44

R726 Q_RES_0402LF-0,5%,1/16W,CHIP,CA
     1 SPA_SIN_SW_BUF_R @SCM_LIB.SCM(SCH_1):SPA_SIN_SW_BUF_R   I266 @SCM_LIB.SCM(SCH_1):PAGE30
     2 SPA_SIN_SW_BUF @SCM_LIB.SCM(SCH_1):SPA_SIN_SW_BUF   I266 @SCM_LIB.SCM(SCH_1):PAGE30

R728 Q_RES_0402LF-0,5%,1/16W,CHIP,CA
     1 SPI_BMC_BIOS_CS0_N @SCM_LIB.SCM(SCH_1):SPI_BMC_BIOS_CS0_N   I336 @SCM_LIB.SCM(SCH_1):PAGE44
     2 SPI_BMC_BIOS_SOURCE_CS0_N @SCM_LIB.SCM(SCH_1):SPI_BMC_BIOS_SOURCE_CS0_N   I336 @SCM_LIB.SCM(SCH_1):PAGE44

R730 Q_RES_0402LF-4.7K,1%,1/16W,CHIA
     1 P3V3_AUX @SCM_LIB.SCM(SCH_1):P3V3_AUX   I204 @SCM_LIB.SCM(SCH_1):PAGE29
     2 FM_DEBUG_PORT_R_PRSNT_N @SCM_LIB.SCM(SCH_1):FM_DEBUG_PORT_R_PRSNT_N   I204 @SCM_LIB.SCM(SCH_1):PAGE29

R731 Q_RES_0402LF-0,5%,1/16W,CHIP,CA
     1 SMB_DEBUG_AUX_LVC3_USB_SDA @SCM_LIB.SCM(SCH_1):SMB_DEBUG_AUX_LVC3_USB_SDA   I135 @SCM_LIB.SCM(SCH_1):PAGE29
     2 SMB_DEBUG_AUX_LVC3_USB_R2_SDA @SCM_LIB.SCM(SCH_1):SMB_DEBUG_AUX_LVC3_USB_R2_SDA   I135 @SCM_LIB.SCM(SCH_1):PAGE29

R732 Q_RES_0402LF-0,5%,1/16W,CHIP,CA
     1 SMB_DEBUG_AUX_LVC3_USB_SCL @SCM_LIB.SCM(SCH_1):SMB_DEBUG_AUX_LVC3_USB_SCL   I136 @SCM_LIB.SCM(SCH_1):PAGE29
     2 SMB_DEBUG_AUX_LVC3_USB_R2_SCL @SCM_LIB.SCM(SCH_1):SMB_DEBUG_AUX_LVC3_USB_R2_SCL   I136 @SCM_LIB.SCM(SCH_1):PAGE29

R733 Q_RES_0402LF-0,5%,1/16W,CHIP,CA
     1 REAR_ID_RST_BTN_N @SCM_LIB.SCM(SCH_1):REAR_ID_RST_BTN_N   I154 @SCM_LIB.SCM(SCH_1):PAGE50
     2 FM_DEBUG_RST_BTN_N @SCM_LIB.SCM(SCH_1):FM_DEBUG_RST_BTN_N   I154 @SCM_LIB.SCM(SCH_1):PAGE50

R734 Q_RES_0402LF-0,5%,1/16W,CHIP,CA
     1 REAR_PWR_BTN_N @SCM_LIB.SCM(SCH_1):REAR_PWR_BTN_N   I152 @SCM_LIB.SCM(SCH_1):PAGE50
     2 FM_DEBUG_PWR_BTN_N @SCM_LIB.SCM(SCH_1):FM_DEBUG_PWR_BTN_N   I152 @SCM_LIB.SCM(SCH_1):PAGE50

R735 Q_RES_0402LF-1K,1%,1/16W,CHIP,A
     1 P3V3_AUX @SCM_LIB.SCM(SCH_1):P3V3_AUX   I166 @SCM_LIB.SCM(SCH_1):PAGE28
     2 FM_UART_SWITCH_N @SCM_LIB.SCM(SCH_1):FM_UART_SWITCH_N   I166 @SCM_LIB.SCM(SCH_1):PAGE28

R736 Q_RES_0402LF-1K,1%,1/16W,CHIP,A
     1 P3V3_AUX @SCM_LIB.SCM(SCH_1):P3V3_AUX   I162 @SCM_LIB.SCM(SCH_1):PAGE28
     2 FM_SOL_UART_CH_SEL_R3 @SCM_LIB.SCM(SCH_1):FM_SOL_UART_CH_SEL_R3   I162 @SCM_LIB.SCM(SCH_1):PAGE28

R737 Q_RES_0402LF-4.7K,1%,1/16W,EMPA
     1 P3V3_AUX @SCM_LIB.SCM(SCH_1):P3V3_AUX   I192 @SCM_LIB.SCM(SCH_1):PAGE30
     2 SPA_SIN_SW_BUF @SCM_LIB.SCM(SCH_1):SPA_SIN_SW_BUF   I192 @SCM_LIB.SCM(SCH_1):PAGE30

R738 Q_RES_0402LF-4.7K,1%,1/16W,CHIA
     1 P3V3_AUX @SCM_LIB.SCM(SCH_1):P3V3_AUX   I171 @SCM_LIB.SCM(SCH_1):PAGE28
     2 LED_POSTCODE_A0 @SCM_LIB.SCM(SCH_1):LED_POSTCODE_A0   I171 @SCM_LIB.SCM(SCH_1):PAGE28

R739 Q_RES_0402LF-4.7K,1%,1/16W,CHIA
     1 P3V3_AUX @SCM_LIB.SCM(SCH_1):P3V3_AUX   I169 @SCM_LIB.SCM(SCH_1):PAGE28
     2 LED_POSTCODE_A1 @SCM_LIB.SCM(SCH_1):LED_POSTCODE_A1   I169 @SCM_LIB.SCM(SCH_1):PAGE28

R740 Q_RES_0402LF-4.7K,1%,1/16W,CHIA
     1 P3V3_AUX @SCM_LIB.SCM(SCH_1):P3V3_AUX   I168 @SCM_LIB.SCM(SCH_1):PAGE28
     2 LED_POSTCODE_A2 @SCM_LIB.SCM(SCH_1):LED_POSTCODE_A2   I168 @SCM_LIB.SCM(SCH_1):PAGE28

R741 Q_RES_0402LF-4.7K,1%,1/16W,CHIA
     1 P3V3_AUX @SCM_LIB.SCM(SCH_1):P3V3_AUX   I197 @SCM_LIB.SCM(SCH_1):PAGE30
     2 UART_BMC_5_RXD_BUF @SCM_LIB.SCM(SCH_1):UART_BMC_5_RXD_BUF   I197 @SCM_LIB.SCM(SCH_1):PAGE30

R742 Q_RES_0402LF-4.7K,1%,1/16W,EMPA
     1 P3V3_AUX @SCM_LIB.SCM(SCH_1):P3V3_AUX   I195 @SCM_LIB.SCM(SCH_1):PAGE30
     2 SPA_SOUT_SW_BUF @SCM_LIB.SCM(SCH_1):SPA_SOUT_SW_BUF   I195 @SCM_LIB.SCM(SCH_1):PAGE30

R743 Q_RES_0402LF-100,1%,1/16W,EMPTA
     1 LED_POSTCODE_A0 @SCM_LIB.SCM(SCH_1):LED_POSTCODE_A0   I175 @SCM_LIB.SCM(SCH_1):PAGE28
     2    GND @SCM_LIB.SCM(SCH_1):GND   I175 @SCM_LIB.SCM(SCH_1):PAGE28

R744 Q_RES_0402LF-100,1%,1/16W,EMPTA
     1 LED_POSTCODE_A1 @SCM_LIB.SCM(SCH_1):LED_POSTCODE_A1   I173 @SCM_LIB.SCM(SCH_1):PAGE28
     2    GND @SCM_LIB.SCM(SCH_1):GND   I173 @SCM_LIB.SCM(SCH_1):PAGE28

R745 Q_RES_0402LF-100,1%,1/16W,EMPTA
     1 LED_POSTCODE_A2 @SCM_LIB.SCM(SCH_1):LED_POSTCODE_A2   I172 @SCM_LIB.SCM(SCH_1):PAGE28
     2    GND @SCM_LIB.SCM(SCH_1):GND   I172 @SCM_LIB.SCM(SCH_1):PAGE28

R746 Q_RES_0402LF-0,5%,1/16W,CHIP,CA
     1 IRQ_PCH_TPM_SPI_N @SCM_LIB.SCM(SCH_1):IRQ_PCH_TPM_SPI_N    I10 @SCM_LIB.SCM(SCH_1):PAGE36
     2 IRQ_PCH_TPM_SPI_R2_N @SCM_LIB.SCM(SCH_1):IRQ_PCH_TPM_SPI_R2_N    I10 @SCM_LIB.SCM(SCH_1):PAGE36

R747 Q_RES_0402LF-0,5%,1/16W,CHIP,CA
     1 FM_BMC_CRASHLOG_TRIG_N @SCM_LIB.SCM(SCH_1):FM_BMC_CRASHLOG_TRIG_N     I9 @SCM_LIB.SCM(SCH_1):PAGE36
     2 FM_BMC_CRASHLOG_TRIG_R2_N @SCM_LIB.SCM(SCH_1):FM_BMC_CRASHLOG_TRIG_R2_N     I9 @SCM_LIB.SCM(SCH_1):PAGE36

R748 Q_RES_0402LF-0,5%,1/16W,CHIP,CA
     1 PU_FPGA_NCONFIG @SCM_LIB.SCM(SCH_1):PU_FPGA_NCONFIG    I78 @SCM_LIB.SCM(SCH_1):PAGE36
     2 RST_ROT_CPU_N @SCM_LIB.SCM(SCH_1):RST_ROT_CPU_N    I78 @SCM_LIB.SCM(SCH_1):PAGE36

R749 Q_RES_0402LF-4.7K,1%,1/16W,CHIA
     1 P3V3_AUX @SCM_LIB.SCM(SCH_1):P3V3_AUX    I61 @SCM_LIB.SCM(SCH_1):PAGE42
     2 FM_BMC_CRASHLOG_TRIG_N @SCM_LIB.SCM(SCH_1):FM_BMC_CRASHLOG_TRIG_N    I61 @SCM_LIB.SCM(SCH_1):PAGE42

R750 Q_RES_0402LF-33.2,1%,1/16W,CHIA
     1 FM_BMC_DEBUG_SW_N @SCM_LIB.SCM(SCH_1):FM_BMC_DEBUG_SW_N    I82 @SCM_LIB.SCM(SCH_1):PAGE36
     2 FM_BMC_DEBUG_SW_R2_N @SCM_LIB.SCM(SCH_1):FM_BMC_DEBUG_SW_R2_N    I82 @SCM_LIB.SCM(SCH_1):PAGE36

R751 Q_RES_0402LF-2K,1%,1/16W,CHIP,A
     1 P3V3_AUX @SCM_LIB.SCM(SCH_1):P3V3_AUX    I83 @SCM_LIB.SCM(SCH_1):PAGE22
     2 PWRGD_P1V0_AUX_DELAY_R1 @SCM_LIB.SCM(SCH_1):PWRGD_P1V0_AUX_DELAY_R1    I83 @SCM_LIB.SCM(SCH_1):PAGE22

R752 Q_RES_0402LF-33.2,1%,1/16W,CHIA
     1 RST_SPI_FLASH_N @SCM_LIB.SCM(SCH_1):RST_SPI_FLASH_N    I67 @SCM_LIB.SCM(SCH_1):PAGE25
     2 RST_SPI_FLASH_R_N @SCM_LIB.SCM(SCH_1):RST_SPI_FLASH_R_N    I67 @SCM_LIB.SCM(SCH_1):PAGE25

R753 Q_RES_0402LF-4.7K,1%,1/16W,EMPA
     1 P3V3_AUX @SCM_LIB.SCM(SCH_1):P3V3_AUX   I233 @SCM_LIB.SCM(SCH_1):PAGE27
     2 SPI_BMC_BOOT_MISO @SCM_LIB.SCM(SCH_1):SPI_BMC_BOOT_MISO   I233 @SCM_LIB.SCM(SCH_1):PAGE27

R754 Q_RES_0402LF-4.7K,1%,1/16W,EMPA
     1 P3V3_RGM @SCM_LIB.SCM(SCH_1):P3V3_RGM   I213 @SCM_LIB.SCM(SCH_1):PAGE27
     2 UART_BMC_5_TXD_R @SCM_LIB.SCM(SCH_1):UART_BMC_5_TXD_R   I213 @SCM_LIB.SCM(SCH_1):PAGE27

R757 Q_RES_0402LF-33.2,1%,1/16W,CHIA
     1 UART_BMC_5_RXD_BUF1_R @SCM_LIB.SCM(SCH_1):UART_BMC_5_RXD_BUF1_R   I226 @SCM_LIB.SCM(SCH_1):PAGE30
     2 UART_BMC_5_RXD_R @SCM_LIB.SCM(SCH_1):UART_BMC_5_RXD_R   I226 @SCM_LIB.SCM(SCH_1):PAGE30

R758 Q_RES_0402LF-4.7K,1%,1/16W,CHIA
     1 P3V3_RGM @SCM_LIB.SCM(SCH_1):P3V3_RGM   I221 @SCM_LIB.SCM(SCH_1):PAGE30
     2 UART_BMC_5_RXD_R @SCM_LIB.SCM(SCH_1):UART_BMC_5_RXD_R   I221 @SCM_LIB.SCM(SCH_1):PAGE30

R759 Q_RES_0402LF-33.2,1%,1/16W,CHIA
     1 UART_BMC_5_RXD @SCM_LIB.SCM(SCH_1):UART_BMC_5_RXD   I208 @SCM_LIB.SCM(SCH_1):PAGE13
     2 UART_BMC_5_RXD_R @SCM_LIB.SCM(SCH_1):UART_BMC_5_RXD_R   I208 @SCM_LIB.SCM(SCH_1):PAGE13

R760 Q_RES_0402LF-33.2,1%,1/16W,CHIA
     1 FM_BMC_CRASHLOG_TRIG_N @SCM_LIB.SCM(SCH_1):FM_BMC_CRASHLOG_TRIG_N   I400 @SCM_LIB.SCM(SCH_1):PAGE13
     2 FM_BMC_CRASHLOG_TRIG_R1_N @SCM_LIB.SCM(SCH_1):FM_BMC_CRASHLOG_TRIG_R1_N   I400 @SCM_LIB.SCM(SCH_1):PAGE13

R761 Q_RES_0402LF-33.2,1%,1/16W,CHIA
     1 UART_6_BMC_TXD @SCM_LIB.SCM(SCH_1):UART_6_BMC_TXD   I473 @SCM_LIB.SCM(SCH_1):PAGE12
     2 UART_6_BMC_R_TXD @SCM_LIB.SCM(SCH_1):UART_6_BMC_R_TXD   I473 @SCM_LIB.SCM(SCH_1):PAGE12

R762 Q_RES_0402LF-33.2,1%,1/16W,CHIA
     1 UART_6_BMC_RXD @SCM_LIB.SCM(SCH_1):UART_6_BMC_RXD   I474 @SCM_LIB.SCM(SCH_1):PAGE12
     2 UART_6_BMC_R_RXD @SCM_LIB.SCM(SCH_1):UART_6_BMC_R_RXD   I474 @SCM_LIB.SCM(SCH_1):PAGE12

R763 Q_RES_0402LF-33.2,1%,1/16W,CHIA
     1 FM_PCH_BMC_THERMTRIP_N @SCM_LIB.SCM(SCH_1):FM_PCH_BMC_THERMTRIP_N   I402 @SCM_LIB.SCM(SCH_1):PAGE13
     2 FM_PLT_BMC_THERMTRIP_N_R @SCM_LIB.SCM(SCH_1):FM_PLT_BMC_THERMTRIP_N_R   I402 @SCM_LIB.SCM(SCH_1):PAGE13

R764 Q_RES_0402LF-0,5%,1/16W,EMPTY,A
     1 PWRGD_P1V8_AUX @SCM_LIB.SCM(SCH_1):PWRGD_P1V8_AUX    I41 @SCM_LIB.SCM(SCH_1):PAGE55
     2 EN_P1V2_AUX_R @SCM_LIB.SCM(SCH_1):EN_P1V2_AUX_R    I41 @SCM_LIB.SCM(SCH_1):PAGE55

R765 Q_RES_0402LF-4.7K,1%,1/16W,CHIA
     1 P3V3_AUX @SCM_LIB.SCM(SCH_1):P3V3_AUX   I239 @SCM_LIB.SCM(SCH_1):PAGE30
     2 UART_BMC_5_TXD_BUF_R @SCM_LIB.SCM(SCH_1):UART_BMC_5_TXD_BUF_R   I239 @SCM_LIB.SCM(SCH_1):PAGE30

R766 Q_RES_0402LF-33.2,1%,1/16W,CHIA
     1 UART_BMC_5_RXD_BUF1 @SCM_LIB.SCM(SCH_1):UART_BMC_5_RXD_BUF1   I237 @SCM_LIB.SCM(SCH_1):PAGE30
     2 UART_BMC_5_RXD_BUF1_SW @SCM_LIB.SCM(SCH_1):UART_BMC_5_RXD_BUF1_SW   I237 @SCM_LIB.SCM(SCH_1):PAGE30

R767 Q_RES_0402LF-33.2,1%,1/16W,CHIA
     1 FM_TPM_PRSNT_0_N @SCM_LIB.SCM(SCH_1):FM_TPM_PRSNT_0_N   I150 @SCM_LIB.SCM(SCH_1):PAGE34
     2 FM_TPM_PRSNT_0_R_N @SCM_LIB.SCM(SCH_1):FM_TPM_PRSNT_0_R_N   I150 @SCM_LIB.SCM(SCH_1):PAGE34

R768 Q_RES_0402LF-8.2K,5%,1/16W,CHIA
     1 P3V3_AUX @SCM_LIB.SCM(SCH_1):P3V3_AUX    I89 @SCM_LIB.SCM(SCH_1):PAGE50
     2 REAR_PWR_BTN_N @SCM_LIB.SCM(SCH_1):REAR_PWR_BTN_N    I89 @SCM_LIB.SCM(SCH_1):PAGE50

R769 Q_RES_0402LF-33.2,1%,1/16W,CHIA
     1 FM_THROTTLE_N @SCM_LIB.SCM(SCH_1):FM_THROTTLE_N   I140 @SCM_LIB.SCM(SCH_1):PAGE35
     2 FM_THROTTLE_R_N @SCM_LIB.SCM(SCH_1):FM_THROTTLE_R_N   I140 @SCM_LIB.SCM(SCH_1):PAGE35

R770 Q_RES_0402LF-4.7K,1%,1/16W,EMPA
     1    GND @SCM_LIB.SCM(SCH_1):GND   I217 @SCM_LIB.SCM(SCH_1):PAGE27
     2 UART_BMC_5_TXD_R @SCM_LIB.SCM(SCH_1):UART_BMC_5_TXD_R   I217 @SCM_LIB.SCM(SCH_1):PAGE27

R773 Q_RES_0402LF-33.2,1%,1/16W,CHIA
     1 FM_SLPS3_GF_N @SCM_LIB.SCM(SCH_1):FM_SLPS3_GF_N   I137 @SCM_LIB.SCM(SCH_1):PAGE35
     2 FM_SLPS3_GF_R_N @SCM_LIB.SCM(SCH_1):FM_SLPS3_GF_R_N   I137 @SCM_LIB.SCM(SCH_1):PAGE35

R774 Q_RES_0402LF-4.7K,1%,1/16W,CHIA
     1 P3V3_AUX @SCM_LIB.SCM(SCH_1):P3V3_AUX   I213 @SCM_LIB.SCM(SCH_1):PAGE13
     2 FM_SLPS3_GF_N @SCM_LIB.SCM(SCH_1):FM_SLPS3_GF_N   I213 @SCM_LIB.SCM(SCH_1):PAGE13

R775 Q_RES_0402LF-1K,1%,1/16W,CHIP,A
     1 BATTERY_DETECT @SCM_LIB.SCM(SCH_1):BATTERY_DETECT   I183 @SCM_LIB.SCM(SCH_1):PAGE15
     2 BATTERY_DETECT_R @SCM_LIB.SCM(SCH_1):BATTERY_DETECT_R   I183 @SCM_LIB.SCM(SCH_1):PAGE15

R776 Q_RES_0402LF-47K,1%,1/16W,CHIPA
     1 BATTERY_DETECT_R @SCM_LIB.SCM(SCH_1):BATTERY_DETECT_R   I184 @SCM_LIB.SCM(SCH_1):PAGE15
     2    GND @SCM_LIB.SCM(SCH_1):GND   I184 @SCM_LIB.SCM(SCH_1):PAGE15

R777 Q_RES_0402LF-200K,1%,1/16W,CHIA
     1 P3V_BAT_R @SCM_LIB.SCM(SCH_1):P3V_BAT_R   I289 @SCM_LIB.SCM(SCH_1):PAGE15
     2 P3V_BAT_R1 @SCM_LIB.SCM(SCH_1):P3V_BAT_R1   I289 @SCM_LIB.SCM(SCH_1):PAGE15

R778 Q_RES_0402LF-100K,1%,1/16W,CHIA
     1 P3V_BAT_SENSOR @SCM_LIB.SCM(SCH_1):P3V_BAT_SENSOR   I181 @SCM_LIB.SCM(SCH_1):PAGE15
     2    GND @SCM_LIB.SCM(SCH_1):GND   I181 @SCM_LIB.SCM(SCH_1):PAGE15

R779 Q_RES_0402LF-0,5%,1/16W,CHIP,CA
     1 P2V5_AUX @SCM_LIB.SCM(SCH_1):P2V5_AUX   I259 @SCM_LIB.SCM(SCH_1):PAGE17
     2 ADCVREFEXT1 @SCM_LIB.SCM(SCH_1):ADCVREFEXT1   I259 @SCM_LIB.SCM(SCH_1):PAGE17

R780 Q_RES_0402LF-0,5%,1/16W,EMPTY,A
     1 P2V5_AUX @SCM_LIB.SCM(SCH_1):P2V5_AUX   I256 @SCM_LIB.SCM(SCH_1):PAGE17
     2 ADCVREFEXT0 @SCM_LIB.SCM(SCH_1):ADCVREFEXT0   I256 @SCM_LIB.SCM(SCH_1):PAGE17

R781 Q_RES_0402LF-0,5%,1/16W,EMPTY,A
     1 P1V8_AUX @SCM_LIB.SCM(SCH_1):P1V8_AUX   I263 @SCM_LIB.SCM(SCH_1):PAGE17
     2 ADCVREFEXT1 @SCM_LIB.SCM(SCH_1):ADCVREFEXT1   I263 @SCM_LIB.SCM(SCH_1):PAGE17

R782 Q_RES_0402LF-0,5%,1/16W,EMPTY,A
     1 P1V2_AUX @SCM_LIB.SCM(SCH_1):P1V2_AUX   I264 @SCM_LIB.SCM(SCH_1):PAGE17
     2 ADCVREFEXT1 @SCM_LIB.SCM(SCH_1):ADCVREFEXT1   I264 @SCM_LIB.SCM(SCH_1):PAGE17

R783 Q_RES_0402LF-0,5%,1/16W,CHIP,CA
     1 P1V8_AUX @SCM_LIB.SCM(SCH_1):P1V8_AUX   I260 @SCM_LIB.SCM(SCH_1):PAGE17
     2 ADCVREFEXT0 @SCM_LIB.SCM(SCH_1):ADCVREFEXT0   I260 @SCM_LIB.SCM(SCH_1):PAGE17

R784 Q_RES_0402LF-0,5%,1/16W,EMPTY,A
     1 P1V2_AUX @SCM_LIB.SCM(SCH_1):P1V2_AUX   I267 @SCM_LIB.SCM(SCH_1):PAGE17
     2 ADCVREFEXT0 @SCM_LIB.SCM(SCH_1):ADCVREFEXT0   I267 @SCM_LIB.SCM(SCH_1):PAGE17

R785 Q_RES_0402LF-15.8K,1%,1/16W,CHA
     1 P12V_AUX @SCM_LIB.SCM(SCH_1):P12V_AUX   I202 @SCM_LIB.SCM(SCH_1):PAGE15
     2 P12V_SENSOR @SCM_LIB.SCM(SCH_1):P12V_SENSOR   I202 @SCM_LIB.SCM(SCH_1):PAGE15

R786 Q_RES_0402LF-2K,1%,1/16W,CHIP,A
     1 P12V_SENSOR @SCM_LIB.SCM(SCH_1):P12V_SENSOR   I203 @SCM_LIB.SCM(SCH_1):PAGE15
     2    GND @SCM_LIB.SCM(SCH_1):GND   I203 @SCM_LIB.SCM(SCH_1):PAGE15

R787 Q_RES_0402LF-5.36K,1%,1/16W,CHA
     1 P5V_AUX @SCM_LIB.SCM(SCH_1):P5V_AUX   I223 @SCM_LIB.SCM(SCH_1):PAGE15
     2 P5V_SENSOR @SCM_LIB.SCM(SCH_1):P5V_SENSOR   I223 @SCM_LIB.SCM(SCH_1):PAGE15

R788 Q_RES_0402LF-2K,1%,1/16W,CHIP,A
     1 P5V_SENSOR @SCM_LIB.SCM(SCH_1):P5V_SENSOR   I211 @SCM_LIB.SCM(SCH_1):PAGE15
     2    GND @SCM_LIB.SCM(SCH_1):GND   I211 @SCM_LIB.SCM(SCH_1):PAGE15

R789 Q_RES_0402LF-2.87K,1%,1/16W,CHA
     1 P3V3_AUX @SCM_LIB.SCM(SCH_1):P3V3_AUX   I219 @SCM_LIB.SCM(SCH_1):PAGE15
     2 P3V3_SENSOR @SCM_LIB.SCM(SCH_1):P3V3_SENSOR   I219 @SCM_LIB.SCM(SCH_1):PAGE15

R790 Q_RES_0402LF-2K,1%,1/16W,CHIP,A
     1 P3V3_SENSOR @SCM_LIB.SCM(SCH_1):P3V3_SENSOR   I220 @SCM_LIB.SCM(SCH_1):PAGE15
     2    GND @SCM_LIB.SCM(SCH_1):GND   I220 @SCM_LIB.SCM(SCH_1):PAGE15

R791 Q_RES_0402LF-1.69K,1%,1/16W,CHA
     1 P2V5_AUX @SCM_LIB.SCM(SCH_1):P2V5_AUX   I245 @SCM_LIB.SCM(SCH_1):PAGE15
     2 P2V5_SENSOR @SCM_LIB.SCM(SCH_1):P2V5_SENSOR   I245 @SCM_LIB.SCM(SCH_1):PAGE15

R792 Q_RES_0402LF-2K,1%,1/16W,CHIP,A
     1 P2V5_SENSOR @SCM_LIB.SCM(SCH_1):P2V5_SENSOR   I236 @SCM_LIB.SCM(SCH_1):PAGE15
     2    GND @SCM_LIB.SCM(SCH_1):GND   I236 @SCM_LIB.SCM(SCH_1):PAGE15

R793 Q_RES_0402LF-665,1%,1/16W,CHIPA
     1 P1V8_AUX @SCM_LIB.SCM(SCH_1):P1V8_AUX   I244 @SCM_LIB.SCM(SCH_1):PAGE15
     2 P1V8_SENSOR @SCM_LIB.SCM(SCH_1):P1V8_SENSOR   I244 @SCM_LIB.SCM(SCH_1):PAGE15

R794 Q_RES_0402LF-2K,1%,1/16W,CHIP,A
     1 P1V8_SENSOR @SCM_LIB.SCM(SCH_1):P1V8_SENSOR   I242 @SCM_LIB.SCM(SCH_1):PAGE15
     2    GND @SCM_LIB.SCM(SCH_1):GND   I242 @SCM_LIB.SCM(SCH_1):PAGE15

R795 Q_RES_0402LF-1K,1%,1/16W,CHIP,A
     1 P1V2_AUX @SCM_LIB.SCM(SCH_1):P1V2_AUX   I252 @SCM_LIB.SCM(SCH_1):PAGE15
     2 P1V2_SENSOR @SCM_LIB.SCM(SCH_1):P1V2_SENSOR   I252 @SCM_LIB.SCM(SCH_1):PAGE15

R796 Q_RES_0402LF-1K,1%,1/16W,CHIP,A
     1 P1V0_AUX @SCM_LIB.SCM(SCH_1):P1V0_AUX   I255 @SCM_LIB.SCM(SCH_1):PAGE15
     2 P1V0_SENSOR @SCM_LIB.SCM(SCH_1):P1V0_SENSOR   I255 @SCM_LIB.SCM(SCH_1):PAGE15

R797 Q_RES_0402LF-2.87K,1%,1/16W,CHA
     1 PGPPA_BMC_AUX @SCM_LIB.SCM(SCH_1):PGPPA_BMC_AUX   I261 @SCM_LIB.SCM(SCH_1):PAGE15
     2 PGPPA_BMC_AUX_SENSOR @SCM_LIB.SCM(SCH_1):PGPPA_BMC_AUX_SENSOR   I261 @SCM_LIB.SCM(SCH_1):PAGE15

R798 Q_RES_0402LF-2K,1%,1/16W,CHIP,A
     1 PGPPA_BMC_AUX_SENSOR @SCM_LIB.SCM(SCH_1):PGPPA_BMC_AUX_SENSOR   I262 @SCM_LIB.SCM(SCH_1):PAGE15
     2    GND @SCM_LIB.SCM(SCH_1):GND   I262 @SCM_LIB.SCM(SCH_1):PAGE15

R799 Q_RES_0402LF-33.2,1%,1/16W,CHIA
     1 SPI_BMC_BIOS_CS0_N @SCM_LIB.SCM(SCH_1):SPI_BMC_BIOS_CS0_N   I215 @SCM_LIB.SCM(SCH_1):PAGE13
     2 SPI_BMC_BIOS_CS0_R1_N @SCM_LIB.SCM(SCH_1):SPI_BMC_BIOS_CS0_R1_N   I215 @SCM_LIB.SCM(SCH_1):PAGE13

R801 Q_RES_0402LF-33.2,1%,1/16W,CHIA
     1 SPI_BMC_BOOT_CS0_R_N @SCM_LIB.SCM(SCH_1):SPI_BMC_BOOT_CS0_R_N   I217 @SCM_LIB.SCM(SCH_1):PAGE13
     2 SPI_BMC_BOOT_CS0_R1_N @SCM_LIB.SCM(SCH_1):SPI_BMC_BOOT_CS0_R1_N   I217 @SCM_LIB.SCM(SCH_1):PAGE13

R802 Q_RES_0402LF-33.2,1%,1/16W,CHIA
     1 SPI_BMC_BOOT_CS1_R_N @SCM_LIB.SCM(SCH_1):SPI_BMC_BOOT_CS1_R_N   I218 @SCM_LIB.SCM(SCH_1):PAGE13
     2 SPI_BMC_BOOT_CS1_R1_N @SCM_LIB.SCM(SCH_1):SPI_BMC_BOOT_CS1_R1_N   I218 @SCM_LIB.SCM(SCH_1):PAGE13

R804 Q_RES_0402LF-0,5%,1/16W,CHIP,CA
     1 SYS_BMC_PWRBTN_R1_N @SCM_LIB.SCM(SCH_1):SYS_BMC_PWRBTN_R1_N   I367 @SCM_LIB.SCM(SCH_1):PAGE15
     2 SYS_BMC_PWRBTN_R_N @SCM_LIB.SCM(SCH_1):SYS_BMC_PWRBTN_R_N   I367 @SCM_LIB.SCM(SCH_1):PAGE15

R805 Q_RES_0402LF-4.7K,1%,1/16W,CHIA
     1 P3V3_AUX @SCM_LIB.SCM(SCH_1):P3V3_AUX   I356 @SCM_LIB.SCM(SCH_1):PAGE13
     2 BMC_HEARTBEAT_N @SCM_LIB.SCM(SCH_1):BMC_HEARTBEAT_N   I356 @SCM_LIB.SCM(SCH_1):PAGE13

R806 Q_RES_0402LF-4.7K,1%,1/16W,CHIA
     1 P3V3_AUX @SCM_LIB.SCM(SCH_1):P3V3_AUX   I119 @SCM_LIB.SCM(SCH_1):PAGE34
     2 PU_25M_FPGA_CLK_EN @SCM_LIB.SCM(SCH_1):PU_25M_FPGA_CLK_EN   I119 @SCM_LIB.SCM(SCH_1):PAGE34

R807 Q_RES_0402LF-33.2,1%,1/16W,CHIA
     1 CLK_25M_OSC_FPGA_R @SCM_LIB.SCM(SCH_1):CLK_25M_OSC_FPGA_R   I126 @SCM_LIB.SCM(SCH_1):PAGE34
     2 CLK_25M_OSC_FPGA @SCM_LIB.SCM(SCH_1):CLK_25M_OSC_FPGA   I126 @SCM_LIB.SCM(SCH_1):PAGE34

R808 Q_RES_0402LF-10K,1%,1/16W,CHIPA
     1 PU_FPGA_CONFIG_DONE @SCM_LIB.SCM(SCH_1):PU_FPGA_CONFIG_DONE   I117 @SCM_LIB.SCM(SCH_1):PAGE34
     2 PVCCIO_AUX_PLD @SCM_LIB.SCM(SCH_1):PVCCIO_AUX_PLD   I117 @SCM_LIB.SCM(SCH_1):PAGE34

R809 Q_RES_0402LF-10K,1%,1/16W,CHIPA
     1 PU_FPGA_NCONFIG @SCM_LIB.SCM(SCH_1):PU_FPGA_NCONFIG   I115 @SCM_LIB.SCM(SCH_1):PAGE34
     2 PVCCIO_AUX_PLD @SCM_LIB.SCM(SCH_1):PVCCIO_AUX_PLD   I115 @SCM_LIB.SCM(SCH_1):PAGE34

R810 Q_RES_0402LF-10K,1%,1/16W,CHIPA
     1 PU_FPGA_NSTATUS @SCM_LIB.SCM(SCH_1):PU_FPGA_NSTATUS   I116 @SCM_LIB.SCM(SCH_1):PAGE34
     2 PVCCIO_AUX_PLD @SCM_LIB.SCM(SCH_1):PVCCIO_AUX_PLD   I116 @SCM_LIB.SCM(SCH_1):PAGE34

R811 Q_RES_0402LF-0,5%,1/16W,EMPTY,A
     1 PCH_BEEP_LED @SCM_LIB.SCM(SCH_1):PCH_BEEP_LED   I565 @SCM_LIB.SCM(SCH_1):PAGE10
     2 PCH_BEEP_R_LED @SCM_LIB.SCM(SCH_1):PCH_BEEP_R_LED   I565 @SCM_LIB.SCM(SCH_1):PAGE10

R812 Q_RES_0402LF-33.2,1%,1/16W,CHIA
     1 PWR_LED_BUF_N @SCM_LIB.SCM(SCH_1):PWR_LED_BUF_N    I34 @SCM_LIB.SCM(SCH_1):PAGE49
     2 PWR_LED_BUF_N_R @SCM_LIB.SCM(SCH_1):PWR_LED_BUF_N_R    I34 @SCM_LIB.SCM(SCH_1):PAGE49

R813 Q_RES_0402LF-33.2,1%,1/16W,CHIA
     1 HDD_LED_BUF @SCM_LIB.SCM(SCH_1):HDD_LED_BUF    I35 @SCM_LIB.SCM(SCH_1):PAGE49
     2 HDD_LED_BUF_R @SCM_LIB.SCM(SCH_1):HDD_LED_BUF_R    I35 @SCM_LIB.SCM(SCH_1):PAGE49

R814 Q_RES_0402LF-10K,1%,1/16W,CHIPA
     1 P5V_AUX @SCM_LIB.SCM(SCH_1):P5V_AUX    I36 @SCM_LIB.SCM(SCH_1):PAGE49
     2 PWR_LED_BUF_N_R @SCM_LIB.SCM(SCH_1):PWR_LED_BUF_N_R    I36 @SCM_LIB.SCM(SCH_1):PAGE49

R815 Q_RES_0402LF-10K,1%,1/16W,CHIPA
     1 P5V_AUX @SCM_LIB.SCM(SCH_1):P5V_AUX    I40 @SCM_LIB.SCM(SCH_1):PAGE49
     2 HDD_LED_BUF_R @SCM_LIB.SCM(SCH_1):HDD_LED_BUF_R    I40 @SCM_LIB.SCM(SCH_1):PAGE49

R816 Q_RES_0402LF-4.7K,1%,1/16W,CHIA
     1 P3V3_AUX @SCM_LIB.SCM(SCH_1):P3V3_AUX   I353 @SCM_LIB.SCM(SCH_1):PAGE13
     2 IRQ_PCH_SCI_WHEA_N @SCM_LIB.SCM(SCH_1):IRQ_PCH_SCI_WHEA_N   I353 @SCM_LIB.SCM(SCH_1):PAGE13

R817 Q_RES_0402LF-100K,1%,1/16W,EMPA
     1 SMB_BMC_MM13_R_SCL @SCM_LIB.SCM(SCH_1):SMB_BMC_MM13_R_SCL   I393 @SCM_LIB.SCM(SCH_1):PAGE12
     2    GND @SCM_LIB.SCM(SCH_1):GND   I393 @SCM_LIB.SCM(SCH_1):PAGE12

R818 Q_RES_0402LF-100K,1%,1/16W,EMPA
     1 SMB_BMC_MM13_R_SDA @SCM_LIB.SCM(SCH_1):SMB_BMC_MM13_R_SDA   I392 @SCM_LIB.SCM(SCH_1):PAGE12
     2    GND @SCM_LIB.SCM(SCH_1):GND   I392 @SCM_LIB.SCM(SCH_1):PAGE12

R819 Q_RES_0402LF-100K,1%,1/16W,EMPA
     1 SMB_BMC_MM14_R_SCL @SCM_LIB.SCM(SCH_1):SMB_BMC_MM14_R_SCL   I391 @SCM_LIB.SCM(SCH_1):PAGE12
     2    GND @SCM_LIB.SCM(SCH_1):GND   I391 @SCM_LIB.SCM(SCH_1):PAGE12

R820 Q_RES_0402LF-100K,1%,1/16W,EMPA
     1 SMB_BMC_MM14_R_SDA @SCM_LIB.SCM(SCH_1):SMB_BMC_MM14_R_SDA   I390 @SCM_LIB.SCM(SCH_1):PAGE12
     2    GND @SCM_LIB.SCM(SCH_1):GND   I390 @SCM_LIB.SCM(SCH_1):PAGE12

R821 Q_RES_0402LF-4.7K,1%,1/16W,EMPA
     1 P3V3_AUX @SCM_LIB.SCM(SCH_1):P3V3_AUX   I220 @SCM_LIB.SCM(SCH_1):PAGE13
     2 FM_BMC_ONCTL_R_N @SCM_LIB.SCM(SCH_1):FM_BMC_ONCTL_R_N   I220 @SCM_LIB.SCM(SCH_1):PAGE13

R822 Q_RES_0402LF-0,5%,1/16W,CHIP,CA
     1 FM_PRSNT_1_N @SCM_LIB.SCM(SCH_1):FM_PRSNT_1_N   I456 @SCM_LIB.SCM(SCH_1):PAGE10
     2 FM_PRSNT_0_R_N @SCM_LIB.SCM(SCH_1):FM_PRSNT_0_R_N   I456 @SCM_LIB.SCM(SCH_1):PAGE10

R823 Q_RES_0402LF-100K,1%,1/16W,CHIA
     1    GND @SCM_LIB.SCM(SCH_1):GND   I234 @SCM_LIB.SCM(SCH_1):PAGE11
     2 FM_VIRTUAL_RESEAT @SCM_LIB.SCM(SCH_1):FM_VIRTUAL_RESEAT   I234 @SCM_LIB.SCM(SCH_1):PAGE11

R824 Q_RES_0402LF-33.2,1%,1/16W,CHIA
     1 FM_VIRTUAL_RESEAT @SCM_LIB.SCM(SCH_1):FM_VIRTUAL_RESEAT   I223 @SCM_LIB.SCM(SCH_1):PAGE13
     2 FM_VIRTUAL_RESEAT_BMC @SCM_LIB.SCM(SCH_1):FM_VIRTUAL_RESEAT_BMC   I223 @SCM_LIB.SCM(SCH_1):PAGE13

R825 Q_RES_0402LF-33.2,1%,1/16W,CHIA
     1 RST_ROT_CPU_N @SCM_LIB.SCM(SCH_1):RST_ROT_CPU_N   I138 @SCM_LIB.SCM(SCH_1):PAGE35
     2 RST_ROT_CPU_R_N @SCM_LIB.SCM(SCH_1):RST_ROT_CPU_R_N   I138 @SCM_LIB.SCM(SCH_1):PAGE35

R826 Q_RES_0402LF-33.2,1%,1/16W,CHIA
     1 IRQ_PCH_SCI_WHEA_R_N @SCM_LIB.SCM(SCH_1):IRQ_PCH_SCI_WHEA_R_N   I351 @SCM_LIB.SCM(SCH_1):PAGE13
     2 IRQ_PCH_SCI_WHEA_N @SCM_LIB.SCM(SCH_1):IRQ_PCH_SCI_WHEA_N   I351 @SCM_LIB.SCM(SCH_1):PAGE13

R827 Q_RES_0402LF-33.2,1%,1/16W,CHIA
     1 RST_SPI_FLASH_BUF_R3_N @SCM_LIB.SCM(SCH_1):RST_SPI_FLASH_BUF_R3_N    I73 @SCM_LIB.SCM(SCH_1):PAGE25
     2 RST_SPI_FLASH_BUF_N @SCM_LIB.SCM(SCH_1):RST_SPI_FLASH_BUF_N    I73 @SCM_LIB.SCM(SCH_1):PAGE25

R828 Q_RES_0402LF-4.7K,1%,1/16W,EMPA
     1 P3V3_AUX @SCM_LIB.SCM(SCH_1):P3V3_AUX   I241 @SCM_LIB.SCM(SCH_1):PAGE11
     2 RST_ROT_CPU_N @SCM_LIB.SCM(SCH_1):RST_ROT_CPU_N   I241 @SCM_LIB.SCM(SCH_1):PAGE11

R829 Q_RES_0402LF-25.5K,1%,1/16W,CHA
     1 P2V5_AUX @SCM_LIB.SCM(SCH_1):P2V5_AUX    I62 @SCM_LIB.SCM(SCH_1):PAGE53
     2 U39_ADJ @SCM_LIB.SCM(SCH_1):U39_ADJ    I62 @SCM_LIB.SCM(SCH_1):PAGE53

R830 Q_RES_0402LF-12K,1%,1/16W,CHIPA
     1 U39_ADJ @SCM_LIB.SCM(SCH_1):U39_ADJ    I61 @SCM_LIB.SCM(SCH_1):PAGE53
     2    GND @SCM_LIB.SCM(SCH_1):GND    I61 @SCM_LIB.SCM(SCH_1):PAGE53

R831 Q_RES_0402LF-15K,1%,1/16W,CHIPA
     1 P1V8_AUX @SCM_LIB.SCM(SCH_1):P1V8_AUX    I98 @SCM_LIB.SCM(SCH_1):PAGE54
     2 U41_ADJ @SCM_LIB.SCM(SCH_1):U41_ADJ    I98 @SCM_LIB.SCM(SCH_1):PAGE54

R832 Q_RES_0402LF-12K,1%,1/16W,CHIPA
     1 U41_ADJ @SCM_LIB.SCM(SCH_1):U41_ADJ    I97 @SCM_LIB.SCM(SCH_1):PAGE54
     2    GND @SCM_LIB.SCM(SCH_1):GND    I97 @SCM_LIB.SCM(SCH_1):PAGE54

R833 Q_RES_0402LF-33.2,1%,1/16W,CHIA
     1 FM_ESPI_PLD_EN @SCM_LIB.SCM(SCH_1):FM_ESPI_PLD_EN   I139 @SCM_LIB.SCM(SCH_1):PAGE35
     2 FM_ESPI_PLD_R_EN @SCM_LIB.SCM(SCH_1):FM_ESPI_PLD_R_EN   I139 @SCM_LIB.SCM(SCH_1):PAGE35

R834 Q_RES_0402LF-10K,1%,1/16W,EMPTA
     1 P3V3_RGM @SCM_LIB.SCM(SCH_1):P3V3_RGM   I131 @SCM_LIB.SCM(SCH_1):PAGE32
     2 JTAG_SCM_TCK @SCM_LIB.SCM(SCH_1):JTAG_SCM_TCK   I131 @SCM_LIB.SCM(SCH_1):PAGE32

R835 Q_RES_0402LF-4.7K,1%,1/16W,CHIA
     1 P3V3_AUX @SCM_LIB.SCM(SCH_1):P3V3_AUX    I63 @SCM_LIB.SCM(SCH_1):PAGE42
     2 FM_ADR_TRIGGER_N @SCM_LIB.SCM(SCH_1):FM_ADR_TRIGGER_N    I63 @SCM_LIB.SCM(SCH_1):PAGE42

R836 Q_RES_0402LF-33.2,1%,1/16W,CHIA
     1 PWRGD_PSU_AC_PWROK @SCM_LIB.SCM(SCH_1):PWRGD_PSU_AC_PWROK   I225 @SCM_LIB.SCM(SCH_1):PAGE13
     2 PWRGD_PSU_AC_PWROK_BMC @SCM_LIB.SCM(SCH_1):PWRGD_PSU_AC_PWROK_BMC   I225 @SCM_LIB.SCM(SCH_1):PAGE13

R837 Q_RES_0402LF-33.2,1%,1/16W,CHIA
     1 PWRGD_PSU_AC_PWROK @SCM_LIB.SCM(SCH_1):PWRGD_PSU_AC_PWROK   I158 @SCM_LIB.SCM(SCH_1):PAGE34
     2 PWRGD_PSU_AC_PWROK_PLD @SCM_LIB.SCM(SCH_1):PWRGD_PSU_AC_PWROK_PLD   I158 @SCM_LIB.SCM(SCH_1):PAGE34

R838 Q_RES_0402LF-0,5%,1/16W,CHIP,CA
     1 HDD_LED_N @SCM_LIB.SCM(SCH_1):HDD_LED_N   I568 @SCM_LIB.SCM(SCH_1):PAGE10
     2 FM_HDD_LED_N @SCM_LIB.SCM(SCH_1):FM_HDD_LED_N   I568 @SCM_LIB.SCM(SCH_1):PAGE10

R839 Q_RES_0402LF-8.2K,5%,1/16W,CHIA
     1 PWR_LED @SCM_LIB.SCM(SCH_1):PWR_LED    I22 @SCM_LIB.SCM(SCH_1):PAGE49
     2    GND @SCM_LIB.SCM(SCH_1):GND    I22 @SCM_LIB.SCM(SCH_1):PAGE49

R840 Q_RES_0402LF-33.2,1%,1/16W,CHIA
     1 PWRGD_SYS_PWROK @SCM_LIB.SCM(SCH_1):PWRGD_SYS_PWROK   I295 @SCM_LIB.SCM(SCH_1):PAGE13
     2 PWRGD_SYS_PWROK_BMC @SCM_LIB.SCM(SCH_1):PWRGD_SYS_PWROK_BMC   I295 @SCM_LIB.SCM(SCH_1):PAGE13

R841 Q_RES_0402LF-33.2,1%,1/16W,CHIA
     1 PWRGD_SYS_PWROK_PLD @SCM_LIB.SCM(SCH_1):PWRGD_SYS_PWROK_PLD   I142 @SCM_LIB.SCM(SCH_1):PAGE35
     2 PWRGD_SYS_PWROK @SCM_LIB.SCM(SCH_1):PWRGD_SYS_PWROK   I142 @SCM_LIB.SCM(SCH_1):PAGE35

R842 Q_RES_0402LF-4.7K,1%,1/16W,CHIA
     1 P3V3_AUX @SCM_LIB.SCM(SCH_1):P3V3_AUX   I168 @SCM_LIB.SCM(SCH_1):PAGE27
     2 SMB_BMC_ALERT9_N @SCM_LIB.SCM(SCH_1):SMB_BMC_ALERT9_N   I168 @SCM_LIB.SCM(SCH_1):PAGE27

R843 Q_RES_0402LF-4.7K,1%,1/16W,CHIA
     1 P3V3_AUX @SCM_LIB.SCM(SCH_1):P3V3_AUX   I177 @SCM_LIB.SCM(SCH_1):PAGE27
     2 SMB_BMC_ALERT10_N @SCM_LIB.SCM(SCH_1):SMB_BMC_ALERT10_N   I177 @SCM_LIB.SCM(SCH_1):PAGE27

R844 Q_RES_0402LF-4.7K,1%,1/16W,CHIA
     1 P3V3_AUX @SCM_LIB.SCM(SCH_1):P3V3_AUX   I179 @SCM_LIB.SCM(SCH_1):PAGE27
     2 SMB_BMC_ALERT12_N @SCM_LIB.SCM(SCH_1):SMB_BMC_ALERT12_N   I179 @SCM_LIB.SCM(SCH_1):PAGE27

R846 Q_RES_0402LF-4.7K,1%,1/16W,EMPA
     1 P3V3_AUX @SCM_LIB.SCM(SCH_1):P3V3_AUX   I181 @SCM_LIB.SCM(SCH_1):PAGE27
     2 FM_BMC_EN_DET_R @SCM_LIB.SCM(SCH_1):FM_BMC_EN_DET_R   I181 @SCM_LIB.SCM(SCH_1):PAGE27

R847 Q_RES_0402LF-0,5%,1/16W,CHIP,CA
     1 PCH_BEEP_LED @SCM_LIB.SCM(SCH_1):PCH_BEEP_LED   I569 @SCM_LIB.SCM(SCH_1):PAGE10
     2 FM_PCH_BEEP_LED @SCM_LIB.SCM(SCH_1):FM_PCH_BEEP_LED   I569 @SCM_LIB.SCM(SCH_1):PAGE10

R848 Q_RES_0402LF-4.7K,1%,1/16W,CHIA
     1 P3V3_AUX @SCM_LIB.SCM(SCH_1):P3V3_AUX   I182 @SCM_LIB.SCM(SCH_1):PAGE27
     2 SMB_BMC_ALERT16_N @SCM_LIB.SCM(SCH_1):SMB_BMC_ALERT16_N   I182 @SCM_LIB.SCM(SCH_1):PAGE27

R849 Q_RES_0402LF-33.2,1%,1/16W,CHIA
     1 SMB_BMC_MM16_R5_SCL @SCM_LIB.SCM(SCH_1):SMB_BMC_MM16_R5_SCL   I157 @SCM_LIB.SCM(SCH_1):PAGE21
     2 SMB_BMC_MM16_R1_SCL @SCM_LIB.SCM(SCH_1):SMB_BMC_MM16_R1_SCL   I157 @SCM_LIB.SCM(SCH_1):PAGE21

R850 Q_RES_0402LF-33.2,1%,1/16W,CHIA
     1 SMB_BMC_MM16_R5_SDA @SCM_LIB.SCM(SCH_1):SMB_BMC_MM16_R5_SDA   I156 @SCM_LIB.SCM(SCH_1):PAGE21
     2 SMB_BMC_MM16_R1_SDA @SCM_LIB.SCM(SCH_1):SMB_BMC_MM16_R1_SDA   I156 @SCM_LIB.SCM(SCH_1):PAGE21

R851 Q_RES_0402LF-4.7K,1%,1/16W,CHIA
     1 P3V3_AUX @SCM_LIB.SCM(SCH_1):P3V3_AUX   I184 @SCM_LIB.SCM(SCH_1):PAGE27
     2 SMB_BMC_ALERT15_N @SCM_LIB.SCM(SCH_1):SMB_BMC_ALERT15_N   I184 @SCM_LIB.SCM(SCH_1):PAGE27

R852 Q_RES_0402LF-68.1,1%,1/16W,CHIA
     1 FM_BMC_MUX_CS_SPI_SEL_0 @SCM_LIB.SCM(SCH_1):FM_BMC_MUX_CS_SPI_SEL_0   I366 @SCM_LIB.SCM(SCH_1):PAGE44
     2 FM_BMC_BIOS_MUX_CS_SPI_R_SEL_0 @SCM_LIB.SCM(SCH_1):FM_BMC_BIOS_MUX_CS_SPI_R_SEL_0   I366 @SCM_LIB.SCM(SCH_1):PAGE44

R853 Q_RES_0402LF-0,5%,1/16W,CHIP,CA
     1 FM_INTRUDER_R_N @SCM_LIB.SCM(SCH_1):FM_INTRUDER_R_N   I387 @SCM_LIB.SCM(SCH_1):PAGE15
     2 FM_INTRUDER_N @SCM_LIB.SCM(SCH_1):FM_INTRUDER_N   I387 @SCM_LIB.SCM(SCH_1):PAGE15

R854 Q_RES_0402LF-4.7K,1%,1/16W,EMPA
     1 P1V8_AUX @SCM_LIB.SCM(SCH_1):P1V8_AUX   I221 @SCM_LIB.SCM(SCH_1):PAGE14
     2 FM_BOARD_BMC_REV_ID2 @SCM_LIB.SCM(SCH_1):FM_BOARD_BMC_REV_ID2   I221 @SCM_LIB.SCM(SCH_1):PAGE14

R855 Q_RES_0402LF-1K,1%,1/16W,CHIP,A
     1 FM_BOARD_BMC_REV_ID2 @SCM_LIB.SCM(SCH_1):FM_BOARD_BMC_REV_ID2   I223 @SCM_LIB.SCM(SCH_1):PAGE14
     2    GND @SCM_LIB.SCM(SCH_1):GND   I223 @SCM_LIB.SCM(SCH_1):PAGE14

R856 Q_RES_0402LF-4.7K,1%,1/16W,CHIA
     1 P1V8_AUX @SCM_LIB.SCM(SCH_1):P1V8_AUX   I220 @SCM_LIB.SCM(SCH_1):PAGE14
     2 FM_BOARD_BMC_REV_ID1 @SCM_LIB.SCM(SCH_1):FM_BOARD_BMC_REV_ID1   I220 @SCM_LIB.SCM(SCH_1):PAGE14

R857 Q_RES_0402LF-1K,1%,1/16W,EMPTYA
     1 FM_BOARD_BMC_REV_ID1 @SCM_LIB.SCM(SCH_1):FM_BOARD_BMC_REV_ID1   I224 @SCM_LIB.SCM(SCH_1):PAGE14
     2    GND @SCM_LIB.SCM(SCH_1):GND   I224 @SCM_LIB.SCM(SCH_1):PAGE14

R858 Q_RES_0402LF-4.7K,1%,1/16W,CHIA
     1 P1V8_AUX @SCM_LIB.SCM(SCH_1):P1V8_AUX   I222 @SCM_LIB.SCM(SCH_1):PAGE14
     2 FM_BOARD_BMC_REV_ID0 @SCM_LIB.SCM(SCH_1):FM_BOARD_BMC_REV_ID0   I222 @SCM_LIB.SCM(SCH_1):PAGE14

R859 Q_RES_0402LF-33.2,1%,1/16W,CHIA
     1 SPI_SYS_R_CLK @SCM_LIB.SCM(SCH_1):SPI_SYS_R_CLK   I339 @SCM_LIB.SCM(SCH_1):PAGE44
     2 SPI_SYS_MUX_CLK @SCM_LIB.SCM(SCH_1):SPI_SYS_MUX_CLK   I339 @SCM_LIB.SCM(SCH_1):PAGE44

R860 Q_RES_0402LF-22,1%,1/16W,CHIP,A
     1 SPI_SYS_R_MOSI @SCM_LIB.SCM(SCH_1):SPI_SYS_R_MOSI   I362 @SCM_LIB.SCM(SCH_1):PAGE44
     2 SPI_SYS_MUX_MOSI @SCM_LIB.SCM(SCH_1):SPI_SYS_MUX_MOSI   I362 @SCM_LIB.SCM(SCH_1):PAGE44

R861 Q_RES_0402LF-22,1%,1/16W,CHIP,A
     1 SPI_SYS_R_MISO @SCM_LIB.SCM(SCH_1):SPI_SYS_R_MISO   I363 @SCM_LIB.SCM(SCH_1):PAGE44
     2 SPI_SYS_MUX_MISO @SCM_LIB.SCM(SCH_1):SPI_SYS_MUX_MISO   I363 @SCM_LIB.SCM(SCH_1):PAGE44

R862 Q_RES_0402LF-22,1%,1/16W,CHIP,A
     1 SPI_SYS_WP_R_IO2 @SCM_LIB.SCM(SCH_1):SPI_SYS_WP_R_IO2   I364 @SCM_LIB.SCM(SCH_1):PAGE44
     2 SPI_SYS_MUX_WP_IO2 @SCM_LIB.SCM(SCH_1):SPI_SYS_MUX_WP_IO2   I364 @SCM_LIB.SCM(SCH_1):PAGE44

R863 Q_RES_0402LF-22,1%,1/16W,CHIP,A
     1 SPI_SYS_HOLD_R_IO3 @SCM_LIB.SCM(SCH_1):SPI_SYS_HOLD_R_IO3   I365 @SCM_LIB.SCM(SCH_1):PAGE44
     2 SPI_SYS_MUX_HOLD_IO3 @SCM_LIB.SCM(SCH_1):SPI_SYS_MUX_HOLD_IO3   I365 @SCM_LIB.SCM(SCH_1):PAGE44

R864 Q_RES_0402LF-33.2,1%,1/16W,CHIA
     1 SPI_SYS_CS0_N @SCM_LIB.SCM(SCH_1):SPI_SYS_CS0_N   I342 @SCM_LIB.SCM(SCH_1):PAGE44
     2 SPI_PCH_SECURE_CS0_N @SCM_LIB.SCM(SCH_1):SPI_PCH_SECURE_CS0_N   I342 @SCM_LIB.SCM(SCH_1):PAGE44

R865 Q_RES_0402LF-1K,1%,1/16W,EMPTYA
     1 FM_BOARD_BMC_REV_ID0 @SCM_LIB.SCM(SCH_1):FM_BOARD_BMC_REV_ID0   I225 @SCM_LIB.SCM(SCH_1):PAGE14
     2    GND @SCM_LIB.SCM(SCH_1):GND   I225 @SCM_LIB.SCM(SCH_1):PAGE14

R866 Q_RES_0402LF-10K,1%,1/16W,CHIPA
     1 FM_BMC_BIOS_MUX_CS_SPI_R_SEL_0 @SCM_LIB.SCM(SCH_1):FM_BMC_BIOS_MUX_CS_SPI_R_SEL_0   I311 @SCM_LIB.SCM(SCH_1):PAGE44
     2    GND @SCM_LIB.SCM(SCH_1):GND   I311 @SCM_LIB.SCM(SCH_1):PAGE44

R867 Q_RES_0402LF-1K,1%,1/16W,EMPTYA
     1 P3V3_AUX @SCM_LIB.SCM(SCH_1):P3V3_AUX   I161 @SCM_LIB.SCM(SCH_1):PAGE21
     2 EMMC_WP @SCM_LIB.SCM(SCH_1):EMMC_WP   I161 @SCM_LIB.SCM(SCH_1):PAGE21

R868 Q_RES_0402LF-0,5%,1/16W,EMPTY,A
     1 PWRGD_P5V_AUX_R @SCM_LIB.SCM(SCH_1):PWRGD_P5V_AUX_R    I54 @SCM_LIB.SCM(SCH_1):PAGE51
     2 EN_P3V3_R1 @SCM_LIB.SCM(SCH_1):EN_P3V3_R1    I54 @SCM_LIB.SCM(SCH_1):PAGE51

R869 Q_RES_0402LF-0,5%,1/16W,EMPTY,A
     1 PWRGD_P1V8_AUX_R3 @SCM_LIB.SCM(SCH_1):PWRGD_P1V8_AUX_R3   I139 @SCM_LIB.SCM(SCH_1):PAGE52
     2 EN_P3V3_RGM_R @SCM_LIB.SCM(SCH_1):EN_P3V3_RGM_R   I139 @SCM_LIB.SCM(SCH_1):PAGE52

R870 Q_RES_0402LF-4.7K,1%,1/16W,EMPA
     1 P3V3_AUX @SCM_LIB.SCM(SCH_1):P3V3_AUX   I315 @SCM_LIB.SCM(SCH_1):PAGE44
     2 PD_BIOS_MUX_EN_N @SCM_LIB.SCM(SCH_1):PD_BIOS_MUX_EN_N   I315 @SCM_LIB.SCM(SCH_1):PAGE44

R871 Q_RES_0402LF-0,5%,1/16W,EMPTY,A
     1 EN_P3V3_R1 @SCM_LIB.SCM(SCH_1):EN_P3V3_R1   I137 @SCM_LIB.SCM(SCH_1):PAGE52
     2 PWRGD_EN_P3V3_R @SCM_LIB.SCM(SCH_1):PWRGD_EN_P3V3_R   I137 @SCM_LIB.SCM(SCH_1):PAGE52

R872 Q_RES_0402LF-0,5%,1/16W,EMPTY,A
     1 PWRGD_P3V3_RGM_R @SCM_LIB.SCM(SCH_1):PWRGD_P3V3_RGM_R   I141 @SCM_LIB.SCM(SCH_1):PAGE52
     2 PWRGD_P3V3_RGM_R3 @SCM_LIB.SCM(SCH_1):PWRGD_P3V3_RGM_R3   I141 @SCM_LIB.SCM(SCH_1):PAGE52

R873 Q_RES_0402LF-0,5%,1/16W,EMPTY,A
     1 PWRGD_P2V5_AUX_R3 @SCM_LIB.SCM(SCH_1):PWRGD_P2V5_AUX_R3    I72 @SCM_LIB.SCM(SCH_1):PAGE53
     2 PWRGD_P2V5_AUX @SCM_LIB.SCM(SCH_1):PWRGD_P2V5_AUX    I72 @SCM_LIB.SCM(SCH_1):PAGE53

R874 Q_RES_0402LF-0,5%,1/16W,EMPTY,A
     1 PWRGD_P1V8_AUX_R3 @SCM_LIB.SCM(SCH_1):PWRGD_P1V8_AUX_R3   I139 @SCM_LIB.SCM(SCH_1):PAGE54
     2 PWRGD_P1V8_AUX_R @SCM_LIB.SCM(SCH_1):PWRGD_P1V8_AUX_R   I139 @SCM_LIB.SCM(SCH_1):PAGE54

R875 Q_RES_0402LF-0,5%,1/16W,EMPTY,A
     1 PWRGD_P2V5_AUX_R3 @SCM_LIB.SCM(SCH_1):PWRGD_P2V5_AUX_R3   I137 @SCM_LIB.SCM(SCH_1):PAGE54
     2 EN_P1V8_R @SCM_LIB.SCM(SCH_1):EN_P1V8_R   I137 @SCM_LIB.SCM(SCH_1):PAGE54

R876 Q_RES_0402LF-0,5%,1/16W,EMPTY,A
     1 PWRGD_P3V3_RGM_R3 @SCM_LIB.SCM(SCH_1):PWRGD_P3V3_RGM_R3    I68 @SCM_LIB.SCM(SCH_1):PAGE55
     2 EN_P1V2_AUX_R @SCM_LIB.SCM(SCH_1):EN_P1V2_AUX_R    I68 @SCM_LIB.SCM(SCH_1):PAGE55

R877 Q_RES_0402LF-0,5%,1/16W,EMPTY,A
     1 PWRGD_P1V2_AUX_R @SCM_LIB.SCM(SCH_1):PWRGD_P1V2_AUX_R    I70 @SCM_LIB.SCM(SCH_1):PAGE55
     2 PWRGD_P1V2_AUX_R2 @SCM_LIB.SCM(SCH_1):PWRGD_P1V2_AUX_R2    I70 @SCM_LIB.SCM(SCH_1):PAGE55

R878 Q_RES_0402LF-0,5%,1/16W,EMPTY,A
     1 PWRGD_P1V2_AUX_R2 @SCM_LIB.SCM(SCH_1):PWRGD_P1V2_AUX_R2    I72 @SCM_LIB.SCM(SCH_1):PAGE56
     2 EN_P1V0_AUX_R @SCM_LIB.SCM(SCH_1):EN_P1V0_AUX_R    I72 @SCM_LIB.SCM(SCH_1):PAGE56

R879 Q_RES_0402LF-200,1%,1/16W,CHIPA
     1 SMB_BMC_MM16_R5_SCL @SCM_LIB.SCM(SCH_1):SMB_BMC_MM16_R5_SCL   I510 @SCM_LIB.SCM(SCH_1):PAGE12
     2 SMB_BMC_MM16_SCL @SCM_LIB.SCM(SCH_1):SMB_BMC_MM16_SCL   I510 @SCM_LIB.SCM(SCH_1):PAGE12

R880 Q_RES_0402LF-33.2,1%,1/16W,CHIA
     1 SMB_BMC_MM16_R5_SDA @SCM_LIB.SCM(SCH_1):SMB_BMC_MM16_R5_SDA   I458 @SCM_LIB.SCM(SCH_1):PAGE12
     2 SMB_BMC_MM16_SDA @SCM_LIB.SCM(SCH_1):SMB_BMC_MM16_SDA   I458 @SCM_LIB.SCM(SCH_1):PAGE12

R881 Q_RES_0402LF-4.7K,1%,1/16W,EMPB
     1 P3V3_AUX @SCM_LIB.SCM(SCH_1):P3V3_AUX    I42 @SCM_LIB.SCM(SCH_1):PAGE48
     2 FM_JTAG_TCK_MUX_BMC_SEL_R @SCM_LIB.SCM(SCH_1):FM_JTAG_TCK_MUX_BMC_SEL_R    I42 @SCM_LIB.SCM(SCH_1):PAGE48

R882 Q_RES_0402LF-0,5%,1/16W,CHIP,CA
     1 REAR_AC_PWR_BTN @SCM_LIB.SCM(SCH_1):REAR_AC_PWR_BTN   I286 @SCM_LIB.SCM(SCH_1):PAGE50
     2 REAR_AC_PWR_BMC_BTN_N @SCM_LIB.SCM(SCH_1):REAR_AC_PWR_BMC_BTN_N   I286 @SCM_LIB.SCM(SCH_1):PAGE50

R883 Q_RES_0402LF-8.2K,5%,1/16W,EMPA
     1 P3V3_AUX @SCM_LIB.SCM(SCH_1):P3V3_AUX   I284 @SCM_LIB.SCM(SCH_1):PAGE50
     2 REAR_AC_PWR_BMC_BTN_N @SCM_LIB.SCM(SCH_1):REAR_AC_PWR_BMC_BTN_N   I284 @SCM_LIB.SCM(SCH_1):PAGE50

R884 Q_RES_0402LF-33.2,1%,1/16W,CHIA
     1 AC_PWR_BMC_BTN_R_N @SCM_LIB.SCM(SCH_1):AC_PWR_BMC_BTN_R_N   I229 @SCM_LIB.SCM(SCH_1):PAGE14
     2 AC_PWR_BMC_BTN_N @SCM_LIB.SCM(SCH_1):AC_PWR_BMC_BTN_N   I229 @SCM_LIB.SCM(SCH_1):PAGE14

R885 Q_RES_0402LF-4.7K,1%,1/16W,CHIA
     1 P1V8_AUX @SCM_LIB.SCM(SCH_1):P1V8_AUX   I231 @SCM_LIB.SCM(SCH_1):PAGE14
     2 AC_PWR_BMC_BTN_N @SCM_LIB.SCM(SCH_1):AC_PWR_BMC_BTN_N   I231 @SCM_LIB.SCM(SCH_1):PAGE14

R886 Q_RES_0402LF-4.7K,1%,1/16W,CHIA
     1 P3V3_AUX @SCM_LIB.SCM(SCH_1):P3V3_AUX   I151 @SCM_LIB.SCM(SCH_1):PAGE35
     2 PWRGD_P5V_AUX_R1 @SCM_LIB.SCM(SCH_1):PWRGD_P5V_AUX_R1   I151 @SCM_LIB.SCM(SCH_1):PAGE35

R887 Q_RES_0402LF-4.7K,1%,1/16W,EMPA
     1 P3V3_AUX @SCM_LIB.SCM(SCH_1):P3V3_AUX   I106 @SCM_LIB.SCM(SCH_1):PAGE22
     2 RST_BMC_HW @SCM_LIB.SCM(SCH_1):RST_BMC_HW   I106 @SCM_LIB.SCM(SCH_1):PAGE22

R888 Q_RES_0402LF-1K,1%,1/16W,EMPTYA
     1 P3V3_AUX @SCM_LIB.SCM(SCH_1):P3V3_AUX   I102 @SCM_LIB.SCM(SCH_1):PAGE22
     2 RST_BMC_SELF_HW @SCM_LIB.SCM(SCH_1):RST_BMC_SELF_HW   I102 @SCM_LIB.SCM(SCH_1):PAGE22

R898 Q_RES_0402LF-0,5%,1/16W,CHIP,CA
     1 FM_UARTSW_LSB_R_N @SCM_LIB.SCM(SCH_1):FM_UARTSW_LSB_R_N    I42 @SCM_LIB.SCM(SCH_1):PAGE36
     2 FM_UARTSW_LSB_N @SCM_LIB.SCM(SCH_1):FM_UARTSW_LSB_N    I42 @SCM_LIB.SCM(SCH_1):PAGE36

R899 Q_RES_0402LF-0,5%,1/16W,CHIP,CA
     1 FM_UARTSW_MSB_R_N @SCM_LIB.SCM(SCH_1):FM_UARTSW_MSB_R_N    I43 @SCM_LIB.SCM(SCH_1):PAGE36
     2 FM_UARTSW_MSB_N @SCM_LIB.SCM(SCH_1):FM_UARTSW_MSB_N    I43 @SCM_LIB.SCM(SCH_1):PAGE36

R900 Q_RES_0402LF-0,5%,1/16W,CHIP,CA
     1 UART_BIC_DBG_TX @SCM_LIB.SCM(SCH_1):UART_BIC_DBG_TX    I70 @SCM_LIB.SCM(SCH_1):PAGE31
     2 UART_BIC_DBG_TX_R @SCM_LIB.SCM(SCH_1):UART_BIC_DBG_TX_R    I70 @SCM_LIB.SCM(SCH_1):PAGE31

R901 Q_RES_0402LF-0,5%,1/16W,CHIP,CA
     1 UART_6_BMC_RXD @SCM_LIB.SCM(SCH_1):UART_6_BMC_RXD    I71 @SCM_LIB.SCM(SCH_1):PAGE31
     2 UART_6_BMC_RXD_R @SCM_LIB.SCM(SCH_1):UART_6_BMC_RXD_R    I71 @SCM_LIB.SCM(SCH_1):PAGE31

R902 Q_RES_0402LF-0,5%,1/16W,CHIP,CA
     1 UART_BIC_DBG_RX @SCM_LIB.SCM(SCH_1):UART_BIC_DBG_RX    I72 @SCM_LIB.SCM(SCH_1):PAGE31
     2 UART_BIC_DBG_RX_R @SCM_LIB.SCM(SCH_1):UART_BIC_DBG_RX_R    I72 @SCM_LIB.SCM(SCH_1):PAGE31

R903 Q_RES_0402LF-0,5%,1/16W,CHIP,CA
     1 UART_6_BMC_TXD @SCM_LIB.SCM(SCH_1):UART_6_BMC_TXD    I73 @SCM_LIB.SCM(SCH_1):PAGE31
     2 UART_6_BMC_TXD_R @SCM_LIB.SCM(SCH_1):UART_6_BMC_TXD_R    I73 @SCM_LIB.SCM(SCH_1):PAGE31

 SW6 SW_PUSHBUTTON4P_12_G34_H2-SW4SA
     1    GND @SCM_LIB.SCM(SCH_1):GND   I292 @SCM_LIB.SCM(SCH_1):PAGE50
     2 REAR_PWR_BTN_N @SCM_LIB.SCM(SCH_1):REAR_PWR_BTN_N   I292 @SCM_LIB.SCM(SCH_1):PAGE50
     3    GND @SCM_LIB.SCM(SCH_1):GND   I292 @SCM_LIB.SCM(SCH_1):PAGE50
     4    GND @SCM_LIB.SCM(SCH_1):GND   I292 @SCM_LIB.SCM(SCH_1):PAGE50

 SW7 SW_PUSHBUTTON4P_12_G34_H2-SW4SA
     1    GND @SCM_LIB.SCM(SCH_1):GND   I204 @SCM_LIB.SCM(SCH_1):PAGE50
     2 REAR_ID_RST_BTN_N @SCM_LIB.SCM(SCH_1):REAR_ID_RST_BTN_N   I204 @SCM_LIB.SCM(SCH_1):PAGE50
     3    GND @SCM_LIB.SCM(SCH_1):GND   I204 @SCM_LIB.SCM(SCH_1):PAGE50
     4    GND @SCM_LIB.SCM(SCH_1):GND   I204 @SCM_LIB.SCM(SCH_1):PAGE50

 SW8 SW_PUSHBUTTON4P_12_G34_H2-SW4SA
     1    GND @SCM_LIB.SCM(SCH_1):GND   I293 @SCM_LIB.SCM(SCH_1):PAGE50
     2 REAR_AC_PWR_BTN @SCM_LIB.SCM(SCH_1):REAR_AC_PWR_BTN   I293 @SCM_LIB.SCM(SCH_1):PAGE50
     3    GND @SCM_LIB.SCM(SCH_1):GND   I293 @SCM_LIB.SCM(SCH_1):PAGE50
     4    GND @SCM_LIB.SCM(SCH_1):GND   I293 @SCM_LIB.SCM(SCH_1):PAGE50

  U1 K4A8G165WCBCTD-K4A8G165WC-BCTDA
    P3 M_BMC_DDR4_MA<0> @SCM_LIB.SCM(SCH_1):M_BMC_DDR4_MA(0)   I196 @SCM_LIB.SCM(SCH_1):PAGE20
    P7 M_BMC_DDR4_MA<1> @SCM_LIB.SCM(SCH_1):M_BMC_DDR4_MA(1)   I196 @SCM_LIB.SCM(SCH_1):PAGE20
    M3 M_BMC_DDR4_MA<10> @SCM_LIB.SCM(SCH_1):M_BMC_DDR4_MA(10)   I196 @SCM_LIB.SCM(SCH_1):PAGE20
    T2 M_BMC_DDR4_MA<11> @SCM_LIB.SCM(SCH_1):M_BMC_DDR4_MA(11)   I196 @SCM_LIB.SCM(SCH_1):PAGE20
    M7 M_BMC_DDR4_MA<12> @SCM_LIB.SCM(SCH_1):M_BMC_DDR4_MA(12)   I196 @SCM_LIB.SCM(SCH_1):PAGE20
    T8 M_BMC_DDR4_MA<13> @SCM_LIB.SCM(SCH_1):M_BMC_DDR4_MA(13)   I196 @SCM_LIB.SCM(SCH_1):PAGE20
    R3 M_BMC_DDR4_MA<2> @SCM_LIB.SCM(SCH_1):M_BMC_DDR4_MA(2)   I196 @SCM_LIB.SCM(SCH_1):PAGE20
    N7 M_BMC_DDR4_MA<3> @SCM_LIB.SCM(SCH_1):M_BMC_DDR4_MA(3)   I196 @SCM_LIB.SCM(SCH_1):PAGE20
    N3 M_BMC_DDR4_MA<4> @SCM_LIB.SCM(SCH_1):M_BMC_DDR4_MA(4)   I196 @SCM_LIB.SCM(SCH_1):PAGE20
    P8 M_BMC_DDR4_MA<5> @SCM_LIB.SCM(SCH_1):M_BMC_DDR4_MA(5)   I196 @SCM_LIB.SCM(SCH_1):PAGE20
    P2 M_BMC_DDR4_MA<6> @SCM_LIB.SCM(SCH_1):M_BMC_DDR4_MA(6)   I196 @SCM_LIB.SCM(SCH_1):PAGE20
    R8 M_BMC_DDR4_MA<7> @SCM_LIB.SCM(SCH_1):M_BMC_DDR4_MA(7)   I196 @SCM_LIB.SCM(SCH_1):PAGE20
    R2 M_BMC_DDR4_MA<8> @SCM_LIB.SCM(SCH_1):M_BMC_DDR4_MA(8)   I196 @SCM_LIB.SCM(SCH_1):PAGE20
    R7 M_BMC_DDR4_MA<9> @SCM_LIB.SCM(SCH_1):M_BMC_DDR4_MA(9)   I196 @SCM_LIB.SCM(SCH_1):PAGE20
    L3 M_BMC_DDR4_MACT_N @SCM_LIB.SCM(SCH_1):M_BMC_DDR4_MACT_N   I196 @SCM_LIB.SCM(SCH_1):PAGE20
    P9 M_BMC_DDR4_ALERT_N @SCM_LIB.SCM(SCH_1):M_BMC_DDR4_ALERT_N   I196 @SCM_LIB.SCM(SCH_1):PAGE20
    N2 M_BMC_DDR4_MBA0 @SCM_LIB.SCM(SCH_1):M_BMC_DDR4_MBA0   I196 @SCM_LIB.SCM(SCH_1):PAGE20
    N8 M_BMC_DDR4_MBA1 @SCM_LIB.SCM(SCH_1):M_BMC_DDR4_MBA1   I196 @SCM_LIB.SCM(SCH_1):PAGE20
    M2 M_BMC_DDR4_MBG0 @SCM_LIB.SCM(SCH_1):M_BMC_DDR4_MBG0   I196 @SCM_LIB.SCM(SCH_1):PAGE20
    M8 M_BMC_DDR4_MCAS_N @SCM_LIB.SCM(SCH_1):M_BMC_DDR4_MCAS_N   I196 @SCM_LIB.SCM(SCH_1):PAGE20
    L7 M_BMC_DDR4_MCS_N @SCM_LIB.SCM(SCH_1):M_BMC_DDR4_MCS_N   I196 @SCM_LIB.SCM(SCH_1):PAGE20
    K2 M_BMC_DDR4_MCKE @SCM_LIB.SCM(SCH_1):M_BMC_DDR4_MCKE   I196 @SCM_LIB.SCM(SCH_1):PAGE20
    T7    GND @SCM_LIB.SCM(SCH_1):GND   I196 @SCM_LIB.SCM(SCH_1):PAGE20
    K3 M_BMC_DDR4_MODT @SCM_LIB.SCM(SCH_1):M_BMC_DDR4_MODT   I196 @SCM_LIB.SCM(SCH_1):PAGE20
    L8 M_BMC_DDR4_MRAS_N @SCM_LIB.SCM(SCH_1):M_BMC_DDR4_MRAS_N   I196 @SCM_LIB.SCM(SCH_1):PAGE20
    B3 P1V2_AUX @SCM_LIB.SCM(SCH_1):P1V2_AUX   I196 @SCM_LIB.SCM(SCH_1):PAGE20
    B9 P1V2_AUX @SCM_LIB.SCM(SCH_1):P1V2_AUX   I196 @SCM_LIB.SCM(SCH_1):PAGE20
    D1 P1V2_AUX @SCM_LIB.SCM(SCH_1):P1V2_AUX   I196 @SCM_LIB.SCM(SCH_1):PAGE20
    G7 P1V2_AUX @SCM_LIB.SCM(SCH_1):P1V2_AUX   I196 @SCM_LIB.SCM(SCH_1):PAGE20
    J1 P1V2_AUX @SCM_LIB.SCM(SCH_1):P1V2_AUX   I196 @SCM_LIB.SCM(SCH_1):PAGE20
    J9 P1V2_AUX @SCM_LIB.SCM(SCH_1):P1V2_AUX   I196 @SCM_LIB.SCM(SCH_1):PAGE20
    L1 P1V2_AUX @SCM_LIB.SCM(SCH_1):P1V2_AUX   I196 @SCM_LIB.SCM(SCH_1):PAGE20
    L9 P1V2_AUX @SCM_LIB.SCM(SCH_1):P1V2_AUX   I196 @SCM_LIB.SCM(SCH_1):PAGE20
    R1 P1V2_AUX @SCM_LIB.SCM(SCH_1):P1V2_AUX   I196 @SCM_LIB.SCM(SCH_1):PAGE20
    T9 P1V2_AUX @SCM_LIB.SCM(SCH_1):P1V2_AUX   I196 @SCM_LIB.SCM(SCH_1):PAGE20
    A1 P1V2_AUX @SCM_LIB.SCM(SCH_1):P1V2_AUX   I196 @SCM_LIB.SCM(SCH_1):PAGE20
    A9 P1V2_AUX @SCM_LIB.SCM(SCH_1):P1V2_AUX   I196 @SCM_LIB.SCM(SCH_1):PAGE20
    C1 P1V2_AUX @SCM_LIB.SCM(SCH_1):P1V2_AUX   I196 @SCM_LIB.SCM(SCH_1):PAGE20
    D9 P1V2_AUX @SCM_LIB.SCM(SCH_1):P1V2_AUX   I196 @SCM_LIB.SCM(SCH_1):PAGE20
    F2 P1V2_AUX @SCM_LIB.SCM(SCH_1):P1V2_AUX   I196 @SCM_LIB.SCM(SCH_1):PAGE20
    F8 P1V2_AUX @SCM_LIB.SCM(SCH_1):P1V2_AUX   I196 @SCM_LIB.SCM(SCH_1):PAGE20
    G1 P1V2_AUX @SCM_LIB.SCM(SCH_1):P1V2_AUX   I196 @SCM_LIB.SCM(SCH_1):PAGE20
    G9 P1V2_AUX @SCM_LIB.SCM(SCH_1):P1V2_AUX   I196 @SCM_LIB.SCM(SCH_1):PAGE20
    J2 P1V2_AUX @SCM_LIB.SCM(SCH_1):P1V2_AUX   I196 @SCM_LIB.SCM(SCH_1):PAGE20
    J8 P1V2_AUX @SCM_LIB.SCM(SCH_1):P1V2_AUX   I196 @SCM_LIB.SCM(SCH_1):PAGE20
    B1 P2V5_AUX @SCM_LIB.SCM(SCH_1):P2V5_AUX   I196 @SCM_LIB.SCM(SCH_1):PAGE20
    R9 P2V5_AUX @SCM_LIB.SCM(SCH_1):P2V5_AUX   I196 @SCM_LIB.SCM(SCH_1):PAGE20
    L2 M_BMC_DDR4_MWE_N @SCM_LIB.SCM(SCH_1):M_BMC_DDR4_MWE_N   I196 @SCM_LIB.SCM(SCH_1):PAGE20
    F9 PD_M_BMC_DDR4_ZQ @SCM_LIB.SCM(SCH_1):PD_M_BMC_DDR4_ZQ   I196 @SCM_LIB.SCM(SCH_1):PAGE20
    G2 M_BMC_DDR4_DQ<0> @SCM_LIB.SCM(SCH_1):M_BMC_DDR4_DQ(0)   I196 @SCM_LIB.SCM(SCH_1):PAGE20
    F7 M_BMC_DDR4_DQ<1> @SCM_LIB.SCM(SCH_1):M_BMC_DDR4_DQ(1)   I196 @SCM_LIB.SCM(SCH_1):PAGE20
    H3 M_BMC_DDR4_DQ<2> @SCM_LIB.SCM(SCH_1):M_BMC_DDR4_DQ(2)   I196 @SCM_LIB.SCM(SCH_1):PAGE20
    H7 M_BMC_DDR4_DQ<3> @SCM_LIB.SCM(SCH_1):M_BMC_DDR4_DQ(3)   I196 @SCM_LIB.SCM(SCH_1):PAGE20
    H2 M_BMC_DDR4_DQ<4> @SCM_LIB.SCM(SCH_1):M_BMC_DDR4_DQ(4)   I196 @SCM_LIB.SCM(SCH_1):PAGE20
    H8 M_BMC_DDR4_DQ<5> @SCM_LIB.SCM(SCH_1):M_BMC_DDR4_DQ(5)   I196 @SCM_LIB.SCM(SCH_1):PAGE20
    J3 M_BMC_DDR4_DQ<6> @SCM_LIB.SCM(SCH_1):M_BMC_DDR4_DQ(6)   I196 @SCM_LIB.SCM(SCH_1):PAGE20
    J7 M_BMC_DDR4_DQ<7> @SCM_LIB.SCM(SCH_1):M_BMC_DDR4_DQ(7)   I196 @SCM_LIB.SCM(SCH_1):PAGE20
    A3 M_BMC_DDR4_DQ<8> @SCM_LIB.SCM(SCH_1):M_BMC_DDR4_DQ(8)   I196 @SCM_LIB.SCM(SCH_1):PAGE20
    B8 M_BMC_DDR4_DQ<9> @SCM_LIB.SCM(SCH_1):M_BMC_DDR4_DQ(9)   I196 @SCM_LIB.SCM(SCH_1):PAGE20
    C3 M_BMC_DDR4_DQ<10> @SCM_LIB.SCM(SCH_1):M_BMC_DDR4_DQ(10)   I196 @SCM_LIB.SCM(SCH_1):PAGE20
    C7 M_BMC_DDR4_DQ<11> @SCM_LIB.SCM(SCH_1):M_BMC_DDR4_DQ(11)   I196 @SCM_LIB.SCM(SCH_1):PAGE20
    C2 M_BMC_DDR4_DQ<12> @SCM_LIB.SCM(SCH_1):M_BMC_DDR4_DQ(12)   I196 @SCM_LIB.SCM(SCH_1):PAGE20
    C8 M_BMC_DDR4_DQ<13> @SCM_LIB.SCM(SCH_1):M_BMC_DDR4_DQ(13)   I196 @SCM_LIB.SCM(SCH_1):PAGE20
    D3 M_BMC_DDR4_DQ<14> @SCM_LIB.SCM(SCH_1):M_BMC_DDR4_DQ(14)   I196 @SCM_LIB.SCM(SCH_1):PAGE20
    D7 M_BMC_DDR4_DQ<15> @SCM_LIB.SCM(SCH_1):M_BMC_DDR4_DQ(15)   I196 @SCM_LIB.SCM(SCH_1):PAGE20
    K7 M_BMC_DDR4_MCLK_DP @SCM_LIB.SCM(SCH_1):M_BMC_DDR4_MCLK_DP   I196 @SCM_LIB.SCM(SCH_1):PAGE20
    K8 M_BMC_DDR4_MCLK_DN @SCM_LIB.SCM(SCH_1):M_BMC_DDR4_MCLK_DN   I196 @SCM_LIB.SCM(SCH_1):PAGE20
    B7 M_BMC_DDR4_DQS1_P @SCM_LIB.SCM(SCH_1):M_BMC_DDR4_DQS1_P   I196 @SCM_LIB.SCM(SCH_1):PAGE20
    A7 M_BMC_DDR4_DQS1_N @SCM_LIB.SCM(SCH_1):M_BMC_DDR4_DQS1_N   I196 @SCM_LIB.SCM(SCH_1):PAGE20
    G3 M_BMC_DDR4_DQS0_P @SCM_LIB.SCM(SCH_1):M_BMC_DDR4_DQS0_P   I196 @SCM_LIB.SCM(SCH_1):PAGE20
    F3 M_BMC_DDR4_DQS0_N @SCM_LIB.SCM(SCH_1):M_BMC_DDR4_DQS0_N   I196 @SCM_LIB.SCM(SCH_1):PAGE20
    N9 PD_M_BMC_DDR4_TEN @SCM_LIB.SCM(SCH_1):PD_M_BMC_DDR4_TEN   I196 @SCM_LIB.SCM(SCH_1):PAGE20
    T3 PD_M_BMC_DDR4_PAR @SCM_LIB.SCM(SCH_1):PD_M_BMC_DDR4_PAR   I196 @SCM_LIB.SCM(SCH_1):PAGE20
    M1 P0V6_DDR_VREF_AUX @SCM_LIB.SCM(SCH_1):P0V6_DDR_VREF_AUX   I196 @SCM_LIB.SCM(SCH_1):PAGE20
    B2    GND @SCM_LIB.SCM(SCH_1):GND   I196 @SCM_LIB.SCM(SCH_1):PAGE20
    E1    GND @SCM_LIB.SCM(SCH_1):GND   I196 @SCM_LIB.SCM(SCH_1):PAGE20
    E9 M_BMC_DDR4_ZQU @SCM_LIB.SCM(SCH_1):M_BMC_DDR4_ZQU   I196 @SCM_LIB.SCM(SCH_1):PAGE20
    G8    GND @SCM_LIB.SCM(SCH_1):GND   I196 @SCM_LIB.SCM(SCH_1):PAGE20
    K1    GND @SCM_LIB.SCM(SCH_1):GND   I196 @SCM_LIB.SCM(SCH_1):PAGE20
    K9    GND @SCM_LIB.SCM(SCH_1):GND   I196 @SCM_LIB.SCM(SCH_1):PAGE20
    M9 M_BMC_DDR4_BG1 @SCM_LIB.SCM(SCH_1):M_BMC_DDR4_BG1   I196 @SCM_LIB.SCM(SCH_1):PAGE20
    N1    GND @SCM_LIB.SCM(SCH_1):GND   I196 @SCM_LIB.SCM(SCH_1):PAGE20
    T1    GND @SCM_LIB.SCM(SCH_1):GND   I196 @SCM_LIB.SCM(SCH_1):PAGE20
    A2    GND @SCM_LIB.SCM(SCH_1):GND   I196 @SCM_LIB.SCM(SCH_1):PAGE20
    A8    GND @SCM_LIB.SCM(SCH_1):GND   I196 @SCM_LIB.SCM(SCH_1):PAGE20
    C9    GND @SCM_LIB.SCM(SCH_1):GND   I196 @SCM_LIB.SCM(SCH_1):PAGE20
    D2    GND @SCM_LIB.SCM(SCH_1):GND   I196 @SCM_LIB.SCM(SCH_1):PAGE20
    D8    GND @SCM_LIB.SCM(SCH_1):GND   I196 @SCM_LIB.SCM(SCH_1):PAGE20
    E3    GND @SCM_LIB.SCM(SCH_1):GND   I196 @SCM_LIB.SCM(SCH_1):PAGE20
    E8    GND @SCM_LIB.SCM(SCH_1):GND   I196 @SCM_LIB.SCM(SCH_1):PAGE20
    F1    GND @SCM_LIB.SCM(SCH_1):GND   I196 @SCM_LIB.SCM(SCH_1):PAGE20
    H1    GND @SCM_LIB.SCM(SCH_1):GND   I196 @SCM_LIB.SCM(SCH_1):PAGE20
    H9    GND @SCM_LIB.SCM(SCH_1):GND   I196 @SCM_LIB.SCM(SCH_1):PAGE20
    E7 M_BMC_DDR4_MDM0 @SCM_LIB.SCM(SCH_1):M_BMC_DDR4_MDM0   I196 @SCM_LIB.SCM(SCH_1):PAGE20
    E2 M_BMC_DDR4_MDM1 @SCM_LIB.SCM(SCH_1):M_BMC_DDR4_MDM1   I196 @SCM_LIB.SCM(SCH_1):PAGE20
    P1 M_BMC_DDR4_RST_N @SCM_LIB.SCM(SCH_1):M_BMC_DDR4_RST_N   I196 @SCM_LIB.SCM(SCH_1):PAGE20

  U2 FSA3357K8X-FSA3357K8X,SMLF,IC,A
     7 SPA_SOUT_SW_BUF @SCM_LIB.SCM(SCH_1):SPA_SOUT_SW_BUF   I250 @SCM_LIB.SCM(SCH_1):PAGE30
     4    GND @SCM_LIB.SCM(SCH_1):GND   I250 @SCM_LIB.SCM(SCH_1):PAGE30
     3 UART_BMC_1_TXD_R @SCM_LIB.SCM(SCH_1):UART_BMC_1_TXD_R   I250 @SCM_LIB.SCM(SCH_1):PAGE30
     5 FM_UARTSW_LSB_N @SCM_LIB.SCM(SCH_1):FM_UARTSW_LSB_N   I250 @SCM_LIB.SCM(SCH_1):PAGE30
     8 P3V3_AUX @SCM_LIB.SCM(SCH_1):P3V3_AUX   I250 @SCM_LIB.SCM(SCH_1):PAGE30
     2 UART_BMC_5_TXD_BUF1_R @SCM_LIB.SCM(SCH_1):UART_BMC_5_TXD_BUF1_R   I250 @SCM_LIB.SCM(SCH_1):PAGE30
     1 UART_BIC_DBG_TX @SCM_LIB.SCM(SCH_1):UART_BIC_DBG_TX   I250 @SCM_LIB.SCM(SCH_1):PAGE30
     6 FM_UARTSW_MSB_N @SCM_LIB.SCM(SCH_1):FM_UARTSW_MSB_N   I250 @SCM_LIB.SCM(SCH_1):PAGE30

  U3 FSA3357K8X-FSA3357K8X,SMLF,IC,A
     7 SPA_SIN_SW_BUF @SCM_LIB.SCM(SCH_1):SPA_SIN_SW_BUF   I251 @SCM_LIB.SCM(SCH_1):PAGE30
     4    GND @SCM_LIB.SCM(SCH_1):GND   I251 @SCM_LIB.SCM(SCH_1):PAGE30
     3 UART_BMC_1_RXD_R @SCM_LIB.SCM(SCH_1):UART_BMC_1_RXD_R   I251 @SCM_LIB.SCM(SCH_1):PAGE30
     5 FM_UARTSW_LSB_N @SCM_LIB.SCM(SCH_1):FM_UARTSW_LSB_N   I251 @SCM_LIB.SCM(SCH_1):PAGE30
     8 P3V3_AUX @SCM_LIB.SCM(SCH_1):P3V3_AUX   I251 @SCM_LIB.SCM(SCH_1):PAGE30
     2 UART_BMC_5_RXD_BUF1_SW @SCM_LIB.SCM(SCH_1):UART_BMC_5_RXD_BUF1_SW   I251 @SCM_LIB.SCM(SCH_1):PAGE30
     1 UART_BIC_DBG_RX @SCM_LIB.SCM(SCH_1):UART_BIC_DBG_RX   I251 @SCM_LIB.SCM(SCH_1):PAGE30
     6 FM_UARTSW_MSB_N @SCM_LIB.SCM(SCH_1):FM_UARTSW_MSB_N   I251 @SCM_LIB.SCM(SCH_1):PAGE30

  U5 AST2600A3GP-AST2600A3-GP,SMLF,A
    T5 P0V6_DDR_VREF_AUX @SCM_LIB.SCM(SCH_1):P0V6_DDR_VREF_AUX   I436 @SCM_LIB.SCM(SCH_1):PAGE12
    P5 IBMC_MIOZ @SCM_LIB.SCM(SCH_1):IBMC_MIOZ   I436 @SCM_LIB.SCM(SCH_1):PAGE12
    L3 M_BMC_DDR4_RST_N @SCM_LIB.SCM(SCH_1):M_BMC_DDR4_RST_N   I436 @SCM_LIB.SCM(SCH_1):PAGE12
    N4 M_BMC_DDR4_ALERT_N @SCM_LIB.SCM(SCH_1):M_BMC_DDR4_ALERT_N   I436 @SCM_LIB.SCM(SCH_1):PAGE12
    T3 M_BMC_DDR4_DQ<0> @SCM_LIB.SCM(SCH_1):M_BMC_DDR4_DQ(0)   I436 @SCM_LIB.SCM(SCH_1):PAGE12
    R4 M_BMC_DDR4_DQ<1> @SCM_LIB.SCM(SCH_1):M_BMC_DDR4_DQ(1)   I436 @SCM_LIB.SCM(SCH_1):PAGE12
    U1 M_BMC_DDR4_DQ<2> @SCM_LIB.SCM(SCH_1):M_BMC_DDR4_DQ(2)   I436 @SCM_LIB.SCM(SCH_1):PAGE12
    R3 M_BMC_DDR4_DQ<3> @SCM_LIB.SCM(SCH_1):M_BMC_DDR4_DQ(3)   I436 @SCM_LIB.SCM(SCH_1):PAGE12
    R1 M_BMC_DDR4_DQ<4> @SCM_LIB.SCM(SCH_1):M_BMC_DDR4_DQ(4)   I436 @SCM_LIB.SCM(SCH_1):PAGE12
    P1 M_BMC_DDR4_DQ<5> @SCM_LIB.SCM(SCH_1):M_BMC_DDR4_DQ(5)   I436 @SCM_LIB.SCM(SCH_1):PAGE12
    P2 M_BMC_DDR4_DQ<6> @SCM_LIB.SCM(SCH_1):M_BMC_DDR4_DQ(6)   I436 @SCM_LIB.SCM(SCH_1):PAGE12
    P3 M_BMC_DDR4_DQ<7> @SCM_LIB.SCM(SCH_1):M_BMC_DDR4_DQ(7)   I436 @SCM_LIB.SCM(SCH_1):PAGE12
    W2 M_BMC_DDR4_DQ<8> @SCM_LIB.SCM(SCH_1):M_BMC_DDR4_DQ(8)   I436 @SCM_LIB.SCM(SCH_1):PAGE12
    V3 M_BMC_DDR4_DQ<9> @SCM_LIB.SCM(SCH_1):M_BMC_DDR4_DQ(9)   I436 @SCM_LIB.SCM(SCH_1):PAGE12
    W1 M_BMC_DDR4_DQ<10> @SCM_LIB.SCM(SCH_1):M_BMC_DDR4_DQ(10)   I436 @SCM_LIB.SCM(SCH_1):PAGE12
    W3 M_BMC_DDR4_DQ<11> @SCM_LIB.SCM(SCH_1):M_BMC_DDR4_DQ(11)   I436 @SCM_LIB.SCM(SCH_1):PAGE12
    W4 M_BMC_DDR4_DQ<12> @SCM_LIB.SCM(SCH_1):M_BMC_DDR4_DQ(12)   I436 @SCM_LIB.SCM(SCH_1):PAGE12
    U4 M_BMC_DDR4_DQ<13> @SCM_LIB.SCM(SCH_1):M_BMC_DDR4_DQ(13)   I436 @SCM_LIB.SCM(SCH_1):PAGE12
    V4 M_BMC_DDR4_DQ<14> @SCM_LIB.SCM(SCH_1):M_BMC_DDR4_DQ(14)   I436 @SCM_LIB.SCM(SCH_1):PAGE12
    U3 M_BMC_DDR4_DQ<15> @SCM_LIB.SCM(SCH_1):M_BMC_DDR4_DQ(15)   I436 @SCM_LIB.SCM(SCH_1):PAGE12
    T2 M_BMC_DDR4_DQS0_P @SCM_LIB.SCM(SCH_1):M_BMC_DDR4_DQS0_P   I436 @SCM_LIB.SCM(SCH_1):PAGE12
    V2 M_BMC_DDR4_DQS1_P @SCM_LIB.SCM(SCH_1):M_BMC_DDR4_DQS1_P   I436 @SCM_LIB.SCM(SCH_1):PAGE12
    T1 M_BMC_DDR4_DQS0_N @SCM_LIB.SCM(SCH_1):M_BMC_DDR4_DQS0_N   I436 @SCM_LIB.SCM(SCH_1):PAGE12
    V1 M_BMC_DDR4_DQS1_N @SCM_LIB.SCM(SCH_1):M_BMC_DDR4_DQS1_N   I436 @SCM_LIB.SCM(SCH_1):PAGE12
   AE7 ESPI_HOST_LPC_BMC_CLK_R @SCM_LIB.SCM(SCH_1):ESPI_HOST_LPC_BMC_CLK_R   I436 @SCM_LIB.SCM(SCH_1):PAGE12
   AF7 ESPI_HOST_LPC_BMC_LFRAME_N_R @SCM_LIB.SCM(SCH_1):ESPI_HOST_LPC_BMC_LFRAME_N_R   I436 @SCM_LIB.SCM(SCH_1):PAGE12
   AD7 IRQ_ESPI_LPC_SERIRQ_ALERT0_N @SCM_LIB.SCM(SCH_1):IRQ_ESPI_LPC_SERIRQ_ALERT0_N   I436 @SCM_LIB.SCM(SCH_1):PAGE12
   AD8 RST_ESPI_LPC_BMC_N @SCM_LIB.SCM(SCH_1):RST_ESPI_LPC_BMC_N   I436 @SCM_LIB.SCM(SCH_1):PAGE12
   D22 BMC_EMMC_CLK @SCM_LIB.SCM(SCH_1):BMC_EMMC_CLK   I436 @SCM_LIB.SCM(SCH_1):PAGE12
   E22 BMC_EMMC_CMD @SCM_LIB.SCM(SCH_1):BMC_EMMC_CMD   I436 @SCM_LIB.SCM(SCH_1):PAGE12
   D23 BMC_EMMC_DT0 @SCM_LIB.SCM(SCH_1):BMC_EMMC_DT0   I436 @SCM_LIB.SCM(SCH_1):PAGE12
   C23 BMC_EMMC_DT1 @SCM_LIB.SCM(SCH_1):BMC_EMMC_DT1   I436 @SCM_LIB.SCM(SCH_1):PAGE12
   C22 BMC_EMMC_DT2 @SCM_LIB.SCM(SCH_1):BMC_EMMC_DT2   I436 @SCM_LIB.SCM(SCH_1):PAGE12
   A25 BMC_EMMC_DT3 @SCM_LIB.SCM(SCH_1):BMC_EMMC_DT3   I436 @SCM_LIB.SCM(SCH_1):PAGE12
   A24 BMC_EMMC_CD_N @SCM_LIB.SCM(SCH_1):BMC_EMMC_CD_N   I436 @SCM_LIB.SCM(SCH_1):PAGE12
   A23 BMC_EMMC_WP_N @SCM_LIB.SCM(SCH_1):BMC_EMMC_WP_N   I436 @SCM_LIB.SCM(SCH_1):PAGE12
   E21 UART_6_BMC_R_TXD @SCM_LIB.SCM(SCH_1):UART_6_BMC_R_TXD   I436 @SCM_LIB.SCM(SCH_1):PAGE12
   B22 UART_6_BMC_R_RXD @SCM_LIB.SCM(SCH_1):UART_6_BMC_R_RXD   I436 @SCM_LIB.SCM(SCH_1):PAGE12
   C21 BMC_EMMC_DT4 @SCM_LIB.SCM(SCH_1):BMC_EMMC_DT4   I436 @SCM_LIB.SCM(SCH_1):PAGE12
   A22 BMC_EMMC_DT5 @SCM_LIB.SCM(SCH_1):BMC_EMMC_DT5   I436 @SCM_LIB.SCM(SCH_1):PAGE12
   A21 BMC_EMMC_DT6 @SCM_LIB.SCM(SCH_1):BMC_EMMC_DT6   I436 @SCM_LIB.SCM(SCH_1):PAGE12
   E20 BMC_EMMC_DT7 @SCM_LIB.SCM(SCH_1):BMC_EMMC_DT7   I436 @SCM_LIB.SCM(SCH_1):PAGE12
   D21 SMB_BMC_ALERT15_N @SCM_LIB.SCM(SCH_1):SMB_BMC_ALERT15_N   I436 @SCM_LIB.SCM(SCH_1):PAGE12
   B21 FM_BMC_DBP_PRESENT_R_N @SCM_LIB.SCM(SCH_1):FM_BMC_DBP_PRESENT_R_N   I436 @SCM_LIB.SCM(SCH_1):PAGE12
   AE4 P2E_PCH_TX_DP @SCM_LIB.SCM(SCH_1):P2E_PCH_TX_DP   I436 @SCM_LIB.SCM(SCH_1):PAGE12
   AE5 P2E_PCH_TX_DN @SCM_LIB.SCM(SCH_1):P2E_PCH_TX_DN   I436 @SCM_LIB.SCM(SCH_1):PAGE12
    A7 RST_PLTRST_N @SCM_LIB.SCM(SCH_1):RST_PLTRST_N   I436 @SCM_LIB.SCM(SCH_1):PAGE12
   AD5 CLK_100M_PCH_DP @SCM_LIB.SCM(SCH_1):CLK_100M_PCH_DP   I436 @SCM_LIB.SCM(SCH_1):PAGE12
   AD6 CLK_100M_PCH_DN @SCM_LIB.SCM(SCH_1):CLK_100M_PCH_DN   I436 @SCM_LIB.SCM(SCH_1):PAGE12
   AF5 P2E_PCH_RX_DP @SCM_LIB.SCM(SCH_1):P2E_PCH_RX_DP   I436 @SCM_LIB.SCM(SCH_1):PAGE12
   AF6 P2E_PCH_RX_DN @SCM_LIB.SCM(SCH_1):P2E_PCH_RX_DN   I436 @SCM_LIB.SCM(SCH_1):PAGE12
    U5 P0V6_DDR_VREF_AUX @SCM_LIB.SCM(SCH_1):P0V6_DDR_VREF_AUX   I436 @SCM_LIB.SCM(SCH_1):PAGE12
    K1 M_BMC_DDR4_MCLK_DN @SCM_LIB.SCM(SCH_1):M_BMC_DDR4_MCLK_DN   I436 @SCM_LIB.SCM(SCH_1):PAGE12
    H5 M_BMC_DDR4_MBA1 @SCM_LIB.SCM(SCH_1):M_BMC_DDR4_MBA1   I436 @SCM_LIB.SCM(SCH_1):PAGE12
    H3 M_BMC_DDR4_MA<3> @SCM_LIB.SCM(SCH_1):M_BMC_DDR4_MA(3)   I436 @SCM_LIB.SCM(SCH_1):PAGE12
    H1 M_BMC_DDR4_MACT_N @SCM_LIB.SCM(SCH_1):M_BMC_DDR4_MACT_N   I436 @SCM_LIB.SCM(SCH_1):PAGE12
    G3 M_BMC_DDR4_MBG0 @SCM_LIB.SCM(SCH_1):M_BMC_DDR4_MBG0   I436 @SCM_LIB.SCM(SCH_1):PAGE12
   E19 SMB_BMC_MM2_R_SCL @SCM_LIB.SCM(SCH_1):SMB_BMC_MM2_R_SCL   I436 @SCM_LIB.SCM(SCH_1):PAGE12
    F3 M_BMC_DDR4_MA<0> @SCM_LIB.SCM(SCH_1):M_BMC_DDR4_MA(0)   I436 @SCM_LIB.SCM(SCH_1):PAGE12
    K3 M_BMC_DDR4_MA<13> @SCM_LIB.SCM(SCH_1):M_BMC_DDR4_MA(13)   I436 @SCM_LIB.SCM(SCH_1):PAGE12
   E13 SMB_BMC_MM6_R_SDA @SCM_LIB.SCM(SCH_1):SMB_BMC_MM6_R_SDA   I436 @SCM_LIB.SCM(SCH_1):PAGE12
    G4 M_BMC_DDR4_MBA0 @SCM_LIB.SCM(SCH_1):M_BMC_DDR4_MBA0   I436 @SCM_LIB.SCM(SCH_1):PAGE12
    G1 M_BMC_DDR4_MA<11> @SCM_LIB.SCM(SCH_1):M_BMC_DDR4_MA(11)   I436 @SCM_LIB.SCM(SCH_1):PAGE12
    N3 M_BMC_DDR4_MDM0 @SCM_LIB.SCM(SCH_1):M_BMC_DDR4_MDM0   I436 @SCM_LIB.SCM(SCH_1):PAGE12
   D19 SMB_BMC_MM4_R_SDA @SCM_LIB.SCM(SCH_1):SMB_BMC_MM4_R_SDA   I436 @SCM_LIB.SCM(SCH_1):PAGE12
    M5 M_BMC_DDR4_MA<6> @SCM_LIB.SCM(SCH_1):M_BMC_DDR4_MA(6)   I436 @SCM_LIB.SCM(SCH_1):PAGE12
    L1 M_BMC_DDR4_MA<5> @SCM_LIB.SCM(SCH_1):M_BMC_DDR4_MA(5)   I436 @SCM_LIB.SCM(SCH_1):PAGE12
    H2 M_BMC_DDR4_MCS_N @SCM_LIB.SCM(SCH_1):M_BMC_DDR4_MCS_N   I436 @SCM_LIB.SCM(SCH_1):PAGE12
    M1 M_BMC_DDR4_MA<8> @SCM_LIB.SCM(SCH_1):M_BMC_DDR4_MA(8)   I436 @SCM_LIB.SCM(SCH_1):PAGE12
    L4 M_BMC_DDR4_MA<12> @SCM_LIB.SCM(SCH_1):M_BMC_DDR4_MA(12)   I436 @SCM_LIB.SCM(SCH_1):PAGE12
    R5 M_BMC_DDR4_MDM1 @SCM_LIB.SCM(SCH_1):M_BMC_DDR4_MDM1   I436 @SCM_LIB.SCM(SCH_1):PAGE12
   E11 SMB_BMC_MM7_R_SDA @SCM_LIB.SCM(SCH_1):SMB_BMC_MM7_R_SDA   I436 @SCM_LIB.SCM(SCH_1):PAGE12
    M3 M_BMC_DDR4_MBG1 @SCM_LIB.SCM(SCH_1):M_BMC_DDR4_MBG1   I436 @SCM_LIB.SCM(SCH_1):PAGE12
   B20 SMB_BMC_MM1_R_SCL @SCM_LIB.SCM(SCH_1):SMB_BMC_MM1_R_SCL   I436 @SCM_LIB.SCM(SCH_1):PAGE12
   F13 SMB_BMC_MM8_R_SCL @SCM_LIB.SCM(SCH_1):SMB_BMC_MM8_R_SCL   I436 @SCM_LIB.SCM(SCH_1):PAGE12
    F2 M_BMC_DDR4_MA<10> @SCM_LIB.SCM(SCH_1):M_BMC_DDR4_MA(10)   I436 @SCM_LIB.SCM(SCH_1):PAGE12
    J5 M_BMC_DDR4_MRAS_N @SCM_LIB.SCM(SCH_1):M_BMC_DDR4_MRAS_N   I436 @SCM_LIB.SCM(SCH_1):PAGE12
    J3 M_BMC_DDR4_MA<4> @SCM_LIB.SCM(SCH_1):M_BMC_DDR4_MA(4)   I436 @SCM_LIB.SCM(SCH_1):PAGE12
   D11 SMB_BMC_MM7_R_SCL @SCM_LIB.SCM(SCH_1):SMB_BMC_MM7_R_SCL   I436 @SCM_LIB.SCM(SCH_1):PAGE12
    N1 M_BMC_DDR4_MA<9> @SCM_LIB.SCM(SCH_1):M_BMC_DDR4_MA(9)   I436 @SCM_LIB.SCM(SCH_1):PAGE12
   C19 SMB_BMC_MM3_R_SCL @SCM_LIB.SCM(SCH_1):SMB_BMC_MM3_R_SCL   I436 @SCM_LIB.SCM(SCH_1):PAGE12
    K5 M_BMC_DDR4_MA<1> @SCM_LIB.SCM(SCH_1):M_BMC_DDR4_MA(1)   I436 @SCM_LIB.SCM(SCH_1):PAGE12
   D12 SMB_BMC_MM6_R_SCL @SCM_LIB.SCM(SCH_1):SMB_BMC_MM6_R_SCL   I436 @SCM_LIB.SCM(SCH_1):PAGE12
   D20 SMB_BMC_MM2_R_SDA @SCM_LIB.SCM(SCH_1):SMB_BMC_MM2_R_SDA   I436 @SCM_LIB.SCM(SCH_1):PAGE12
    J4 M_BMC_DDR4_MCAS_N @SCM_LIB.SCM(SCH_1):M_BMC_DDR4_MCAS_N   I436 @SCM_LIB.SCM(SCH_1):PAGE12
   AB7 ESPI_LPC_D0_IO0 @SCM_LIB.SCM(SCH_1):ESPI_LPC_D0_IO0   I436 @SCM_LIB.SCM(SCH_1):PAGE12
    K2 M_BMC_DDR4_MCLK_DP @SCM_LIB.SCM(SCH_1):M_BMC_DDR4_MCLK_DP   I436 @SCM_LIB.SCM(SCH_1):PAGE12
    F1 M_BMC_DDR4_MA<2> @SCM_LIB.SCM(SCH_1):M_BMC_DDR4_MA(2)   I436 @SCM_LIB.SCM(SCH_1):PAGE12
    G5 M_BMC_DDR4_MWE_N @SCM_LIB.SCM(SCH_1):M_BMC_DDR4_MWE_N   I436 @SCM_LIB.SCM(SCH_1):PAGE12
   C20 SMB_BMC_MM4_R_SCL @SCM_LIB.SCM(SCH_1):SMB_BMC_MM4_R_SCL   I436 @SCM_LIB.SCM(SCH_1):PAGE12
    M2 M_BMC_DDR4_MA<7> @SCM_LIB.SCM(SCH_1):M_BMC_DDR4_MA(7)   I436 @SCM_LIB.SCM(SCH_1):PAGE12
   A11 SMB_BMC_MM5_R_SCL @SCM_LIB.SCM(SCH_1):SMB_BMC_MM5_R_SCL   I436 @SCM_LIB.SCM(SCH_1):PAGE12
    J1 M_BMC_DDR4_MODT @SCM_LIB.SCM(SCH_1):M_BMC_DDR4_MODT   I436 @SCM_LIB.SCM(SCH_1):PAGE12
   AC7 ESPI_LPC_D3_IO3 @SCM_LIB.SCM(SCH_1):ESPI_LPC_D3_IO3   I436 @SCM_LIB.SCM(SCH_1):PAGE12
   A20 SMB_BMC_MM1_R_SDA @SCM_LIB.SCM(SCH_1):SMB_BMC_MM1_R_SDA   I436 @SCM_LIB.SCM(SCH_1):PAGE12
   AC8 ESPI_LPC_D2_IO2 @SCM_LIB.SCM(SCH_1):ESPI_LPC_D2_IO2   I436 @SCM_LIB.SCM(SCH_1):PAGE12
   A19 SMB_BMC_MM3_R_SDA @SCM_LIB.SCM(SCH_1):SMB_BMC_MM3_R_SDA   I436 @SCM_LIB.SCM(SCH_1):PAGE12
   AB8 ESPI_LPC_D1_IO1 @SCM_LIB.SCM(SCH_1):ESPI_LPC_D1_IO1   I436 @SCM_LIB.SCM(SCH_1):PAGE12
    L5 M_BMC_DDR4_MCKE @SCM_LIB.SCM(SCH_1):M_BMC_DDR4_MCKE   I436 @SCM_LIB.SCM(SCH_1):PAGE12
   C11 SMB_BMC_MM5_R_SDA @SCM_LIB.SCM(SCH_1):SMB_BMC_MM5_R_SDA   I436 @SCM_LIB.SCM(SCH_1):PAGE12
   E12 SMB_BMC_MM8_R_SDA @SCM_LIB.SCM(SCH_1):SMB_BMC_MM8_R_SDA   I436 @SCM_LIB.SCM(SCH_1):PAGE12
   AE1 CLK_100M_GPU_DP @SCM_LIB.SCM(SCH_1):CLK_100M_GPU_DP   I436 @SCM_LIB.SCM(SCH_1):PAGE12
   AE2 CLK_100M_GPU_DN @SCM_LIB.SCM(SCH_1):CLK_100M_GPU_DN   I436 @SCM_LIB.SCM(SCH_1):PAGE12
   AD2 P2E_GPU_RX_DP @SCM_LIB.SCM(SCH_1):P2E_GPU_RX_DP   I436 @SCM_LIB.SCM(SCH_1):PAGE12
   AD3 P2E_GPU_RX_DN @SCM_LIB.SCM(SCH_1):P2E_GPU_RX_DN   I436 @SCM_LIB.SCM(SCH_1):PAGE12
   AF2 P2E_GPU_TX_DN @SCM_LIB.SCM(SCH_1):P2E_GPU_TX_DN   I436 @SCM_LIB.SCM(SCH_1):PAGE12
   AF3 P2E_GPU_TX_DP @SCM_LIB.SCM(SCH_1):P2E_GPU_TX_DP   I436 @SCM_LIB.SCM(SCH_1):PAGE12
   AC1 NC_DP_BMC_TX0_P @SCM_LIB.SCM(SCH_1):NC_DP_BMC_TX0_P   I436 @SCM_LIB.SCM(SCH_1):PAGE12
   AB1 NC_DP_BMC_TX0_N @SCM_LIB.SCM(SCH_1):NC_DP_BMC_TX0_N   I436 @SCM_LIB.SCM(SCH_1):PAGE12
   AC3 NC_DP_BMC_AUX_P @SCM_LIB.SCM(SCH_1):NC_DP_BMC_AUX_P   I436 @SCM_LIB.SCM(SCH_1):PAGE12
   AB3 NC_DP_BMC_AUX_N @SCM_LIB.SCM(SCH_1):NC_DP_BMC_AUX_N   I436 @SCM_LIB.SCM(SCH_1):PAGE12
    C7 DP_BMC_HPD_3V3_BUF @SCM_LIB.SCM(SCH_1):DP_BMC_HPD_3V3_BUF   I436 @SCM_LIB.SCM(SCH_1):PAGE12
   AB2 NC_DP_BMC_TX1_P @SCM_LIB.SCM(SCH_1):NC_DP_BMC_TX1_P   I436 @SCM_LIB.SCM(SCH_1):PAGE12
   AA2 NC_DP_BMC_TX1_N @SCM_LIB.SCM(SCH_1):NC_DP_BMC_TX1_N   I436 @SCM_LIB.SCM(SCH_1):PAGE12
   D15 SMB_BMC_MM9_R_SCL @SCM_LIB.SCM(SCH_1):SMB_BMC_MM9_R_SCL   I436 @SCM_LIB.SCM(SCH_1):PAGE12
   A14 SMB_BMC_MM9_R_SDA @SCM_LIB.SCM(SCH_1):SMB_BMC_MM9_R_SDA   I436 @SCM_LIB.SCM(SCH_1):PAGE12
   E15 SMB_BMC_MM10_R_SCL @SCM_LIB.SCM(SCH_1):SMB_BMC_MM10_R_SCL   I436 @SCM_LIB.SCM(SCH_1):PAGE12
   A13 SMB_BMC_MM10_R_SDA @SCM_LIB.SCM(SCH_1):SMB_BMC_MM10_R_SDA   I436 @SCM_LIB.SCM(SCH_1):PAGE12
   M24 FM_PFR_DSW_PWROK_N @SCM_LIB.SCM(SCH_1):FM_PFR_DSW_PWROK_N   I436 @SCM_LIB.SCM(SCH_1):PAGE12
   M25 RST_PFR_OVR_RTC_R @SCM_LIB.SCM(SCH_1):RST_PFR_OVR_RTC_R   I436 @SCM_LIB.SCM(SCH_1):PAGE12
   L26 SMB_BMC_MM12_R_SCL @SCM_LIB.SCM(SCH_1):SMB_BMC_MM12_R_SCL   I436 @SCM_LIB.SCM(SCH_1):PAGE12
   K24 SMB_BMC_MM12_R_SDA @SCM_LIB.SCM(SCH_1):SMB_BMC_MM12_R_SDA   I436 @SCM_LIB.SCM(SCH_1):PAGE12
   L23 SMB_BMC_MM14_R_SCL @SCM_LIB.SCM(SCH_1):SMB_BMC_MM14_R_SCL   I436 @SCM_LIB.SCM(SCH_1):PAGE12
   K25 SMB_BMC_MM14_R_SDA @SCM_LIB.SCM(SCH_1):SMB_BMC_MM14_R_SDA   I436 @SCM_LIB.SCM(SCH_1):PAGE12
   K26 SMB_BMC_MM13_R_SCL @SCM_LIB.SCM(SCH_1):SMB_BMC_MM13_R_SCL   I436 @SCM_LIB.SCM(SCH_1):PAGE12
   L24 SMB_BMC_MM13_R_SDA @SCM_LIB.SCM(SCH_1):SMB_BMC_MM13_R_SDA   I436 @SCM_LIB.SCM(SCH_1):PAGE12
   A18 SGPIO_BMC_M1_CLK @SCM_LIB.SCM(SCH_1):SGPIO_BMC_M1_CLK   I436 @SCM_LIB.SCM(SCH_1):PAGE12
   B18 SGPIO_BMC_M1_LD @SCM_LIB.SCM(SCH_1):SGPIO_BMC_M1_LD   I436 @SCM_LIB.SCM(SCH_1):PAGE12
   C18 SGPIO_BMC_M1_DO @SCM_LIB.SCM(SCH_1):SGPIO_BMC_M1_DO   I436 @SCM_LIB.SCM(SCH_1):PAGE12
   A17 SGPIO_BMC_M1_DI @SCM_LIB.SCM(SCH_1):SGPIO_BMC_M1_DI   I436 @SCM_LIB.SCM(SCH_1):PAGE12
   D18 SMB_BMC_MM15_R_SCL @SCM_LIB.SCM(SCH_1):SMB_BMC_MM15_R_SCL   I436 @SCM_LIB.SCM(SCH_1):PAGE12
   B17 SMB_BMC_MM15_R_SDA @SCM_LIB.SCM(SCH_1):SMB_BMC_MM15_R_SDA   I436 @SCM_LIB.SCM(SCH_1):PAGE12
   C17 SMB_BMC_MM16_R_SCL @SCM_LIB.SCM(SCH_1):SMB_BMC_MM16_R_SCL   I436 @SCM_LIB.SCM(SCH_1):PAGE12
   E18 SMB_BMC_MM16_R_SDA @SCM_LIB.SCM(SCH_1):SMB_BMC_MM16_R_SDA   I436 @SCM_LIB.SCM(SCH_1):PAGE12
   T26 FM_THERMTRIP_DLY_LVC1_R_N @SCM_LIB.SCM(SCH_1):FM_THERMTRIP_DLY_LVC1_R_N   I436 @SCM_LIB.SCM(SCH_1):PAGE12
   R24 FM_TPM_PRSNT_1_N @SCM_LIB.SCM(SCH_1):FM_TPM_PRSNT_1_N   I436 @SCM_LIB.SCM(SCH_1):PAGE12
  AB14 SPI_BMC_BOOT_CS0_R1_N @SCM_LIB.SCM(SCH_1):SPI_BMC_BOOT_CS0_R1_N   I363 @SCM_LIB.SCM(SCH_1):PAGE13
   D14 H_CPU0_PROCHOT_LVC1_N @SCM_LIB.SCM(SCH_1):H_CPU0_PROCHOT_LVC1_N   I363 @SCM_LIB.SCM(SCH_1):PAGE13
   B13 FM_VIRTUAL_RESEAT_BMC @SCM_LIB.SCM(SCH_1):FM_VIRTUAL_RESEAT_BMC   I363 @SCM_LIB.SCM(SCH_1):PAGE13
   A12 PWRGD_PSU_AC_PWROK_BMC @SCM_LIB.SCM(SCH_1):PWRGD_PSU_AC_PWROK_BMC   I363 @SCM_LIB.SCM(SCH_1):PAGE13
   E14 FM_PECI_SEL_R_N @SCM_LIB.SCM(SCH_1):FM_PECI_SEL_R_N   I363 @SCM_LIB.SCM(SCH_1):PAGE13
   B12 PWRGD_SYS_PWROK_BMC @SCM_LIB.SCM(SCH_1):PWRGD_SYS_PWROK_BMC   I363 @SCM_LIB.SCM(SCH_1):PAGE13
   C12 FM_DBP_BMC_PRDY_R_N @SCM_LIB.SCM(SCH_1):FM_DBP_BMC_PRDY_R_N   I363 @SCM_LIB.SCM(SCH_1):PAGE13
   C13 UART_BMC_1_TXD @SCM_LIB.SCM(SCH_1):UART_BMC_1_TXD   I363 @SCM_LIB.SCM(SCH_1):PAGE13
   D13 UART_BMC_1_RXD @SCM_LIB.SCM(SCH_1):UART_BMC_1_RXD   I363 @SCM_LIB.SCM(SCH_1):PAGE13
   P25 LED_POSTCODE_0 @SCM_LIB.SCM(SCH_1):LED_POSTCODE_0   I363 @SCM_LIB.SCM(SCH_1):PAGE13
   N23 LED_POSTCODE_1 @SCM_LIB.SCM(SCH_1):LED_POSTCODE_1   I363 @SCM_LIB.SCM(SCH_1):PAGE13
   N25 LED_POSTCODE_2 @SCM_LIB.SCM(SCH_1):LED_POSTCODE_2   I363 @SCM_LIB.SCM(SCH_1):PAGE13
   N24 LED_POSTCODE_3 @SCM_LIB.SCM(SCH_1):LED_POSTCODE_3   I363 @SCM_LIB.SCM(SCH_1):PAGE13
   P26 LED_POSTCODE_4 @SCM_LIB.SCM(SCH_1):LED_POSTCODE_4   I363 @SCM_LIB.SCM(SCH_1):PAGE13
   M23 LED_POSTCODE_5 @SCM_LIB.SCM(SCH_1):LED_POSTCODE_5   I363 @SCM_LIB.SCM(SCH_1):PAGE13
   N26 LED_POSTCODE_6 @SCM_LIB.SCM(SCH_1):LED_POSTCODE_6   I363 @SCM_LIB.SCM(SCH_1):PAGE13
   M26 LED_POSTCODE_7 @SCM_LIB.SCM(SCH_1):LED_POSTCODE_7   I363 @SCM_LIB.SCM(SCH_1):PAGE13
   F15 FM_JTAG_TCK_MUX_BMC_SEL_R1 @SCM_LIB.SCM(SCH_1):FM_JTAG_TCK_MUX_BMC_SEL_R1   I363 @SCM_LIB.SCM(SCH_1):PAGE13
   C15 FM_DBP_CPU_PREQ_GF_N @SCM_LIB.SCM(SCH_1):FM_DBP_CPU_PREQ_GF_N   I363 @SCM_LIB.SCM(SCH_1):PAGE13
  AA13 SPI_BMC_BOOT_CS1_R1_N @SCM_LIB.SCM(SCH_1):SPI_BMC_BOOT_CS1_R1_N   I363 @SCM_LIB.SCM(SCH_1):PAGE13
  AC13 TP_BMC_SPICS2_N @SCM_LIB.SCM(SCH_1):TP_BMC_SPICS2_N   I363 @SCM_LIB.SCM(SCH_1):PAGE13
  AB15 FM_SLPS3_GF_R1_N @SCM_LIB.SCM(SCH_1):FM_SLPS3_GF_R1_N   I363 @SCM_LIB.SCM(SCH_1):PAGE13
  AF14 RST_RSMRST_R_N @SCM_LIB.SCM(SCH_1):RST_RSMRST_R_N   I363 @SCM_LIB.SCM(SCH_1):PAGE13
  AD14 BMC_ID_BEEP_SEL_R1 @SCM_LIB.SCM(SCH_1):BMC_ID_BEEP_SEL_R1   I363 @SCM_LIB.SCM(SCH_1):PAGE13
  AC15 FM_BMC_ONCTL_R_N @SCM_LIB.SCM(SCH_1):FM_BMC_ONCTL_R_N   I363 @SCM_LIB.SCM(SCH_1):PAGE13
  AE15 BATTERY_DETECT @SCM_LIB.SCM(SCH_1):BATTERY_DETECT   I363 @SCM_LIB.SCM(SCH_1):PAGE13
  AE14 FM_BMC_READY_R_PLD_N @SCM_LIB.SCM(SCH_1):FM_BMC_READY_R_PLD_N   I363 @SCM_LIB.SCM(SCH_1):PAGE13
  AD15 FM_BMC_SUSACK_R1_N @SCM_LIB.SCM(SCH_1):FM_BMC_SUSACK_R1_N   I363 @SCM_LIB.SCM(SCH_1):PAGE13
  AF15 IRQ_TPM_SPI_N @SCM_LIB.SCM(SCH_1):IRQ_TPM_SPI_N   I363 @SCM_LIB.SCM(SCH_1):PAGE13
  AF13 SPI_BMC_CLK_R @SCM_LIB.SCM(SCH_1):SPI_BMC_CLK_R   I363 @SCM_LIB.SCM(SCH_1):PAGE13
  AC14 SPI_BMC_MOSI_IO0_R @SCM_LIB.SCM(SCH_1):SPI_BMC_MOSI_IO0_R   I363 @SCM_LIB.SCM(SCH_1):PAGE13
  AB13 SPI_BMC_MISO_IO1_R @SCM_LIB.SCM(SCH_1):SPI_BMC_MISO_IO1_R   I363 @SCM_LIB.SCM(SCH_1):PAGE13
  AF12 SPI_BMC_IO3_R @SCM_LIB.SCM(SCH_1):SPI_BMC_IO3_R   I363 @SCM_LIB.SCM(SCH_1):PAGE13
  AE12 SPI_BMC_IO2_R @SCM_LIB.SCM(SCH_1):SPI_BMC_IO2_R   I363 @SCM_LIB.SCM(SCH_1):PAGE13
  AC12 PU_BMC_FWSPIABR_N_R @SCM_LIB.SCM(SCH_1):PU_BMC_FWSPIABR_N_R   I363 @SCM_LIB.SCM(SCH_1):PAGE13
  AB12 PU_FWSPIWP_N_R @SCM_LIB.SCM(SCH_1):PU_FWSPIWP_N_R   I363 @SCM_LIB.SCM(SCH_1):PAGE13
  AB11 SPI_BMC_TPM_CLK_R1 @SCM_LIB.SCM(SCH_1):SPI_BMC_TPM_CLK_R1   I363 @SCM_LIB.SCM(SCH_1):PAGE13
  AC11 SPI_BMC_TPM_MOSI_R1 @SCM_LIB.SCM(SCH_1):SPI_BMC_TPM_MOSI_R1   I363 @SCM_LIB.SCM(SCH_1):PAGE13
  AA11 SPI_BMC_TPM_MISO_R1 @SCM_LIB.SCM(SCH_1):SPI_BMC_TPM_MISO_R1   I363 @SCM_LIB.SCM(SCH_1):PAGE13
  AD11 FM_DEBUG_PORT_PRSNT_R1_N @SCM_LIB.SCM(SCH_1):FM_DEBUG_PORT_PRSNT_R1_N   I363 @SCM_LIB.SCM(SCH_1):PAGE13
  AF10 CLK_GEN2_BMC_RC_OE_N @SCM_LIB.SCM(SCH_1):CLK_GEN2_BMC_RC_OE_N   I363 @SCM_LIB.SCM(SCH_1):PAGE13
  AD13 TP_BMC_SPICS0_N @SCM_LIB.SCM(SCH_1):TP_BMC_SPICS0_N   I363 @SCM_LIB.SCM(SCH_1):PAGE13
  AC10 SPI_BMC_TPM_CS2_R1_N @SCM_LIB.SCM(SCH_1):SPI_BMC_TPM_CS2_R1_N   I363 @SCM_LIB.SCM(SCH_1):PAGE13
  AD10 PU_SPI1ABR @SCM_LIB.SCM(SCH_1):PU_SPI1ABR   I363 @SCM_LIB.SCM(SCH_1):PAGE13
  AE10 PU_SPI1WP_N @SCM_LIB.SCM(SCH_1):PU_SPI1WP_N   I363 @SCM_LIB.SCM(SCH_1):PAGE13
   AF8 SPI_BMC_BIOS_ROM_CLK @SCM_LIB.SCM(SCH_1):SPI_BMC_BIOS_ROM_CLK   I363 @SCM_LIB.SCM(SCH_1):PAGE13
   AB9 SPI_BMC_BIOS_ROM_MOSI @SCM_LIB.SCM(SCH_1):SPI_BMC_BIOS_ROM_MOSI   I363 @SCM_LIB.SCM(SCH_1):PAGE13
   AD9 SPI_BMC_BIOS_ROM_MISO @SCM_LIB.SCM(SCH_1):SPI_BMC_BIOS_ROM_MISO   I363 @SCM_LIB.SCM(SCH_1):PAGE13
   AF9 SPI_BMC_BIOS_ROM_IO2 @SCM_LIB.SCM(SCH_1):SPI_BMC_BIOS_ROM_IO2   I363 @SCM_LIB.SCM(SCH_1):PAGE13
  AB10 SPI_BMC_BIOS_ROM_IO3 @SCM_LIB.SCM(SCH_1):SPI_BMC_BIOS_ROM_IO3   I363 @SCM_LIB.SCM(SCH_1):PAGE13
   AE8 SPI_BMC_BIOS_CS0_R1_N @SCM_LIB.SCM(SCH_1):SPI_BMC_BIOS_CS0_R1_N   I363 @SCM_LIB.SCM(SCH_1):PAGE13
   AA9 PWRGD_DSW_PWROK_R1 @SCM_LIB.SCM(SCH_1):PWRGD_DSW_PWROK_R1   I363 @SCM_LIB.SCM(SCH_1):PAGE13
   AC9 IRQ_SMI_ACTIVE_BMC_N @SCM_LIB.SCM(SCH_1):IRQ_SMI_ACTIVE_BMC_N   I363 @SCM_LIB.SCM(SCH_1):PAGE13
   J26 FM_ME_BT_DONE @SCM_LIB.SCM(SCH_1):FM_ME_BT_DONE   I363 @SCM_LIB.SCM(SCH_1):PAGE13
   K23 VOL_SEN_ALERT_R @SCM_LIB.SCM(SCH_1):VOL_SEN_ALERT_R   I363 @SCM_LIB.SCM(SCH_1):PAGE13
   H26 SMB_BMC_ALERT3_R_N @SCM_LIB.SCM(SCH_1):SMB_BMC_ALERT3_R_N   I363 @SCM_LIB.SCM(SCH_1):PAGE13
   J25 SMB_BMC_ALERT4_R_N @SCM_LIB.SCM(SCH_1):SMB_BMC_ALERT4_R_N   I363 @SCM_LIB.SCM(SCH_1):PAGE13
   J23 FM_BMC_MUX_CS_SPI_SEL_0 @SCM_LIB.SCM(SCH_1):FM_BMC_MUX_CS_SPI_SEL_0   I363 @SCM_LIB.SCM(SCH_1):PAGE13
   G26 FM_ID_LED @SCM_LIB.SCM(SCH_1):FM_ID_LED   I363 @SCM_LIB.SCM(SCH_1):PAGE13
   H25 FM_ESPI_PLD_R1_EN @SCM_LIB.SCM(SCH_1):FM_ESPI_PLD_R1_EN   I363 @SCM_LIB.SCM(SCH_1):PAGE13
   J24 IRQ_BMC_CPU_NMI @SCM_LIB.SCM(SCH_1):IRQ_BMC_CPU_NMI   I363 @SCM_LIB.SCM(SCH_1):PAGE13
  AF11 RST_BMC_SELF_HW_R1 @SCM_LIB.SCM(SCH_1):RST_BMC_SELF_HW_R1   I363 @SCM_LIB.SCM(SCH_1):PAGE13
  AD12 RST_WDTRST_PLD_R1_N @SCM_LIB.SCM(SCH_1):RST_WDTRST_PLD_R1_N   I363 @SCM_LIB.SCM(SCH_1):PAGE13
  AE11 FM_FLASH_LATCH_N_R1 @SCM_LIB.SCM(SCH_1):FM_FLASH_LATCH_N_R1   I363 @SCM_LIB.SCM(SCH_1):PAGE13
  AA12 BMC_EMMC_RST_R_N @SCM_LIB.SCM(SCH_1):BMC_EMMC_RST_R_N   I363 @SCM_LIB.SCM(SCH_1):PAGE13
    C8 UART_BMC_5_TXD @SCM_LIB.SCM(SCH_1):UART_BMC_5_TXD   I363 @SCM_LIB.SCM(SCH_1):PAGE13
    D8 UART_BMC_5_RXD @SCM_LIB.SCM(SCH_1):UART_BMC_5_RXD   I363 @SCM_LIB.SCM(SCH_1):PAGE13
   G23 FM_JTAG_SEL @SCM_LIB.SCM(SCH_1):FM_JTAG_SEL   I363 @SCM_LIB.SCM(SCH_1):PAGE13
   G24 IRQ_SGPIO_BMC_N @SCM_LIB.SCM(SCH_1):IRQ_SGPIO_BMC_N   I363 @SCM_LIB.SCM(SCH_1):PAGE13
   F23 GPU_FPGA_RST_N @SCM_LIB.SCM(SCH_1):GPU_FPGA_RST_N   I363 @SCM_LIB.SCM(SCH_1):PAGE13
   F26 CLK_BUF1_GPU_FPGA_OE_R_N @SCM_LIB.SCM(SCH_1):CLK_BUF1_GPU_FPGA_OE_R_N   I363 @SCM_LIB.SCM(SCH_1):PAGE13
   F25 FM_BIC_DEBUG_SW_N_R @SCM_LIB.SCM(SCH_1):FM_BIC_DEBUG_SW_N_R   I363 @SCM_LIB.SCM(SCH_1):PAGE13
   E26 FM_BMC_CRASHLOG_TRIG_R1_N @SCM_LIB.SCM(SCH_1):FM_BMC_CRASHLOG_TRIG_R1_N   I363 @SCM_LIB.SCM(SCH_1):PAGE13
   C25 RMII_OCP_RCLKI_R_ISO @SCM_LIB.SCM(SCH_1):RMII_OCP_RCLKI_R_ISO   I363 @SCM_LIB.SCM(SCH_1):PAGE13
   C26 FM_PLT_BMC_THERMTRIP_N_R @SCM_LIB.SCM(SCH_1):FM_PLT_BMC_THERMTRIP_N_R   I363 @SCM_LIB.SCM(SCH_1):PAGE13
   C24 RMII_RXD0 @SCM_LIB.SCM(SCH_1):RMII_RXD0   I363 @SCM_LIB.SCM(SCH_1):PAGE13
   B26 RMII_RXD1 @SCM_LIB.SCM(SCH_1):RMII_RXD1   I363 @SCM_LIB.SCM(SCH_1):PAGE13
   B25 RMII_CSRDV @SCM_LIB.SCM(SCH_1):RMII_CSRDV   I363 @SCM_LIB.SCM(SCH_1):PAGE13
   B24 RMII_RXER @SCM_LIB.SCM(SCH_1):RMII_RXER   I363 @SCM_LIB.SCM(SCH_1):PAGE13
   F24 IRQ_SML0_ALERT_R_N @SCM_LIB.SCM(SCH_1):IRQ_SML0_ALERT_R_N   I363 @SCM_LIB.SCM(SCH_1):PAGE13
   E23 RMII_TXEN_R @SCM_LIB.SCM(SCH_1):RMII_TXEN_R   I363 @SCM_LIB.SCM(SCH_1):PAGE13
   E24 RMII_TXD0_R @SCM_LIB.SCM(SCH_1):RMII_TXD0_R   I363 @SCM_LIB.SCM(SCH_1):PAGE13
   E25 RMII_TXD1_R @SCM_LIB.SCM(SCH_1):RMII_TXD1_R   I363 @SCM_LIB.SCM(SCH_1):PAGE13
   D26 PD_BIOS_MUX_EN_R_N @SCM_LIB.SCM(SCH_1):PD_BIOS_MUX_EN_R_N   I363 @SCM_LIB.SCM(SCH_1):PAGE13
   D24 FM_BIOS_DEBUG_EN_R_N @SCM_LIB.SCM(SCH_1):FM_BIOS_DEBUG_EN_R_N   I363 @SCM_LIB.SCM(SCH_1):PAGE13
   H24 RST_PLTRST_R_N @SCM_LIB.SCM(SCH_1):RST_PLTRST_R_N   I363 @SCM_LIB.SCM(SCH_1):PAGE13
   J22 FM_CPU_RMCA_CATERR_LVT3_R_N @SCM_LIB.SCM(SCH_1):FM_CPU_RMCA_CATERR_LVT3_R_N   I363 @SCM_LIB.SCM(SCH_1):PAGE13
   H22 FM_BMC_CPU_FBRK_OUT_N @SCM_LIB.SCM(SCH_1):FM_BMC_CPU_FBRK_OUT_N   I363 @SCM_LIB.SCM(SCH_1):PAGE13
   H23 RST_SGPIO_RESET_BMC_N @SCM_LIB.SCM(SCH_1):RST_SGPIO_RESET_BMC_N   I363 @SCM_LIB.SCM(SCH_1):PAGE13
   G22 RST_ROT_CPU_R1_N @SCM_LIB.SCM(SCH_1):RST_ROT_CPU_R1_N   I363 @SCM_LIB.SCM(SCH_1):PAGE13
   F22 H_CPU_CATERR_LVC2_R2_N @SCM_LIB.SCM(SCH_1):H_CPU_CATERR_LVC2_R2_N   I363 @SCM_LIB.SCM(SCH_1):PAGE13
   A10 PD_CLK_125M_PHY_BMC_RGMII @SCM_LIB.SCM(SCH_1):PD_CLK_125M_PHY_BMC_RGMII   I363 @SCM_LIB.SCM(SCH_1):PAGE13
   R23 IRQ_BMC_PCH_NMI_N @SCM_LIB.SCM(SCH_1):IRQ_BMC_PCH_NMI_N   I363 @SCM_LIB.SCM(SCH_1):PAGE13
   T25 BMC_MONITER @SCM_LIB.SCM(SCH_1):BMC_MONITER   I363 @SCM_LIB.SCM(SCH_1):PAGE13
   P24 H_CPU1_PROCHOT_LVC1_N @SCM_LIB.SCM(SCH_1):H_CPU1_PROCHOT_LVC1_N   I363 @SCM_LIB.SCM(SCH_1):PAGE13
   P23 RST_PCA9548_SENSOR_R_N @SCM_LIB.SCM(SCH_1):RST_PCA9548_SENSOR_R_N   I363 @SCM_LIB.SCM(SCH_1):PAGE13
   T24 BMC_CPLD_GPIO_2_R1 @SCM_LIB.SCM(SCH_1):BMC_CPLD_GPIO_2_R1   I363 @SCM_LIB.SCM(SCH_1):PAGE13
   R26 FM_BMC_DEBUG_SW_N @SCM_LIB.SCM(SCH_1):FM_BMC_DEBUG_SW_N   I363 @SCM_LIB.SCM(SCH_1):PAGE13
   B16 FM_THROTTLE_N @SCM_LIB.SCM(SCH_1):FM_THROTTLE_N   I363 @SCM_LIB.SCM(SCH_1):PAGE13
   E16 FLASH_WP_STATUS_R1 @SCM_LIB.SCM(SCH_1):FLASH_WP_STATUS_R1   I363 @SCM_LIB.SCM(SCH_1):PAGE13
   A15 IRQ_PCH_SCI_WHEA_R_N @SCM_LIB.SCM(SCH_1):IRQ_PCH_SCI_WHEA_R_N   I363 @SCM_LIB.SCM(SCH_1):PAGE13
    B3     NC     NC   I149 @SCM_LIB.SCM(SCH_1):PAGE14
    A2     NC     NC   I149 @SCM_LIB.SCM(SCH_1):PAGE14
    B2     NC     NC   I149 @SCM_LIB.SCM(SCH_1):PAGE14
    B1     NC     NC   I149 @SCM_LIB.SCM(SCH_1):PAGE14
    C4     NC     NC   I149 @SCM_LIB.SCM(SCH_1):PAGE14
    E5     NC     NC   I149 @SCM_LIB.SCM(SCH_1):PAGE14
    C6 AC_PWR_BMC_BTN_R_N @SCM_LIB.SCM(SCH_1):AC_PWR_BMC_BTN_R_N   I149 @SCM_LIB.SCM(SCH_1):PAGE14
    D6     NC     NC   I149 @SCM_LIB.SCM(SCH_1):PAGE14
    D5     NC     NC   I149 @SCM_LIB.SCM(SCH_1):PAGE14
    A3     NC     NC   I149 @SCM_LIB.SCM(SCH_1):PAGE14
    C5     NC     NC   I149 @SCM_LIB.SCM(SCH_1):PAGE14
    E6     NC     NC   I149 @SCM_LIB.SCM(SCH_1):PAGE14
    D2     NC     NC   I149 @SCM_LIB.SCM(SCH_1):PAGE14
    E3     NC     NC   I149 @SCM_LIB.SCM(SCH_1):PAGE14
    D1     NC     NC   I149 @SCM_LIB.SCM(SCH_1):PAGE14
    F4     NC     NC   I149 @SCM_LIB.SCM(SCH_1):PAGE14
    E2     NC     NC   I149 @SCM_LIB.SCM(SCH_1):PAGE14
    E1     NC     NC   I149 @SCM_LIB.SCM(SCH_1):PAGE14
    D4     NC     NC   I149 @SCM_LIB.SCM(SCH_1):PAGE14
    C2     NC     NC   I149 @SCM_LIB.SCM(SCH_1):PAGE14
    C1     NC     NC   I149 @SCM_LIB.SCM(SCH_1):PAGE14
    D3 FM_BOARD_BMC_REV_ID0 @SCM_LIB.SCM(SCH_1):FM_BOARD_BMC_REV_ID0   I149 @SCM_LIB.SCM(SCH_1):PAGE14
    E4 FM_BOARD_BMC_REV_ID1 @SCM_LIB.SCM(SCH_1):FM_BOARD_BMC_REV_ID1   I149 @SCM_LIB.SCM(SCH_1):PAGE14
    F5 FM_BOARD_BMC_REV_ID2 @SCM_LIB.SCM(SCH_1):FM_BOARD_BMC_REV_ID2   I149 @SCM_LIB.SCM(SCH_1):PAGE14
   AB4     NC     NC   I149 @SCM_LIB.SCM(SCH_1):PAGE14
   AA4     NC     NC   I149 @SCM_LIB.SCM(SCH_1):PAGE14
   AC4     NC     NC   I149 @SCM_LIB.SCM(SCH_1):PAGE14
   AA5     NC     NC   I149 @SCM_LIB.SCM(SCH_1):PAGE14
    Y5     NC     NC   I149 @SCM_LIB.SCM(SCH_1):PAGE14
   AB5     NC     NC   I149 @SCM_LIB.SCM(SCH_1):PAGE14
   AC5     NC     NC   I149 @SCM_LIB.SCM(SCH_1):PAGE14
   AB6     NC     NC   I149 @SCM_LIB.SCM(SCH_1):PAGE14
    Y1     NC     NC   I149 @SCM_LIB.SCM(SCH_1):PAGE14
    Y2     NC     NC   I149 @SCM_LIB.SCM(SCH_1):PAGE14
    Y3     NC     NC   I149 @SCM_LIB.SCM(SCH_1):PAGE14
    Y4     NC     NC   I149 @SCM_LIB.SCM(SCH_1):PAGE14
  AF23 I3C1_SCL_R @SCM_LIB.SCM(SCH_1):I3C1_SCL_R   I149 @SCM_LIB.SCM(SCH_1):PAGE14
  AE24 I3C1_SDA_R @SCM_LIB.SCM(SCH_1):I3C1_SDA_R   I149 @SCM_LIB.SCM(SCH_1):PAGE14
  AF22 I3C2_SCL_R @SCM_LIB.SCM(SCH_1):I3C2_SCL_R   I149 @SCM_LIB.SCM(SCH_1):PAGE14
  AE22 I3C2_SDA_R @SCM_LIB.SCM(SCH_1):I3C2_SDA_R   I149 @SCM_LIB.SCM(SCH_1):PAGE14
  AF25 I3C3_SCL_R @SCM_LIB.SCM(SCH_1):I3C3_SCL_R   I149 @SCM_LIB.SCM(SCH_1):PAGE14
  AE26 I3C3_SDA_R @SCM_LIB.SCM(SCH_1):I3C3_SDA_R   I149 @SCM_LIB.SCM(SCH_1):PAGE14
  AE25 I3C4_SCL_R @SCM_LIB.SCM(SCH_1):I3C4_SCL_R   I149 @SCM_LIB.SCM(SCH_1):PAGE14
  AF24 I3C4_SDA_R @SCM_LIB.SCM(SCH_1):I3C4_SDA_R   I149 @SCM_LIB.SCM(SCH_1):PAGE14
  AD21 V_DACB_R @SCM_LIB.SCM(SCH_1):V_DACB_R   I350 @SCM_LIB.SCM(SCH_1):PAGE15
  AE21 V_DACG_R @SCM_LIB.SCM(SCH_1):V_DACG_R   I350 @SCM_LIB.SCM(SCH_1):PAGE15
  AF21 V_DACR_R @SCM_LIB.SCM(SCH_1):V_DACR_R   I350 @SCM_LIB.SCM(SCH_1):PAGE15
   J10 P3V3_BMC_USB2AV33 @SCM_LIB.SCM(SCH_1):P3V3_BMC_USB2AV33   I350 @SCM_LIB.SCM(SCH_1):PAGE15
    B4 USB_HOST_BMC_A_R_DN @SCM_LIB.SCM(SCH_1):USB_HOST_BMC_A_R_DN   I350 @SCM_LIB.SCM(SCH_1):PAGE15
    A4 USB_HOST_BMC_A_R_DP @SCM_LIB.SCM(SCH_1):USB_HOST_BMC_A_R_DP   I350 @SCM_LIB.SCM(SCH_1):PAGE15
    B6 USB_HOST_BMC_B_R_DN @SCM_LIB.SCM(SCH_1):USB_HOST_BMC_B_R_DN   I350 @SCM_LIB.SCM(SCH_1):PAGE15
    A6 USB_HOST_BMC_B_R_DP @SCM_LIB.SCM(SCH_1):USB_HOST_BMC_B_R_DP   I350 @SCM_LIB.SCM(SCH_1):PAGE15
  AD20 P12V_SENSOR @SCM_LIB.SCM(SCH_1):P12V_SENSOR   I350 @SCM_LIB.SCM(SCH_1):PAGE15
  AC18 P5V_SENSOR @SCM_LIB.SCM(SCH_1):P5V_SENSOR   I350 @SCM_LIB.SCM(SCH_1):PAGE15
  AE19 P3V3_SENSOR @SCM_LIB.SCM(SCH_1):P3V3_SENSOR   I350 @SCM_LIB.SCM(SCH_1):PAGE15
  AD19 P2V5_SENSOR @SCM_LIB.SCM(SCH_1):P2V5_SENSOR   I350 @SCM_LIB.SCM(SCH_1):PAGE15
  AC19 P1V8_SENSOR @SCM_LIB.SCM(SCH_1):P1V8_SENSOR   I350 @SCM_LIB.SCM(SCH_1):PAGE15
  AB19 PGPPA_BMC_AUX_SENSOR @SCM_LIB.SCM(SCH_1):PGPPA_BMC_AUX_SENSOR   I350 @SCM_LIB.SCM(SCH_1):PAGE15
  AB18 P1V2_SENSOR @SCM_LIB.SCM(SCH_1):P1V2_SENSOR   I350 @SCM_LIB.SCM(SCH_1):PAGE15
  AE18 P3V_BAT_SENSOR @SCM_LIB.SCM(SCH_1):P3V_BAT_SENSOR   I350 @SCM_LIB.SCM(SCH_1):PAGE15
  AB16 SMB_BMC_ALERT9_R_N @SCM_LIB.SCM(SCH_1):SMB_BMC_ALERT9_R_N   I350 @SCM_LIB.SCM(SCH_1):PAGE15
  AA17 SMB_BMC_ALERT10_R_N @SCM_LIB.SCM(SCH_1):SMB_BMC_ALERT10_R_N   I350 @SCM_LIB.SCM(SCH_1):PAGE15
  AB17 P1V0_SENSOR @SCM_LIB.SCM(SCH_1):P1V0_SENSOR   I350 @SCM_LIB.SCM(SCH_1):PAGE15
  AE16 SMB_BMC_ALERT12_N @SCM_LIB.SCM(SCH_1):SMB_BMC_ALERT12_N   I350 @SCM_LIB.SCM(SCH_1):PAGE15
  AC16 BSM_PRSNT_R_N @SCM_LIB.SCM(SCH_1):BSM_PRSNT_R_N   I350 @SCM_LIB.SCM(SCH_1):PAGE15
  AA16 FM_BMC_EN_DET_R @SCM_LIB.SCM(SCH_1):FM_BMC_EN_DET_R   I350 @SCM_LIB.SCM(SCH_1):PAGE15
  AD16 FM_PCHHOT_R_N @SCM_LIB.SCM(SCH_1):FM_PCHHOT_R_N   I350 @SCM_LIB.SCM(SCH_1):PAGE15
  AC17 SMB_BMC_ALERT16_N @SCM_LIB.SCM(SCH_1):SMB_BMC_ALERT16_N   I350 @SCM_LIB.SCM(SCH_1):PAGE15
   C10 PD_SP_ENTEST @SCM_LIB.SCM(SCH_1):PD_SP_ENTEST   I350 @SCM_LIB.SCM(SCH_1):PAGE15
   E10 RST_BMC_SRST_N @SCM_LIB.SCM(SCH_1):RST_BMC_SRST_N   I350 @SCM_LIB.SCM(SCH_1):PAGE15
   B10 RST_EXTRST_N @SCM_LIB.SCM(SCH_1):RST_EXTRST_N   I350 @SCM_LIB.SCM(SCH_1):PAGE15
   D10 BMC_CLK_25M @SCM_LIB.SCM(SCH_1):BMC_CLK_25M   I350 @SCM_LIB.SCM(SCH_1):PAGE15
    B7 RST_SPI_FLASH_N @SCM_LIB.SCM(SCH_1):RST_SPI_FLASH_N   I350 @SCM_LIB.SCM(SCH_1):PAGE15
   F11 JTAG_SCM_NTRST @SCM_LIB.SCM(SCH_1):JTAG_SCM_NTRST   I350 @SCM_LIB.SCM(SCH_1):PAGE15
    B9 JTAG_SCM_TCK @SCM_LIB.SCM(SCH_1):JTAG_SCM_TCK   I350 @SCM_LIB.SCM(SCH_1):PAGE15
    D9 JTAG_SCM_TDI @SCM_LIB.SCM(SCH_1):JTAG_SCM_TDI   I350 @SCM_LIB.SCM(SCH_1):PAGE15
    C9 JTAG_SCM_TDO @SCM_LIB.SCM(SCH_1):JTAG_SCM_TDO   I350 @SCM_LIB.SCM(SCH_1):PAGE15
    A9 JTAG_SCM_TMS @SCM_LIB.SCM(SCH_1):JTAG_SCM_TMS   I350 @SCM_LIB.SCM(SCH_1):PAGE15
   B14 V_VGAHS_R @SCM_LIB.SCM(SCH_1):V_VGAHS_R   I350 @SCM_LIB.SCM(SCH_1):PAGE15
   C14 V_VGAVS_R @SCM_LIB.SCM(SCH_1):V_VGAVS_R   I350 @SCM_LIB.SCM(SCH_1):PAGE15
    B8 V_BMC_DDC_SCL @SCM_LIB.SCM(SCH_1):V_BMC_DDC_SCL   I350 @SCM_LIB.SCM(SCH_1):PAGE15
    A8 V_BMC_DDC_SDA @SCM_LIB.SCM(SCH_1):V_BMC_DDC_SDA   I350 @SCM_LIB.SCM(SCH_1):PAGE15
  AD26 FM_PMBUS_ALERT_EN @SCM_LIB.SCM(SCH_1):FM_PMBUS_ALERT_EN   I350 @SCM_LIB.SCM(SCH_1):PAGE15
  AD22     NC     NC   I350 @SCM_LIB.SCM(SCH_1):PAGE15
  AD23 FM_PCIE_M2_SSD0_PRSNT_N @SCM_LIB.SCM(SCH_1):FM_PCIE_M2_SSD0_PRSNT_N   I350 @SCM_LIB.SCM(SCH_1):PAGE15
  AD24 FM_JTAG_BMC_MUX_SEL_R1 @SCM_LIB.SCM(SCH_1):FM_JTAG_BMC_MUX_SEL_R1   I350 @SCM_LIB.SCM(SCH_1):PAGE15
  AD25 FM_ADR_TRIGGER_N @SCM_LIB.SCM(SCH_1):FM_ADR_TRIGGER_N   I350 @SCM_LIB.SCM(SCH_1):PAGE15
  AC22 FM_TPM_PRSNT_0_N @SCM_LIB.SCM(SCH_1):FM_TPM_PRSNT_0_N   I350 @SCM_LIB.SCM(SCH_1):PAGE15
  AC24 FM_ADR_COMPLETE @SCM_LIB.SCM(SCH_1):FM_ADR_COMPLETE   I350 @SCM_LIB.SCM(SCH_1):PAGE15
  AC23 FM_SPD_REMOTE_EN_R @SCM_LIB.SCM(SCH_1):FM_SPD_REMOTE_EN_R   I350 @SCM_LIB.SCM(SCH_1):PAGE15
  AA25 IRQ_PCH_TPM_SPI_N @SCM_LIB.SCM(SCH_1):IRQ_PCH_TPM_SPI_N   I350 @SCM_LIB.SCM(SCH_1):PAGE15
  AB25 USB_OC0_REAR_R_N @SCM_LIB.SCM(SCH_1):USB_OC0_REAR_R_N   I350 @SCM_LIB.SCM(SCH_1):PAGE15
   Y24 GPU_NVS_PWR_BRAKE_R_N @SCM_LIB.SCM(SCH_1):GPU_NVS_PWR_BRAKE_R_N   I350 @SCM_LIB.SCM(SCH_1):PAGE15
  AB26 GPU_WP_HW_CTRL_R_N @SCM_LIB.SCM(SCH_1):GPU_WP_HW_CTRL_R_N   I350 @SCM_LIB.SCM(SCH_1):PAGE15
   Y26 FM_HDD_LED_N @SCM_LIB.SCM(SCH_1):FM_HDD_LED_N   I350 @SCM_LIB.SCM(SCH_1):PAGE15
  AC26 FM_P12V_HSC_ENABLE_R1 @SCM_LIB.SCM(SCH_1):FM_P12V_HSC_ENABLE_R1   I350 @SCM_LIB.SCM(SCH_1):PAGE15
   Y25 FM_PCH_BEEP_LED @SCM_LIB.SCM(SCH_1):FM_PCH_BEEP_LED   I350 @SCM_LIB.SCM(SCH_1):PAGE15
  AA26 FM_SOL_UART_CH_SEL_R1 @SCM_LIB.SCM(SCH_1):FM_SOL_UART_CH_SEL_R1   I350 @SCM_LIB.SCM(SCH_1):PAGE15
   V25 IRQ_OC_DETECT_N @SCM_LIB.SCM(SCH_1):IRQ_OC_DETECT_N   I350 @SCM_LIB.SCM(SCH_1):PAGE15
   U24 IRQ_UV_DETECT_N @SCM_LIB.SCM(SCH_1):IRQ_UV_DETECT_N   I350 @SCM_LIB.SCM(SCH_1):PAGE15
   V24 IRQ_OC_DETECT_EN_N @SCM_LIB.SCM(SCH_1):IRQ_OC_DETECT_EN_N   I350 @SCM_LIB.SCM(SCH_1):PAGE15
   V26 IRQ_CPU0_VRHOT_N @SCM_LIB.SCM(SCH_1):IRQ_CPU0_VRHOT_N   I350 @SCM_LIB.SCM(SCH_1):PAGE15
   U25 IRQ_CPU1_VRHOT_N @SCM_LIB.SCM(SCH_1):IRQ_CPU1_VRHOT_N   I350 @SCM_LIB.SCM(SCH_1):PAGE15
   T23 PWRGD_PCH_PWROK @SCM_LIB.SCM(SCH_1):PWRGD_PCH_PWROK   I350 @SCM_LIB.SCM(SCH_1):PAGE15
   W26 PWRGD_CPUPWRGD_LVC1 @SCM_LIB.SCM(SCH_1):PWRGD_CPUPWRGD_LVC1   I350 @SCM_LIB.SCM(SCH_1):PAGE15
   U26 FM_BIOS_POST_CMPLT_BMC_N @SCM_LIB.SCM(SCH_1):FM_BIOS_POST_CMPLT_BMC_N   I350 @SCM_LIB.SCM(SCH_1):PAGE15
  AB22 FM_PWR_BTN @SCM_LIB.SCM(SCH_1):FM_PWR_BTN   I350 @SCM_LIB.SCM(SCH_1):PAGE15
   W24 SYS_BMC_PWRBTN_R1_N @SCM_LIB.SCM(SCH_1):SYS_BMC_PWRBTN_R1_N   I350 @SCM_LIB.SCM(SCH_1):PAGE15
  AA23 ID_RST_BTN_BMC_R_N @SCM_LIB.SCM(SCH_1):ID_RST_BTN_BMC_R_N   I350 @SCM_LIB.SCM(SCH_1):PAGE15
  AA24 RST_BMC_RSTBTN_OUT_R_N @SCM_LIB.SCM(SCH_1):RST_BMC_RSTBTN_OUT_R_N   I350 @SCM_LIB.SCM(SCH_1):PAGE15
   W23 BMC_PWR_LED @SCM_LIB.SCM(SCH_1):BMC_PWR_LED   I350 @SCM_LIB.SCM(SCH_1):PAGE15
  AB23 H_CPU0_MEMTRIP_LVC1_N @SCM_LIB.SCM(SCH_1):H_CPU0_MEMTRIP_LVC1_N   I350 @SCM_LIB.SCM(SCH_1):PAGE15
  AB24 H_CPU1_MEMTRIP_LVC1_N @SCM_LIB.SCM(SCH_1):H_CPU1_MEMTRIP_LVC1_N   I350 @SCM_LIB.SCM(SCH_1):PAGE15
   Y23 BMC_HEARTBEAT_N @SCM_LIB.SCM(SCH_1):BMC_HEARTBEAT_N   I350 @SCM_LIB.SCM(SCH_1):PAGE15
    D7 FM_BMC_SSPRST_N @SCM_LIB.SCM(SCH_1):FM_BMC_SSPRST_N   I350 @SCM_LIB.SCM(SCH_1):PAGE15
   K10 P1V8_BMC_USB2AV18 @SCM_LIB.SCM(SCH_1):P1V8_BMC_USB2AV18   I350 @SCM_LIB.SCM(SCH_1):PAGE15
  AA18 PVCCIO_PECI_BMC @SCM_LIB.SCM(SCH_1):PVCCIO_PECI_BMC   I350 @SCM_LIB.SCM(SCH_1):PAGE15
  AF16 PECI_BMC_R @SCM_LIB.SCM(SCH_1):PECI_BMC_R   I350 @SCM_LIB.SCM(SCH_1):PAGE15
   C16 JTAG_1_BMC_TDO @SCM_LIB.SCM(SCH_1):JTAG_1_BMC_TDO   I350 @SCM_LIB.SCM(SCH_1):PAGE15
   D16 JTAG_1_BMC_TMS_R @SCM_LIB.SCM(SCH_1):JTAG_1_BMC_TMS_R   I350 @SCM_LIB.SCM(SCH_1):PAGE15
   E17 JTAG_1_BMC_TCK_R @SCM_LIB.SCM(SCH_1):JTAG_1_BMC_TCK_R   I350 @SCM_LIB.SCM(SCH_1):PAGE15
   D17 JTAG_1_BMC_TRST_R @SCM_LIB.SCM(SCH_1):JTAG_1_BMC_TRST_R   I350 @SCM_LIB.SCM(SCH_1):PAGE15
   A16 JTAG_1_BMC_TDI_R @SCM_LIB.SCM(SCH_1):JTAG_1_BMC_TDI_R   I350 @SCM_LIB.SCM(SCH_1):PAGE15
  AB21 FM_INTRUDER_R_N @SCM_LIB.SCM(SCH_1):FM_INTRUDER_R_N   I350 @SCM_LIB.SCM(SCH_1):PAGE15
  AF20 A_BMC_ADCREXT0 @SCM_LIB.SCM(SCH_1):A_BMC_ADCREXT0   I188 @SCM_LIB.SCM(SCH_1):PAGE16
  AB20 A_BMC_ADCVREFN0 @SCM_LIB.SCM(SCH_1):A_BMC_ADCVREFN0   I188 @SCM_LIB.SCM(SCH_1):PAGE16
  AC20 A_BMC_ADCVREFP0 @SCM_LIB.SCM(SCH_1):A_BMC_ADCVREFP0   I188 @SCM_LIB.SCM(SCH_1):PAGE16
   Y21 A_BMC_ADCAV33 @SCM_LIB.SCM(SCH_1):A_BMC_ADCAV33   I188 @SCM_LIB.SCM(SCH_1):PAGE16
   V21 P3V3_STBY_DACAV33 @SCM_LIB.SCM(SCH_1):P3V3_STBY_DACAV33   I188 @SCM_LIB.SCM(SCH_1):PAGE16
  AC21 A_BMC_DACREST @SCM_LIB.SCM(SCH_1):A_BMC_DACREST   I188 @SCM_LIB.SCM(SCH_1):PAGE16
    E7 P1V0_STBY_PLAVDD @SCM_LIB.SCM(SCH_1):P1V0_STBY_PLAVDD   I188 @SCM_LIB.SCM(SCH_1):PAGE16
   H14 P3V3_STBY_PLLAHVDD @SCM_LIB.SCM(SCH_1):P3V3_STBY_PLLAHVDD   I188 @SCM_LIB.SCM(SCH_1):PAGE16
  AD17 A_BMC_ADCVREFP1 @SCM_LIB.SCM(SCH_1):A_BMC_ADCVREFP1   I188 @SCM_LIB.SCM(SCH_1):PAGE16
  AD18 A_BMC_ADCVREFN1 @SCM_LIB.SCM(SCH_1):A_BMC_ADCVREFN1   I188 @SCM_LIB.SCM(SCH_1):PAGE16
  AF18 A_BMC_ADCREXT1 @SCM_LIB.SCM(SCH_1):A_BMC_ADCREXT1   I188 @SCM_LIB.SCM(SCH_1):PAGE16
    L9 P1V0_AUX @SCM_LIB.SCM(SCH_1):P1V0_AUX   I188 @SCM_LIB.SCM(SCH_1):PAGE16
   L10 P1V0_AUX @SCM_LIB.SCM(SCH_1):P1V0_AUX   I188 @SCM_LIB.SCM(SCH_1):PAGE16
    M8 P1V0_AUX @SCM_LIB.SCM(SCH_1):P1V0_AUX   I188 @SCM_LIB.SCM(SCH_1):PAGE16
    N5 P1V8_STBY_AVDDPLL @SCM_LIB.SCM(SCH_1):P1V8_STBY_AVDDPLL   I188 @SCM_LIB.SCM(SCH_1):PAGE16
    G6 P1V2_AUX @SCM_LIB.SCM(SCH_1):P1V2_AUX   I188 @SCM_LIB.SCM(SCH_1):PAGE16
    F7 P1V0_STBY_PLAVDD @SCM_LIB.SCM(SCH_1):P1V0_STBY_PLAVDD   I188 @SCM_LIB.SCM(SCH_1):PAGE16
   W21 P3V3_STBY_DACAV33 @SCM_LIB.SCM(SCH_1):P3V3_STBY_DACAV33   I188 @SCM_LIB.SCM(SCH_1):PAGE16
    E9 P1V0_STBY_PLAVDD @SCM_LIB.SCM(SCH_1):P1V0_STBY_PLAVDD   I188 @SCM_LIB.SCM(SCH_1):PAGE16
    F9 P1V0_STBY_PLAVDD @SCM_LIB.SCM(SCH_1):P1V0_STBY_PLAVDD   I188 @SCM_LIB.SCM(SCH_1):PAGE16
    T9 P1V0_STBY_PE_VCC10A @SCM_LIB.SCM(SCH_1):P1V0_STBY_PE_VCC10A   I188 @SCM_LIB.SCM(SCH_1):PAGE16
    V9 P1V8_STBY_PE_VCC18A @SCM_LIB.SCM(SCH_1):P1V8_STBY_PE_VCC18A   I188 @SCM_LIB.SCM(SCH_1):PAGE16
   T10 P1V0_STBY_RC_VCC10A @SCM_LIB.SCM(SCH_1):P1V0_STBY_RC_VCC10A   I188 @SCM_LIB.SCM(SCH_1):PAGE16
   V10 P1V8_STBY_RC_VCC18A @SCM_LIB.SCM(SCH_1):P1V8_STBY_RC_VCC18A   I188 @SCM_LIB.SCM(SCH_1):PAGE16
    V8 P1V8_STBY_DP_VCC18A @SCM_LIB.SCM(SCH_1):P1V8_STBY_DP_VCC18A   I188 @SCM_LIB.SCM(SCH_1):PAGE16
    T8 P1V0_STBY_DP_VCC10A @SCM_LIB.SCM(SCH_1):P1V0_STBY_DP_VCC10A   I188 @SCM_LIB.SCM(SCH_1):PAGE16
    H6 P1V2_AUX @SCM_LIB.SCM(SCH_1):P1V2_AUX   I188 @SCM_LIB.SCM(SCH_1):PAGE16
    J6 P1V2_AUX @SCM_LIB.SCM(SCH_1):P1V2_AUX   I188 @SCM_LIB.SCM(SCH_1):PAGE16
    K6 P1V2_AUX @SCM_LIB.SCM(SCH_1):P1V2_AUX   I188 @SCM_LIB.SCM(SCH_1):PAGE16
    L6 P1V2_AUX @SCM_LIB.SCM(SCH_1):P1V2_AUX   I188 @SCM_LIB.SCM(SCH_1):PAGE16
    P6 P1V2_AUX @SCM_LIB.SCM(SCH_1):P1V2_AUX   I188 @SCM_LIB.SCM(SCH_1):PAGE16
    R6 P1V2_AUX @SCM_LIB.SCM(SCH_1):P1V2_AUX   I188 @SCM_LIB.SCM(SCH_1):PAGE16
    T6 P1V2_AUX @SCM_LIB.SCM(SCH_1):P1V2_AUX   I188 @SCM_LIB.SCM(SCH_1):PAGE16
    M6 P1V2_STBY_MVDD_CK @SCM_LIB.SCM(SCH_1):P1V2_STBY_MVDD_CK   I188 @SCM_LIB.SCM(SCH_1):PAGE16
   K16 P1V2_AUX @SCM_LIB.SCM(SCH_1):P1V2_AUX   I188 @SCM_LIB.SCM(SCH_1):PAGE16
   K17 P1V2_AUX @SCM_LIB.SCM(SCH_1):P1V2_AUX   I188 @SCM_LIB.SCM(SCH_1):PAGE16
   K18 P1V2_AUX @SCM_LIB.SCM(SCH_1):P1V2_AUX   I188 @SCM_LIB.SCM(SCH_1):PAGE16
   K19 P1V2_AUX @SCM_LIB.SCM(SCH_1):P1V2_AUX   I188 @SCM_LIB.SCM(SCH_1):PAGE16
   L14 P1V2_AUX @SCM_LIB.SCM(SCH_1):P1V2_AUX   I188 @SCM_LIB.SCM(SCH_1):PAGE16
   M14 P1V2_AUX @SCM_LIB.SCM(SCH_1):P1V2_AUX   I188 @SCM_LIB.SCM(SCH_1):PAGE16
   N14 P1V2_AUX @SCM_LIB.SCM(SCH_1):P1V2_AUX   I188 @SCM_LIB.SCM(SCH_1):PAGE16
   P14 P1V2_AUX @SCM_LIB.SCM(SCH_1):P1V2_AUX   I188 @SCM_LIB.SCM(SCH_1):PAGE16
   R14 P1V2_AUX @SCM_LIB.SCM(SCH_1):P1V2_AUX   I188 @SCM_LIB.SCM(SCH_1):PAGE16
   T14 P1V2_AUX @SCM_LIB.SCM(SCH_1):P1V2_AUX   I188 @SCM_LIB.SCM(SCH_1):PAGE16
   L21 P1V2_AUX @SCM_LIB.SCM(SCH_1):P1V2_AUX   I188 @SCM_LIB.SCM(SCH_1):PAGE16
   M21 P1V2_AUX @SCM_LIB.SCM(SCH_1):P1V2_AUX   I188 @SCM_LIB.SCM(SCH_1):PAGE16
   N21 P1V2_AUX @SCM_LIB.SCM(SCH_1):P1V2_AUX   I188 @SCM_LIB.SCM(SCH_1):PAGE16
   P21 P1V2_AUX @SCM_LIB.SCM(SCH_1):P1V2_AUX   I188 @SCM_LIB.SCM(SCH_1):PAGE16
   R21 P1V2_AUX @SCM_LIB.SCM(SCH_1):P1V2_AUX   I188 @SCM_LIB.SCM(SCH_1):PAGE16
   T21 P1V2_AUX @SCM_LIB.SCM(SCH_1):P1V2_AUX   I188 @SCM_LIB.SCM(SCH_1):PAGE16
   U15 P1V2_AUX @SCM_LIB.SCM(SCH_1):P1V2_AUX   I188 @SCM_LIB.SCM(SCH_1):PAGE16
   U16 P1V2_AUX @SCM_LIB.SCM(SCH_1):P1V2_AUX   I188 @SCM_LIB.SCM(SCH_1):PAGE16
   U17 P1V2_AUX @SCM_LIB.SCM(SCH_1):P1V2_AUX   I188 @SCM_LIB.SCM(SCH_1):PAGE16
   U18 P1V2_AUX @SCM_LIB.SCM(SCH_1):P1V2_AUX   I188 @SCM_LIB.SCM(SCH_1):PAGE16
   L22 P3V3_P2V5_P1V8_RVDD @SCM_LIB.SCM(SCH_1):P3V3_P2V5_P1V8_RVDD   I188 @SCM_LIB.SCM(SCH_1):PAGE16
   M22 P3V3_P2V5_P1V8_RVDD @SCM_LIB.SCM(SCH_1):P3V3_P2V5_P1V8_RVDD   I188 @SCM_LIB.SCM(SCH_1):PAGE16
   J21 P3V3_P2V5_P1V8_RVDD @SCM_LIB.SCM(SCH_1):P3V3_P2V5_P1V8_RVDD   I188 @SCM_LIB.SCM(SCH_1):PAGE16
   K21 P3V3_P2V5_P1V8_RVDD @SCM_LIB.SCM(SCH_1):P3V3_P2V5_P1V8_RVDD   I188 @SCM_LIB.SCM(SCH_1):PAGE16
   G21 P3V3_P1V8_SD1VDD @SCM_LIB.SCM(SCH_1):P3V3_P1V8_SD1VDD   I188 @SCM_LIB.SCM(SCH_1):PAGE16
   H18 P3V3_P1V8_SD2VDD @SCM_LIB.SCM(SCH_1):P3V3_P1V8_SD2VDD   I188 @SCM_LIB.SCM(SCH_1):PAGE16
   W15 PGPPA_BMC_AUX @SCM_LIB.SCM(SCH_1):PGPPA_BMC_AUX   I188 @SCM_LIB.SCM(SCH_1):PAGE16
   F19 P3V3_P1V8_I2C_I3C @SCM_LIB.SCM(SCH_1):P3V3_P1V8_I2C_I3C   I188 @SCM_LIB.SCM(SCH_1):PAGE16
    N8 P1V0_AUX @SCM_LIB.SCM(SCH_1):P1V0_AUX   I188 @SCM_LIB.SCM(SCH_1):PAGE16
    P8 P1V0_AUX @SCM_LIB.SCM(SCH_1):P1V0_AUX   I188 @SCM_LIB.SCM(SCH_1):PAGE16
   M11 P1V0_AUX @SCM_LIB.SCM(SCH_1):P1V0_AUX   I188 @SCM_LIB.SCM(SCH_1):PAGE16
   N11 P1V0_AUX @SCM_LIB.SCM(SCH_1):P1V0_AUX   I188 @SCM_LIB.SCM(SCH_1):PAGE16
   P11 P1V0_AUX @SCM_LIB.SCM(SCH_1):P1V0_AUX   I188 @SCM_LIB.SCM(SCH_1):PAGE16
    R9 P1V0_AUX @SCM_LIB.SCM(SCH_1):P1V0_AUX   I188 @SCM_LIB.SCM(SCH_1):PAGE16
    U6 P1V8_AUX @SCM_LIB.SCM(SCH_1):P1V8_AUX   I188 @SCM_LIB.SCM(SCH_1):PAGE16
    V6 P1V8_AUX @SCM_LIB.SCM(SCH_1):P1V8_AUX   I188 @SCM_LIB.SCM(SCH_1):PAGE16
    H8 P1V8_AUX @SCM_LIB.SCM(SCH_1):P1V8_AUX   I188 @SCM_LIB.SCM(SCH_1):PAGE16
    J8 P1V8_AUX @SCM_LIB.SCM(SCH_1):P1V8_AUX   I188 @SCM_LIB.SCM(SCH_1):PAGE16
   H12 P1V8_AUX @SCM_LIB.SCM(SCH_1):P1V8_AUX   I188 @SCM_LIB.SCM(SCH_1):PAGE16
   H16 P3V3_AUX @SCM_LIB.SCM(SCH_1):P3V3_AUX   I188 @SCM_LIB.SCM(SCH_1):PAGE16
   H17 P3V3_AUX @SCM_LIB.SCM(SCH_1):P3V3_AUX   I188 @SCM_LIB.SCM(SCH_1):PAGE16
   W16 P3V3_AUX @SCM_LIB.SCM(SCH_1):P3V3_AUX   I188 @SCM_LIB.SCM(SCH_1):PAGE16
   W17 P3V3_AUX @SCM_LIB.SCM(SCH_1):P3V3_AUX   I188 @SCM_LIB.SCM(SCH_1):PAGE16
   W18 P3V3_AUX @SCM_LIB.SCM(SCH_1):P3V3_AUX   I188 @SCM_LIB.SCM(SCH_1):PAGE16
   W19 P3V3_AUX @SCM_LIB.SCM(SCH_1):P3V3_AUX   I188 @SCM_LIB.SCM(SCH_1):PAGE16
   N22 P3V3_AUX @SCM_LIB.SCM(SCH_1):P3V3_AUX   I188 @SCM_LIB.SCM(SCH_1):PAGE16
   P22 P3V3_AUX @SCM_LIB.SCM(SCH_1):P3V3_AUX   I188 @SCM_LIB.SCM(SCH_1):PAGE16
   R22 P3V3_AUX @SCM_LIB.SCM(SCH_1):P3V3_AUX   I188 @SCM_LIB.SCM(SCH_1):PAGE16
   T22 P3V3_AUX @SCM_LIB.SCM(SCH_1):P3V3_AUX   I188 @SCM_LIB.SCM(SCH_1):PAGE16
   V23 P3V3_RTC_AUX @SCM_LIB.SCM(SCH_1):P3V3_RTC_AUX   I188 @SCM_LIB.SCM(SCH_1):PAGE16
   L13 P1V8_AUX @SCM_LIB.SCM(SCH_1):P1V8_AUX   I188 @SCM_LIB.SCM(SCH_1):PAGE16
   M13 P1V8_AUX @SCM_LIB.SCM(SCH_1):P1V8_AUX   I188 @SCM_LIB.SCM(SCH_1):PAGE16
   N13 P1V8_AUX @SCM_LIB.SCM(SCH_1):P1V8_AUX   I188 @SCM_LIB.SCM(SCH_1):PAGE16
   P13 P1V8_AUX @SCM_LIB.SCM(SCH_1):P1V8_AUX   I188 @SCM_LIB.SCM(SCH_1):PAGE16
   R13 P1V8_AUX @SCM_LIB.SCM(SCH_1):P1V8_AUX   I188 @SCM_LIB.SCM(SCH_1):PAGE16
   T13 P1V8_AUX @SCM_LIB.SCM(SCH_1):P1V8_AUX   I188 @SCM_LIB.SCM(SCH_1):PAGE16
   U13 P1V8_AUX @SCM_LIB.SCM(SCH_1):P1V8_AUX   I188 @SCM_LIB.SCM(SCH_1):PAGE16
   V13 P1V8_AUX @SCM_LIB.SCM(SCH_1):P1V8_AUX   I188 @SCM_LIB.SCM(SCH_1):PAGE16
   W13 P1V8_AUX @SCM_LIB.SCM(SCH_1):P1V8_AUX   I188 @SCM_LIB.SCM(SCH_1):PAGE16
   W14 P1V8_AUX @SCM_LIB.SCM(SCH_1):P1V8_AUX   I188 @SCM_LIB.SCM(SCH_1):PAGE16
  AA21 A_BMC_ADCAV33 @SCM_LIB.SCM(SCH_1):A_BMC_ADCAV33   I188 @SCM_LIB.SCM(SCH_1):PAGE16
   J12 P1V8_AUX @SCM_LIB.SCM(SCH_1):P1V8_AUX   I188 @SCM_LIB.SCM(SCH_1):PAGE16
   R10 P1V0_AUX @SCM_LIB.SCM(SCH_1):P1V0_AUX   I188 @SCM_LIB.SCM(SCH_1):PAGE16
  AF19 ADCVREFEXT0 @SCM_LIB.SCM(SCH_1):ADCVREFEXT0   I188 @SCM_LIB.SCM(SCH_1):PAGE16
  AF17 ADCVREFEXT1 @SCM_LIB.SCM(SCH_1):ADCVREFEXT1   I188 @SCM_LIB.SCM(SCH_1):PAGE16
   N12 P1V8_AUX @SCM_LIB.SCM(SCH_1):P1V8_AUX   I188 @SCM_LIB.SCM(SCH_1):PAGE16
   P12 P1V8_AUX @SCM_LIB.SCM(SCH_1):P1V8_AUX   I188 @SCM_LIB.SCM(SCH_1):PAGE16
   R12 P1V8_AUX @SCM_LIB.SCM(SCH_1):P1V8_AUX   I188 @SCM_LIB.SCM(SCH_1):PAGE16
   H21 P3V3_P1V8_SD1VDD @SCM_LIB.SCM(SCH_1):P3V3_P1V8_SD1VDD   I188 @SCM_LIB.SCM(SCH_1):PAGE16
   H19 P3V3_P1V8_SD2VDD @SCM_LIB.SCM(SCH_1):P3V3_P1V8_SD2VDD   I188 @SCM_LIB.SCM(SCH_1):PAGE16
   F20 P3V3_P1V8_I2C_I3C @SCM_LIB.SCM(SCH_1):P3V3_P1V8_I2C_I3C   I188 @SCM_LIB.SCM(SCH_1):PAGE16
   H15 P3V3_AUX @SCM_LIB.SCM(SCH_1):P3V3_AUX   I188 @SCM_LIB.SCM(SCH_1):PAGE16
    J9 P1V0_STBY_PLAVDD @SCM_LIB.SCM(SCH_1):P1V0_STBY_PLAVDD   I188 @SCM_LIB.SCM(SCH_1):PAGE16
   V22 P1V2_P1V0_I3C_VDDL1 @SCM_LIB.SCM(SCH_1):P1V2_P1V0_I3C_VDDL1   I188 @SCM_LIB.SCM(SCH_1):PAGE16
   U21 P1V2_P1V0_I3C_VDDL2 @SCM_LIB.SCM(SCH_1):P1V2_P1V0_I3C_VDDL2   I188 @SCM_LIB.SCM(SCH_1):PAGE16
   K11 P3V3_RGM @SCM_LIB.SCM(SCH_1):P3V3_RGM   I188 @SCM_LIB.SCM(SCH_1):PAGE16
   K12 P3V3_RGM @SCM_LIB.SCM(SCH_1):P3V3_RGM   I188 @SCM_LIB.SCM(SCH_1):PAGE16
    A1    GND @SCM_LIB.SCM(SCH_1):GND   I286 @SCM_LIB.SCM(SCH_1):PAGE17
    A5    GND @SCM_LIB.SCM(SCH_1):GND   I286 @SCM_LIB.SCM(SCH_1):PAGE17
   A26    GND @SCM_LIB.SCM(SCH_1):GND   I286 @SCM_LIB.SCM(SCH_1):PAGE17
    B5    GND @SCM_LIB.SCM(SCH_1):GND   I286 @SCM_LIB.SCM(SCH_1):PAGE17
   B11    GND @SCM_LIB.SCM(SCH_1):GND   I286 @SCM_LIB.SCM(SCH_1):PAGE17
   B15    GND @SCM_LIB.SCM(SCH_1):GND   I286 @SCM_LIB.SCM(SCH_1):PAGE17
   B19    GND @SCM_LIB.SCM(SCH_1):GND   I286 @SCM_LIB.SCM(SCH_1):PAGE17
   B23    GND @SCM_LIB.SCM(SCH_1):GND   I286 @SCM_LIB.SCM(SCH_1):PAGE17
    C3    GND @SCM_LIB.SCM(SCH_1):GND   I286 @SCM_LIB.SCM(SCH_1):PAGE17
   D25    GND @SCM_LIB.SCM(SCH_1):GND   I286 @SCM_LIB.SCM(SCH_1):PAGE17
    E8    GND @SCM_LIB.SCM(SCH_1):GND   I286 @SCM_LIB.SCM(SCH_1):PAGE17
    F6    GND @SCM_LIB.SCM(SCH_1):GND   I286 @SCM_LIB.SCM(SCH_1):PAGE17
    F8    GND @SCM_LIB.SCM(SCH_1):GND   I286 @SCM_LIB.SCM(SCH_1):PAGE17
   F10    GND @SCM_LIB.SCM(SCH_1):GND   I286 @SCM_LIB.SCM(SCH_1):PAGE17
   F12    GND @SCM_LIB.SCM(SCH_1):GND   I286 @SCM_LIB.SCM(SCH_1):PAGE17
   F14    GND @SCM_LIB.SCM(SCH_1):GND   I286 @SCM_LIB.SCM(SCH_1):PAGE17
   F16    GND @SCM_LIB.SCM(SCH_1):GND   I286 @SCM_LIB.SCM(SCH_1):PAGE17
   F17    GND @SCM_LIB.SCM(SCH_1):GND   I286 @SCM_LIB.SCM(SCH_1):PAGE17
   F18    GND @SCM_LIB.SCM(SCH_1):GND   I286 @SCM_LIB.SCM(SCH_1):PAGE17
   F21    GND @SCM_LIB.SCM(SCH_1):GND   I286 @SCM_LIB.SCM(SCH_1):PAGE17
    G2    GND @SCM_LIB.SCM(SCH_1):GND   I286 @SCM_LIB.SCM(SCH_1):PAGE17
   G25    GND @SCM_LIB.SCM(SCH_1):GND   I286 @SCM_LIB.SCM(SCH_1):PAGE17
    H4    GND @SCM_LIB.SCM(SCH_1):GND   I286 @SCM_LIB.SCM(SCH_1):PAGE17
    H9    GND @SCM_LIB.SCM(SCH_1):GND   I286 @SCM_LIB.SCM(SCH_1):PAGE17
   H10    GND @SCM_LIB.SCM(SCH_1):GND   I286 @SCM_LIB.SCM(SCH_1):PAGE17
   H11    GND @SCM_LIB.SCM(SCH_1):GND   I286 @SCM_LIB.SCM(SCH_1):PAGE17
   H13    GND @SCM_LIB.SCM(SCH_1):GND   I286 @SCM_LIB.SCM(SCH_1):PAGE17
    J2    GND @SCM_LIB.SCM(SCH_1):GND   I286 @SCM_LIB.SCM(SCH_1):PAGE17
   J11    GND @SCM_LIB.SCM(SCH_1):GND   I286 @SCM_LIB.SCM(SCH_1):PAGE17
   J13    GND @SCM_LIB.SCM(SCH_1):GND   I286 @SCM_LIB.SCM(SCH_1):PAGE17
   J14    GND @SCM_LIB.SCM(SCH_1):GND   I286 @SCM_LIB.SCM(SCH_1):PAGE17
   J15    GND @SCM_LIB.SCM(SCH_1):GND   I286 @SCM_LIB.SCM(SCH_1):PAGE17
   J16    GND @SCM_LIB.SCM(SCH_1):GND   I286 @SCM_LIB.SCM(SCH_1):PAGE17
   J17    GND @SCM_LIB.SCM(SCH_1):GND   I286 @SCM_LIB.SCM(SCH_1):PAGE17
   J18    GND @SCM_LIB.SCM(SCH_1):GND   I286 @SCM_LIB.SCM(SCH_1):PAGE17
   J19    GND @SCM_LIB.SCM(SCH_1):GND   I286 @SCM_LIB.SCM(SCH_1):PAGE17
    K4    GND @SCM_LIB.SCM(SCH_1):GND   I286 @SCM_LIB.SCM(SCH_1):PAGE17
    K8    GND @SCM_LIB.SCM(SCH_1):GND   I286 @SCM_LIB.SCM(SCH_1):PAGE17
    K9    GND @SCM_LIB.SCM(SCH_1):GND   I286 @SCM_LIB.SCM(SCH_1):PAGE17
   K13    GND @SCM_LIB.SCM(SCH_1):GND   I286 @SCM_LIB.SCM(SCH_1):PAGE17
   K14    GND @SCM_LIB.SCM(SCH_1):GND   I286 @SCM_LIB.SCM(SCH_1):PAGE17
   K15    GND @SCM_LIB.SCM(SCH_1):GND   I286 @SCM_LIB.SCM(SCH_1):PAGE17
   K22    GND @SCM_LIB.SCM(SCH_1):GND   I286 @SCM_LIB.SCM(SCH_1):PAGE17
    L2    GND @SCM_LIB.SCM(SCH_1):GND   I286 @SCM_LIB.SCM(SCH_1):PAGE17
    L8    GND @SCM_LIB.SCM(SCH_1):GND   I286 @SCM_LIB.SCM(SCH_1):PAGE17
   L11    GND @SCM_LIB.SCM(SCH_1):GND   I286 @SCM_LIB.SCM(SCH_1):PAGE17
   L12    GND @SCM_LIB.SCM(SCH_1):GND   I286 @SCM_LIB.SCM(SCH_1):PAGE17
   L15    GND @SCM_LIB.SCM(SCH_1):GND   I286 @SCM_LIB.SCM(SCH_1):PAGE17
   L16    GND @SCM_LIB.SCM(SCH_1):GND   I286 @SCM_LIB.SCM(SCH_1):PAGE17
   L17    GND @SCM_LIB.SCM(SCH_1):GND   I286 @SCM_LIB.SCM(SCH_1):PAGE17
    R2    GND @SCM_LIB.SCM(SCH_1):GND   I286 @SCM_LIB.SCM(SCH_1):PAGE17
    R8    GND @SCM_LIB.SCM(SCH_1):GND   I286 @SCM_LIB.SCM(SCH_1):PAGE17
   R11    GND @SCM_LIB.SCM(SCH_1):GND   I286 @SCM_LIB.SCM(SCH_1):PAGE17
   R15    GND @SCM_LIB.SCM(SCH_1):GND   I286 @SCM_LIB.SCM(SCH_1):PAGE17
   R16    GND @SCM_LIB.SCM(SCH_1):GND   I286 @SCM_LIB.SCM(SCH_1):PAGE17
   R17    GND @SCM_LIB.SCM(SCH_1):GND   I286 @SCM_LIB.SCM(SCH_1):PAGE17
   R18    GND @SCM_LIB.SCM(SCH_1):GND   I286 @SCM_LIB.SCM(SCH_1):PAGE17
   R19    GND @SCM_LIB.SCM(SCH_1):GND   I286 @SCM_LIB.SCM(SCH_1):PAGE17
   R25    GND @SCM_LIB.SCM(SCH_1):GND   I286 @SCM_LIB.SCM(SCH_1):PAGE17
    T4    GND @SCM_LIB.SCM(SCH_1):GND   I286 @SCM_LIB.SCM(SCH_1):PAGE17
   T11    GND @SCM_LIB.SCM(SCH_1):GND   I286 @SCM_LIB.SCM(SCH_1):PAGE17
   T12    GND @SCM_LIB.SCM(SCH_1):GND   I286 @SCM_LIB.SCM(SCH_1):PAGE17
   T15    GND @SCM_LIB.SCM(SCH_1):GND   I286 @SCM_LIB.SCM(SCH_1):PAGE17
   T16    GND @SCM_LIB.SCM(SCH_1):GND   I286 @SCM_LIB.SCM(SCH_1):PAGE17
   T17    GND @SCM_LIB.SCM(SCH_1):GND   I286 @SCM_LIB.SCM(SCH_1):PAGE17
   T18    GND @SCM_LIB.SCM(SCH_1):GND   I286 @SCM_LIB.SCM(SCH_1):PAGE17
   T19    GND @SCM_LIB.SCM(SCH_1):GND   I286 @SCM_LIB.SCM(SCH_1):PAGE17
    U2    GND @SCM_LIB.SCM(SCH_1):GND   I286 @SCM_LIB.SCM(SCH_1):PAGE17
    U8    GND @SCM_LIB.SCM(SCH_1):GND   I286 @SCM_LIB.SCM(SCH_1):PAGE17
    U9    GND @SCM_LIB.SCM(SCH_1):GND   I286 @SCM_LIB.SCM(SCH_1):PAGE17
   U10    GND @SCM_LIB.SCM(SCH_1):GND   I286 @SCM_LIB.SCM(SCH_1):PAGE17
   U11    GND @SCM_LIB.SCM(SCH_1):GND   I286 @SCM_LIB.SCM(SCH_1):PAGE17
   U12    GND @SCM_LIB.SCM(SCH_1):GND   I286 @SCM_LIB.SCM(SCH_1):PAGE17
   U14    GND @SCM_LIB.SCM(SCH_1):GND   I286 @SCM_LIB.SCM(SCH_1):PAGE17
   U19    GND @SCM_LIB.SCM(SCH_1):GND   I286 @SCM_LIB.SCM(SCH_1):PAGE17
   U22    GND @SCM_LIB.SCM(SCH_1):GND   I286 @SCM_LIB.SCM(SCH_1):PAGE17
    V5    GND @SCM_LIB.SCM(SCH_1):GND   I286 @SCM_LIB.SCM(SCH_1):PAGE17
   V11    GND @SCM_LIB.SCM(SCH_1):GND   I286 @SCM_LIB.SCM(SCH_1):PAGE17
   V12    GND @SCM_LIB.SCM(SCH_1):GND   I286 @SCM_LIB.SCM(SCH_1):PAGE17
   V14    GND @SCM_LIB.SCM(SCH_1):GND   I286 @SCM_LIB.SCM(SCH_1):PAGE17
   V15    GND @SCM_LIB.SCM(SCH_1):GND   I286 @SCM_LIB.SCM(SCH_1):PAGE17
   V16    GND @SCM_LIB.SCM(SCH_1):GND   I286 @SCM_LIB.SCM(SCH_1):PAGE17
   V17    GND @SCM_LIB.SCM(SCH_1):GND   I286 @SCM_LIB.SCM(SCH_1):PAGE17
   V18    GND @SCM_LIB.SCM(SCH_1):GND   I286 @SCM_LIB.SCM(SCH_1):PAGE17
   V19    GND @SCM_LIB.SCM(SCH_1):GND   I286 @SCM_LIB.SCM(SCH_1):PAGE17
    W5    GND @SCM_LIB.SCM(SCH_1):GND   I286 @SCM_LIB.SCM(SCH_1):PAGE17
    W6    GND @SCM_LIB.SCM(SCH_1):GND   I286 @SCM_LIB.SCM(SCH_1):PAGE17
    W8    GND @SCM_LIB.SCM(SCH_1):GND   I286 @SCM_LIB.SCM(SCH_1):PAGE17
    W9    GND @SCM_LIB.SCM(SCH_1):GND   I286 @SCM_LIB.SCM(SCH_1):PAGE17
   W10    GND @SCM_LIB.SCM(SCH_1):GND   I286 @SCM_LIB.SCM(SCH_1):PAGE17
   W11    GND @SCM_LIB.SCM(SCH_1):GND   I286 @SCM_LIB.SCM(SCH_1):PAGE17
   W12    GND @SCM_LIB.SCM(SCH_1):GND   I286 @SCM_LIB.SCM(SCH_1):PAGE17
   L18    GND @SCM_LIB.SCM(SCH_1):GND   I286 @SCM_LIB.SCM(SCH_1):PAGE17
   L19    GND @SCM_LIB.SCM(SCH_1):GND   I286 @SCM_LIB.SCM(SCH_1):PAGE17
   L25    GND @SCM_LIB.SCM(SCH_1):GND   I286 @SCM_LIB.SCM(SCH_1):PAGE17
    M4    GND @SCM_LIB.SCM(SCH_1):GND   I286 @SCM_LIB.SCM(SCH_1):PAGE17
    M9    GND @SCM_LIB.SCM(SCH_1):GND   I286 @SCM_LIB.SCM(SCH_1):PAGE17
   M10    GND @SCM_LIB.SCM(SCH_1):GND   I286 @SCM_LIB.SCM(SCH_1):PAGE17
   M12    GND @SCM_LIB.SCM(SCH_1):GND   I286 @SCM_LIB.SCM(SCH_1):PAGE17
   M15    GND @SCM_LIB.SCM(SCH_1):GND   I286 @SCM_LIB.SCM(SCH_1):PAGE17
   M16    GND @SCM_LIB.SCM(SCH_1):GND   I286 @SCM_LIB.SCM(SCH_1):PAGE17
   M17    GND @SCM_LIB.SCM(SCH_1):GND   I286 @SCM_LIB.SCM(SCH_1):PAGE17
   W22    GND @SCM_LIB.SCM(SCH_1):GND   I286 @SCM_LIB.SCM(SCH_1):PAGE17
   W25    GND @SCM_LIB.SCM(SCH_1):GND   I286 @SCM_LIB.SCM(SCH_1):PAGE17
    Y6    GND @SCM_LIB.SCM(SCH_1):GND   I286 @SCM_LIB.SCM(SCH_1):PAGE17
   Y22    GND @SCM_LIB.SCM(SCH_1):GND   I286 @SCM_LIB.SCM(SCH_1):PAGE17
   AA1    GND @SCM_LIB.SCM(SCH_1):GND   I286 @SCM_LIB.SCM(SCH_1):PAGE17
   AA3    GND @SCM_LIB.SCM(SCH_1):GND   I286 @SCM_LIB.SCM(SCH_1):PAGE17
   AA8    GND @SCM_LIB.SCM(SCH_1):GND   I286 @SCM_LIB.SCM(SCH_1):PAGE17
   AA7    GND @SCM_LIB.SCM(SCH_1):GND   I286 @SCM_LIB.SCM(SCH_1):PAGE17
   AA6    GND @SCM_LIB.SCM(SCH_1):GND   I286 @SCM_LIB.SCM(SCH_1):PAGE17
   M18    GND @SCM_LIB.SCM(SCH_1):GND   I286 @SCM_LIB.SCM(SCH_1):PAGE17
   M19    GND @SCM_LIB.SCM(SCH_1):GND   I286 @SCM_LIB.SCM(SCH_1):PAGE17
    N2    GND @SCM_LIB.SCM(SCH_1):GND   I286 @SCM_LIB.SCM(SCH_1):PAGE17
    N6    GND @SCM_LIB.SCM(SCH_1):GND   I286 @SCM_LIB.SCM(SCH_1):PAGE17
    N9    GND @SCM_LIB.SCM(SCH_1):GND   I286 @SCM_LIB.SCM(SCH_1):PAGE17
   N10    GND @SCM_LIB.SCM(SCH_1):GND   I286 @SCM_LIB.SCM(SCH_1):PAGE17
   N15    GND @SCM_LIB.SCM(SCH_1):GND   I286 @SCM_LIB.SCM(SCH_1):PAGE17
   N16    GND @SCM_LIB.SCM(SCH_1):GND   I286 @SCM_LIB.SCM(SCH_1):PAGE17
   N17    GND @SCM_LIB.SCM(SCH_1):GND   I286 @SCM_LIB.SCM(SCH_1):PAGE17
   N18    GND @SCM_LIB.SCM(SCH_1):GND   I286 @SCM_LIB.SCM(SCH_1):PAGE17
   N19    GND @SCM_LIB.SCM(SCH_1):GND   I286 @SCM_LIB.SCM(SCH_1):PAGE17
  AA10    GND @SCM_LIB.SCM(SCH_1):GND   I286 @SCM_LIB.SCM(SCH_1):PAGE17
  AA14    GND @SCM_LIB.SCM(SCH_1):GND   I286 @SCM_LIB.SCM(SCH_1):PAGE17
  AA15    GND @SCM_LIB.SCM(SCH_1):GND   I286 @SCM_LIB.SCM(SCH_1):PAGE17
  AA19    GND @SCM_LIB.SCM(SCH_1):GND   I286 @SCM_LIB.SCM(SCH_1):PAGE17
  AA22    GND @SCM_LIB.SCM(SCH_1):GND   I286 @SCM_LIB.SCM(SCH_1):PAGE17
   AC2    GND @SCM_LIB.SCM(SCH_1):GND   I286 @SCM_LIB.SCM(SCH_1):PAGE17
   AC6    GND @SCM_LIB.SCM(SCH_1):GND   I286 @SCM_LIB.SCM(SCH_1):PAGE17
  AC25    GND @SCM_LIB.SCM(SCH_1):GND   I286 @SCM_LIB.SCM(SCH_1):PAGE17
   AD1    GND @SCM_LIB.SCM(SCH_1):GND   I286 @SCM_LIB.SCM(SCH_1):PAGE17
   AD4    GND @SCM_LIB.SCM(SCH_1):GND   I286 @SCM_LIB.SCM(SCH_1):PAGE17
   AE3    GND @SCM_LIB.SCM(SCH_1):GND   I286 @SCM_LIB.SCM(SCH_1):PAGE17
   AE6    GND @SCM_LIB.SCM(SCH_1):GND   I286 @SCM_LIB.SCM(SCH_1):PAGE17
   AE9    GND @SCM_LIB.SCM(SCH_1):GND   I286 @SCM_LIB.SCM(SCH_1):PAGE17
  AE13    GND @SCM_LIB.SCM(SCH_1):GND   I286 @SCM_LIB.SCM(SCH_1):PAGE17
  AE17    GND @SCM_LIB.SCM(SCH_1):GND   I286 @SCM_LIB.SCM(SCH_1):PAGE17
  AE20    GND @SCM_LIB.SCM(SCH_1):GND   I286 @SCM_LIB.SCM(SCH_1):PAGE17
  AE23    GND @SCM_LIB.SCM(SCH_1):GND   I286 @SCM_LIB.SCM(SCH_1):PAGE17
   AF1    GND @SCM_LIB.SCM(SCH_1):GND   I286 @SCM_LIB.SCM(SCH_1):PAGE17
   AF4    GND @SCM_LIB.SCM(SCH_1):GND   I286 @SCM_LIB.SCM(SCH_1):PAGE17
  AF26    GND @SCM_LIB.SCM(SCH_1):GND   I286 @SCM_LIB.SCM(SCH_1):PAGE17
    P4    GND @SCM_LIB.SCM(SCH_1):GND   I286 @SCM_LIB.SCM(SCH_1):PAGE17
    P9    GND @SCM_LIB.SCM(SCH_1):GND   I286 @SCM_LIB.SCM(SCH_1):PAGE17
   P10    GND @SCM_LIB.SCM(SCH_1):GND   I286 @SCM_LIB.SCM(SCH_1):PAGE17
   P15    GND @SCM_LIB.SCM(SCH_1):GND   I286 @SCM_LIB.SCM(SCH_1):PAGE17
   P16    GND @SCM_LIB.SCM(SCH_1):GND   I286 @SCM_LIB.SCM(SCH_1):PAGE17
   P17    GND @SCM_LIB.SCM(SCH_1):GND   I286 @SCM_LIB.SCM(SCH_1):PAGE17
   P18    GND @SCM_LIB.SCM(SCH_1):GND   I286 @SCM_LIB.SCM(SCH_1):PAGE17
   P19    GND @SCM_LIB.SCM(SCH_1):GND   I286 @SCM_LIB.SCM(SCH_1):PAGE17
  AA20    GND @SCM_LIB.SCM(SCH_1):GND   I286 @SCM_LIB.SCM(SCH_1):PAGE17
   U23    GND @SCM_LIB.SCM(SCH_1):GND   I286 @SCM_LIB.SCM(SCH_1):PAGE17

  U6 74LVC2G07DW7-74LVC2G07DW-7,SMLA
     1 PWRGD_P1V0_AUX_DELAY @SCM_LIB.SCM(SCH_1):PWRGD_P1V0_AUX_DELAY    I87 @SCM_LIB.SCM(SCH_1):PAGE22
     3 RST_SRST_PLD_BMC_R1_N @SCM_LIB.SCM(SCH_1):RST_SRST_PLD_BMC_R1_N    I87 @SCM_LIB.SCM(SCH_1):PAGE22
     6 PWRGD_P1V0_AUX_DELAY_BUF @SCM_LIB.SCM(SCH_1):PWRGD_P1V0_AUX_DELAY_BUF    I87 @SCM_LIB.SCM(SCH_1):PAGE22
     4 RST_SRST_PLD_BMC_BUF_N @SCM_LIB.SCM(SCH_1):RST_SRST_PLD_BMC_BUF_N    I87 @SCM_LIB.SCM(SCH_1):PAGE22
     2    GND @SCM_LIB.SCM(SCH_1):GND    I87 @SCM_LIB.SCM(SCH_1):PAGE22
     5 P3V3_AUX @SCM_LIB.SCM(SCH_1):P3V3_AUX    I87 @SCM_LIB.SCM(SCH_1):PAGE22

  U7 NC7SB3157_SMLF-NC7SB3157P6X,NCA
     1 SPA_SOUT_SW_DBG_R @SCM_LIB.SCM(SCH_1):SPA_SOUT_SW_DBG_R    I27 @SCM_LIB.SCM(SCH_1):PAGE31
     2    GND @SCM_LIB.SCM(SCH_1):GND    I27 @SCM_LIB.SCM(SCH_1):PAGE31
     3 UART_SYS_DBG_TX_R @SCM_LIB.SCM(SCH_1):UART_SYS_DBG_TX_R    I27 @SCM_LIB.SCM(SCH_1):PAGE31
     6 FM_DBG_SW_N @SCM_LIB.SCM(SCH_1):FM_DBG_SW_N    I27 @SCM_LIB.SCM(SCH_1):PAGE31
     5 P3V3_AUX @SCM_LIB.SCM(SCH_1):P3V3_AUX    I27 @SCM_LIB.SCM(SCH_1):PAGE31
     4 SPA_SOUT_SW_BUF_R @SCM_LIB.SCM(SCH_1):SPA_SOUT_SW_BUF_R    I27 @SCM_LIB.SCM(SCH_1):PAGE31

  U8 74LVC1G126SE7-74LVC1G126SE-7,SA
     2 PCH_BEEP_LED @SCM_LIB.SCM(SCH_1):PCH_BEEP_LED    I11 @SCM_LIB.SCM(SCH_1):PAGE49
     4 BEEP_LED @SCM_LIB.SCM(SCH_1):BEEP_LED    I11 @SCM_LIB.SCM(SCH_1):PAGE49
     5 P3V3_AUX @SCM_LIB.SCM(SCH_1):P3V3_AUX    I11 @SCM_LIB.SCM(SCH_1):PAGE49
     3    GND @SCM_LIB.SCM(SCH_1):GND    I11 @SCM_LIB.SCM(SCH_1):PAGE49
     1 BMC_ID_BEEP_SEL @SCM_LIB.SCM(SCH_1):BMC_ID_BEEP_SEL    I11 @SCM_LIB.SCM(SCH_1):PAGE49

  U9 MC74VHC1G32DTT1G-MC74VHC1G32DTA
     4 ID_LED_BUF @SCM_LIB.SCM(SCH_1):ID_LED_BUF     I5 @SCM_LIB.SCM(SCH_1):PAGE49
     1 BEEP_LED @SCM_LIB.SCM(SCH_1):BEEP_LED     I5 @SCM_LIB.SCM(SCH_1):PAGE49
     2 FM_ID_R_LED @SCM_LIB.SCM(SCH_1):FM_ID_R_LED     I5 @SCM_LIB.SCM(SCH_1):PAGE49
     3    GND @SCM_LIB.SCM(SCH_1):GND     I5 @SCM_LIB.SCM(SCH_1):PAGE49
     5 P3V3_AUX @SCM_LIB.SCM(SCH_1):P3V3_AUX     I5 @SCM_LIB.SCM(SCH_1):PAGE49

 U10 NCP380HSNAJAAT1G-NCP380HSNAJAAA
     4 USB_OC0_REAR_N @SCM_LIB.SCM(SCH_1):USB_OC0_REAR_N   I179 @SCM_LIB.SCM(SCH_1):PAGE28
     1 P5V_AUX @SCM_LIB.SCM(SCH_1):P5V_AUX   I179 @SCM_LIB.SCM(SCH_1):PAGE28
     5 USB_OC0_ILIM @SCM_LIB.SCM(SCH_1):USB_OC0_ILIM   I179 @SCM_LIB.SCM(SCH_1):PAGE28
     6 P5V_USB_REAR @SCM_LIB.SCM(SCH_1):P5V_USB_REAR   I179 @SCM_LIB.SCM(SCH_1):PAGE28
     3 USB_OC0_EN @SCM_LIB.SCM(SCH_1):USB_OC0_EN   I179 @SCM_LIB.SCM(SCH_1):PAGE28
     2    GND @SCM_LIB.SCM(SCH_1):GND   I179 @SCM_LIB.SCM(SCH_1):PAGE28

 U11 BAT54C-BAT54C,SMLF,IC,BCBAT54CA
     2 UART_BMC_5_TXD_R @SCM_LIB.SCM(SCH_1):UART_BMC_5_TXD_R   I185 @SCM_LIB.SCM(SCH_1):PAGE27
     1 FM_BMC_ONCTL_R_N @SCM_LIB.SCM(SCH_1):FM_BMC_ONCTL_R_N   I185 @SCM_LIB.SCM(SCH_1):PAGE27
     3 FM_BMC_DISABLE @SCM_LIB.SCM(SCH_1):FM_BMC_DISABLE   I185 @SCM_LIB.SCM(SCH_1):PAGE27

 U12 MOSFET_N_SMLF-BSS138K,BSS138K,A
     G RST_BMC_SELF_HW_D_C @SCM_LIB.SCM(SCH_1):RST_BMC_SELF_HW_D_C    I14 @SCM_LIB.SCM(SCH_1):PAGE22
     D RST_BMC_EXTRST_R1_N @SCM_LIB.SCM(SCH_1):RST_BMC_EXTRST_R1_N    I14 @SCM_LIB.SCM(SCH_1):PAGE22
     S    GND @SCM_LIB.SCM(SCH_1):GND    I14 @SCM_LIB.SCM(SCH_1):PAGE22

 U13 MC74VHC1G07DFT2G-MC74VHC1G07DFA
     5 P3V3_AUX @SCM_LIB.SCM(SCH_1):P3V3_AUX    I89 @SCM_LIB.SCM(SCH_1):PAGE22
     2 RST_BMC_SRST_BUF_R1_N @SCM_LIB.SCM(SCH_1):RST_BMC_SRST_BUF_R1_N    I89 @SCM_LIB.SCM(SCH_1):PAGE22
     3    GND @SCM_LIB.SCM(SCH_1):GND    I89 @SCM_LIB.SCM(SCH_1):PAGE22
     4 RST_BMC_EXTRST_R1_N @SCM_LIB.SCM(SCH_1):RST_BMC_EXTRST_R1_N    I89 @SCM_LIB.SCM(SCH_1):PAGE22
     1     NC     NC    I89 @SCM_LIB.SCM(SCH_1):PAGE22

 U14 AP22811AW57-AP22811AW5-7,SMLF,A
     1 P3V3_RGM @SCM_LIB.SCM(SCH_1):P3V3_RGM    I79 @SCM_LIB.SCM(SCH_1):PAGE52
     2    GND @SCM_LIB.SCM(SCH_1):GND    I79 @SCM_LIB.SCM(SCH_1):PAGE52
     4 EN_P3V3_RGM_R @SCM_LIB.SCM(SCH_1):EN_P3V3_RGM_R    I79 @SCM_LIB.SCM(SCH_1):PAGE52
     3 TP_U14_FLAG_N @SCM_LIB.SCM(SCH_1):TP_U14_FLAG_N    I79 @SCM_LIB.SCM(SCH_1):PAGE52
     5 P3V3_AUX @SCM_LIB.SCM(SCH_1):P3V3_AUX    I79 @SCM_LIB.SCM(SCH_1):PAGE52

 U15 74LVC1G08GW_SM-74LVC1G08GW,IC,A
     1 SYS_BMC_PWRBTN_R_N @SCM_LIB.SCM(SCH_1):SYS_BMC_PWRBTN_R_N   I393 @SCM_LIB.SCM(SCH_1):PAGE15
     2 PWR_BTN_BMC_N @SCM_LIB.SCM(SCH_1):PWR_BTN_BMC_N   I393 @SCM_LIB.SCM(SCH_1):PAGE15
     4 SYS_PWRBTN_N @SCM_LIB.SCM(SCH_1):SYS_PWRBTN_N   I393 @SCM_LIB.SCM(SCH_1):PAGE15
     5 P3V3_AUX @SCM_LIB.SCM(SCH_1):P3V3_AUX   I393 @SCM_LIB.SCM(SCH_1):PAGE15
     3    GND @SCM_LIB.SCM(SCH_1):GND   I393 @SCM_LIB.SCM(SCH_1):PAGE15

 U16 74LVC1G07GW-74LVC1G07GW,SMLF,EA
     5 P3V3_AUX @SCM_LIB.SCM(SCH_1):P3V3_AUX   I227 @SCM_LIB.SCM(SCH_1):PAGE50
     2 REAR_AC_PWR_BTN_N @SCM_LIB.SCM(SCH_1):REAR_AC_PWR_BTN_N   I227 @SCM_LIB.SCM(SCH_1):PAGE50
     3    GND @SCM_LIB.SCM(SCH_1):GND   I227 @SCM_LIB.SCM(SCH_1):PAGE50
     4 AC_PWR_BTN_R1_N @SCM_LIB.SCM(SCH_1):AC_PWR_BTN_R1_N   I227 @SCM_LIB.SCM(SCH_1):PAGE50
     1 NC_U16_P1 @SCM_LIB.SCM(SCH_1):NC_U16_P1   I227 @SCM_LIB.SCM(SCH_1):PAGE50

 U17 MX25L51245GMI10G-MX25L51245GMIA
     1 SPI_PCH_IO3_FLASH_R1 @SCM_LIB.SCM(SCH_1):SPI_PCH_IO3_FLASH_R1    I54 @SCM_LIB.SCM(SCH_1):PAGE45
     2 P3V3_AUX @SCM_LIB.SCM(SCH_1):P3V3_AUX    I54 @SCM_LIB.SCM(SCH_1):PAGE45
     3 RST_SPI_PCH_FLASH_R1_N @SCM_LIB.SCM(SCH_1):RST_SPI_PCH_FLASH_R1_N    I54 @SCM_LIB.SCM(SCH_1):PAGE45
     4 TP_J40_4 @SCM_LIB.SCM(SCH_1):TP_J40_4    I54 @SCM_LIB.SCM(SCH_1):PAGE45
     5 TP_J40_5 @SCM_LIB.SCM(SCH_1):TP_J40_5    I54 @SCM_LIB.SCM(SCH_1):PAGE45
     6 TP_J40_6 @SCM_LIB.SCM(SCH_1):TP_J40_6    I54 @SCM_LIB.SCM(SCH_1):PAGE45
     7 SPI_PCH_CS0_FLASH_R1_N @SCM_LIB.SCM(SCH_1):SPI_PCH_CS0_FLASH_R1_N    I54 @SCM_LIB.SCM(SCH_1):PAGE45
     8 SPI_PCH_IO1_FLASH_R1 @SCM_LIB.SCM(SCH_1):SPI_PCH_IO1_FLASH_R1    I54 @SCM_LIB.SCM(SCH_1):PAGE45
     9 SPI_PCH_IO2_FLASH_R1 @SCM_LIB.SCM(SCH_1):SPI_PCH_IO2_FLASH_R1    I54 @SCM_LIB.SCM(SCH_1):PAGE45
    10    GND @SCM_LIB.SCM(SCH_1):GND    I54 @SCM_LIB.SCM(SCH_1):PAGE45
    11 TP_J40_11 @SCM_LIB.SCM(SCH_1):TP_J40_11    I54 @SCM_LIB.SCM(SCH_1):PAGE45
    12 TP_J40_12 @SCM_LIB.SCM(SCH_1):TP_J40_12    I54 @SCM_LIB.SCM(SCH_1):PAGE45
    13 TP_J40_13 @SCM_LIB.SCM(SCH_1):TP_J40_13    I54 @SCM_LIB.SCM(SCH_1):PAGE45
    14 TP_J40_14 @SCM_LIB.SCM(SCH_1):TP_J40_14    I54 @SCM_LIB.SCM(SCH_1):PAGE45
    15 SPI_PCH_IO0_FLASH_R1 @SCM_LIB.SCM(SCH_1):SPI_PCH_IO0_FLASH_R1    I54 @SCM_LIB.SCM(SCH_1):PAGE45
    16 SPI_PCH_CLK_FLASH_R1 @SCM_LIB.SCM(SCH_1):SPI_PCH_CLK_FLASH_R1    I54 @SCM_LIB.SCM(SCH_1):PAGE45

 U18 74LVC1G08GW_SM-74LVC1G08GW,IC,A
     1 PWRGD_P5V_AUX @SCM_LIB.SCM(SCH_1):PWRGD_P5V_AUX   I114 @SCM_LIB.SCM(SCH_1):PAGE52
     2 PWRGD_P1V8_AUX_R2 @SCM_LIB.SCM(SCH_1):PWRGD_P1V8_AUX_R2   I114 @SCM_LIB.SCM(SCH_1):PAGE52
     4 EN_P3V3_RGM @SCM_LIB.SCM(SCH_1):EN_P3V3_RGM   I114 @SCM_LIB.SCM(SCH_1):PAGE52
     5 P3V3_LDO @SCM_LIB.SCM(SCH_1):P3V3_LDO   I114 @SCM_LIB.SCM(SCH_1):PAGE52
     3    GND @SCM_LIB.SCM(SCH_1):GND   I114 @SCM_LIB.SCM(SCH_1):PAGE52

 U19 M24128BWDW6TP-M24128-BWDW6TP,SA
     8 P3V3_AUX @SCM_LIB.SCM(SCH_1):P3V3_AUX    I15 @SCM_LIB.SCM(SCH_1):PAGE26
     7 PD_FRU_WC_N @SCM_LIB.SCM(SCH_1):PD_FRU_WC_N    I15 @SCM_LIB.SCM(SCH_1):PAGE26
     6 SMB_BMC_MM16_R2_SCL @SCM_LIB.SCM(SCH_1):SMB_BMC_MM16_R2_SCL    I15 @SCM_LIB.SCM(SCH_1):PAGE26
     5 SMB_BMC_MM16_R2_SDA @SCM_LIB.SCM(SCH_1):SMB_BMC_MM16_R2_SDA    I15 @SCM_LIB.SCM(SCH_1):PAGE26
     4    GND @SCM_LIB.SCM(SCH_1):GND    I15 @SCM_LIB.SCM(SCH_1):PAGE26
     3 FRU_E2 @SCM_LIB.SCM(SCH_1):FRU_E2    I15 @SCM_LIB.SCM(SCH_1):PAGE26
     2 FRU_E1 @SCM_LIB.SCM(SCH_1):FRU_E1    I15 @SCM_LIB.SCM(SCH_1):PAGE26
     1 FRU_E0 @SCM_LIB.SCM(SCH_1):FRU_E0    I15 @SCM_LIB.SCM(SCH_1):PAGE26

 U20 NC7SB3157_SMLF-NC7SB3157P6X,NCA
     1 SPA_SIN_SW_DBG_R @SCM_LIB.SCM(SCH_1):SPA_SIN_SW_DBG_R    I38 @SCM_LIB.SCM(SCH_1):PAGE31
     2    GND @SCM_LIB.SCM(SCH_1):GND    I38 @SCM_LIB.SCM(SCH_1):PAGE31
     3 UART_SYS_DBG_RX_R @SCM_LIB.SCM(SCH_1):UART_SYS_DBG_RX_R    I38 @SCM_LIB.SCM(SCH_1):PAGE31
     6 FM_DBG_SW_N @SCM_LIB.SCM(SCH_1):FM_DBG_SW_N    I38 @SCM_LIB.SCM(SCH_1):PAGE31
     5 P3V3_AUX @SCM_LIB.SCM(SCH_1):P3V3_AUX    I38 @SCM_LIB.SCM(SCH_1):PAGE31
     4 SPA_SIN_SW_BUF_R @SCM_LIB.SCM(SCH_1):SPA_SIN_SW_BUF_R    I38 @SCM_LIB.SCM(SCH_1):PAGE31

 U21 IDTQS3VH257PAG_SMLF-IDTQS3VH25A
     4 SPI_PCH_MUXED_IO2 @SCM_LIB.SCM(SCH_1):SPI_PCH_MUXED_IO2   I296 @SCM_LIB.SCM(SCH_1):PAGE44
     7 SPI_PCH_MUXED_IO1 @SCM_LIB.SCM(SCH_1):SPI_PCH_MUXED_IO1   I296 @SCM_LIB.SCM(SCH_1):PAGE44
     9 SPI_PCH_MUXED_CS0_N @SCM_LIB.SCM(SCH_1):SPI_PCH_MUXED_CS0_N   I296 @SCM_LIB.SCM(SCH_1):PAGE44
    12 TP_BIOS_MUX1_PIN12 @SCM_LIB.SCM(SCH_1):TP_BIOS_MUX1_PIN12   I296 @SCM_LIB.SCM(SCH_1):PAGE44
     1 FM_BMC_BIOS_MUX_CS_SPI_R_SEL_0 @SCM_LIB.SCM(SCH_1):FM_BMC_BIOS_MUX_CS_SPI_R_SEL_0   I296 @SCM_LIB.SCM(SCH_1):PAGE44
    15 PD_BIOS_MUX_EN_N @SCM_LIB.SCM(SCH_1):PD_BIOS_MUX_EN_N   I296 @SCM_LIB.SCM(SCH_1):PAGE44
     2 SPI_SYS_MUX_WP_IO2 @SCM_LIB.SCM(SCH_1):SPI_SYS_MUX_WP_IO2   I296 @SCM_LIB.SCM(SCH_1):PAGE44
     3 SPI_BMC_BIOS_ROM_R_IO2 @SCM_LIB.SCM(SCH_1):SPI_BMC_BIOS_ROM_R_IO2   I296 @SCM_LIB.SCM(SCH_1):PAGE44
     6 SPI_BMC_BIOS_ROM_R_MISO @SCM_LIB.SCM(SCH_1):SPI_BMC_BIOS_ROM_R_MISO   I296 @SCM_LIB.SCM(SCH_1):PAGE44
     5 SPI_SYS_MUX_MISO @SCM_LIB.SCM(SCH_1):SPI_SYS_MUX_MISO   I296 @SCM_LIB.SCM(SCH_1):PAGE44
    10 SPI_BMC_BIOS_SOURCE_CS0_N @SCM_LIB.SCM(SCH_1):SPI_BMC_BIOS_SOURCE_CS0_N   I296 @SCM_LIB.SCM(SCH_1):PAGE44
    11 SPI_PCH_SECURE_CS0_N @SCM_LIB.SCM(SCH_1):SPI_PCH_SECURE_CS0_N   I296 @SCM_LIB.SCM(SCH_1):PAGE44
    14 TP_BIOS_MUX1_PIN14 @SCM_LIB.SCM(SCH_1):TP_BIOS_MUX1_PIN14   I296 @SCM_LIB.SCM(SCH_1):PAGE44
    13 TP_BIOS_MUX1_PIN13 @SCM_LIB.SCM(SCH_1):TP_BIOS_MUX1_PIN13   I296 @SCM_LIB.SCM(SCH_1):PAGE44
     8    GND @SCM_LIB.SCM(SCH_1):GND   I296 @SCM_LIB.SCM(SCH_1):PAGE44
    16 P3V3_AUX @SCM_LIB.SCM(SCH_1):P3V3_AUX   I296 @SCM_LIB.SCM(SCH_1):PAGE44

 U22 PI3PCIE3212ZBEX-PI3PCIE3212ZBEA
    10 P3V3_AUX @SCM_LIB.SCM(SCH_1):P3V3_AUX   I206 @SCM_LIB.SCM(SCH_1):PAGE29
     6 P3V3_AUX @SCM_LIB.SCM(SCH_1):P3V3_AUX   I206 @SCM_LIB.SCM(SCH_1):PAGE29
     1 P3V3_AUX @SCM_LIB.SCM(SCH_1):P3V3_AUX   I206 @SCM_LIB.SCM(SCH_1):PAGE29
     3 USB3_01_MUX_FB_TXP @SCM_LIB.SCM(SCH_1):USB3_01_MUX_FB_TXP   I206 @SCM_LIB.SCM(SCH_1):PAGE29
     4 USB3_01_MUX_FB_TXN @SCM_LIB.SCM(SCH_1):USB3_01_MUX_FB_TXN   I206 @SCM_LIB.SCM(SCH_1):PAGE29
     7 USB3_01_MUX_FB_RXP @SCM_LIB.SCM(SCH_1):USB3_01_MUX_FB_RXP   I206 @SCM_LIB.SCM(SCH_1):PAGE29
     8 USB3_01_MUX_FB_RXN @SCM_LIB.SCM(SCH_1):USB3_01_MUX_FB_RXN   I206 @SCM_LIB.SCM(SCH_1):PAGE29
     9 DEBUG_PORT_PRSNT @SCM_LIB.SCM(SCH_1):DEBUG_PORT_PRSNT   I206 @SCM_LIB.SCM(SCH_1):PAGE29
    19 USB3_01_TXP_C @SCM_LIB.SCM(SCH_1):USB3_01_TXP_C   I206 @SCM_LIB.SCM(SCH_1):PAGE29
    18 USB3_01_TXN_C @SCM_LIB.SCM(SCH_1):USB3_01_TXN_C   I206 @SCM_LIB.SCM(SCH_1):PAGE29
    17 USB3_FPNL_RXP @SCM_LIB.SCM(SCH_1):USB3_FPNL_RXP   I206 @SCM_LIB.SCM(SCH_1):PAGE29
    16 USB3_FPNL_RXN @SCM_LIB.SCM(SCH_1):USB3_FPNL_RXN   I206 @SCM_LIB.SCM(SCH_1):PAGE29
    15 DEBUG_PORT_UART_RX @SCM_LIB.SCM(SCH_1):DEBUG_PORT_UART_RX   I206 @SCM_LIB.SCM(SCH_1):PAGE29
    14 DEBUG_PORT_UART_TX @SCM_LIB.SCM(SCH_1):DEBUG_PORT_UART_TX   I206 @SCM_LIB.SCM(SCH_1):PAGE29
    13 SMB_DEBUG_AUX_LVC3_USB_R2_SDA @SCM_LIB.SCM(SCH_1):SMB_DEBUG_AUX_LVC3_USB_R2_SDA   I206 @SCM_LIB.SCM(SCH_1):PAGE29
    12 SMB_DEBUG_AUX_LVC3_USB_R2_SCL @SCM_LIB.SCM(SCH_1):SMB_DEBUG_AUX_LVC3_USB_R2_SCL   I206 @SCM_LIB.SCM(SCH_1):PAGE29
    TH     NC     NC   I206 @SCM_LIB.SCM(SCH_1):PAGE29
    11    GND @SCM_LIB.SCM(SCH_1):GND   I206 @SCM_LIB.SCM(SCH_1):PAGE29
     5    GND @SCM_LIB.SCM(SCH_1):GND   I206 @SCM_LIB.SCM(SCH_1):PAGE29
    20    GND @SCM_LIB.SCM(SCH_1):GND   I206 @SCM_LIB.SCM(SCH_1):PAGE29
     2 USB3_MUX_PD @SCM_LIB.SCM(SCH_1):USB3_MUX_PD   I206 @SCM_LIB.SCM(SCH_1):PAGE29

 U23 74LVC1G07W57-74LVC1G07W5-7,SMLA
     5 P3V3_AUX @SCM_LIB.SCM(SCH_1):P3V3_AUX   I180 @SCM_LIB.SCM(SCH_1):PAGE28
     2 DEBUG_PORT_PRSNT @SCM_LIB.SCM(SCH_1):DEBUG_PORT_PRSNT   I180 @SCM_LIB.SCM(SCH_1):PAGE28
     3    GND @SCM_LIB.SCM(SCH_1):GND   I180 @SCM_LIB.SCM(SCH_1):PAGE28
     4 DEBUG_PORT_PRSNT_BUF_R_EN @SCM_LIB.SCM(SCH_1):DEBUG_PORT_PRSNT_BUF_R_EN   I180 @SCM_LIB.SCM(SCH_1):PAGE28
     1     NC     NC   I180 @SCM_LIB.SCM(SCH_1):PAGE28

 U24 74LVC2G07DW7-74LVC2G07DW-7,SMLA
     1 UART_BMC_5_TXD_BUF1_R @SCM_LIB.SCM(SCH_1):UART_BMC_5_TXD_BUF1_R   I246 @SCM_LIB.SCM(SCH_1):PAGE30
     3 UART_BMC_5_RXD_BUF @SCM_LIB.SCM(SCH_1):UART_BMC_5_RXD_BUF   I246 @SCM_LIB.SCM(SCH_1):PAGE30
     6 UART_BMC_5_TXD_BUF @SCM_LIB.SCM(SCH_1):UART_BMC_5_TXD_BUF   I246 @SCM_LIB.SCM(SCH_1):PAGE30
     4 UART_BMC_5_RXD_BUF_R @SCM_LIB.SCM(SCH_1):UART_BMC_5_RXD_BUF_R   I246 @SCM_LIB.SCM(SCH_1):PAGE30
     2    GND @SCM_LIB.SCM(SCH_1):GND   I246 @SCM_LIB.SCM(SCH_1):PAGE30
     5 P3V3_AUX @SCM_LIB.SCM(SCH_1):P3V3_AUX   I246 @SCM_LIB.SCM(SCH_1):PAGE30

 U25 LCMXO3LF2100C5BG256C-LCMXO3LF-A
    D5 VCCIO0 @SCM_LIB.SCM(SCH_1):VCCIO0     I1 @SCM_LIB.SCM(SCH_1):PAGE34
   D12 VCCIO0 @SCM_LIB.SCM(SCH_1):VCCIO0     I1 @SCM_LIB.SCM(SCH_1):PAGE34
    G8 VCCIO0 @SCM_LIB.SCM(SCH_1):VCCIO0     I1 @SCM_LIB.SCM(SCH_1):PAGE34
    G9 VCCIO0 @SCM_LIB.SCM(SCH_1):VCCIO0     I1 @SCM_LIB.SCM(SCH_1):PAGE34
    C4 FM_TPM_PRSNT_0_R_N @SCM_LIB.SCM(SCH_1):FM_TPM_PRSNT_0_R_N     I1 @SCM_LIB.SCM(SCH_1):PAGE34
    B5 FM_TPM_PRSNT_1_R_N @SCM_LIB.SCM(SCH_1):FM_TPM_PRSNT_1_R_N     I1 @SCM_LIB.SCM(SCH_1):PAGE34
    B3 IRQ_BMC_CPU_NMI_R @SCM_LIB.SCM(SCH_1):IRQ_BMC_CPU_NMI_R     I1 @SCM_LIB.SCM(SCH_1):PAGE34
    A4 RST_PLTRST_R1_N @SCM_LIB.SCM(SCH_1):RST_PLTRST_R1_N     I1 @SCM_LIB.SCM(SCH_1):PAGE34
    C5 PWRGD_PSU_AC_PWROK_PLD @SCM_LIB.SCM(SCH_1):PWRGD_PSU_AC_PWROK_PLD     I1 @SCM_LIB.SCM(SCH_1):PAGE34
    A5 RST_RSMRST_N @SCM_LIB.SCM(SCH_1):RST_RSMRST_N     I1 @SCM_LIB.SCM(SCH_1):PAGE34
    B6 FM_JTAG_BMC_MUX_SEL_R2 @SCM_LIB.SCM(SCH_1):FM_JTAG_BMC_MUX_SEL_R2     I1 @SCM_LIB.SCM(SCH_1):PAGE34
    A3 BSM_PRSNT_R1_N @SCM_LIB.SCM(SCH_1):BSM_PRSNT_R1_N     I1 @SCM_LIB.SCM(SCH_1):PAGE34
    B4 RST_PCA9548_SENSOR_N @SCM_LIB.SCM(SCH_1):RST_PCA9548_SENSOR_N     I1 @SCM_LIB.SCM(SCH_1):PAGE34
    D6 FM_BMC_DBP_PRESENT_N @SCM_LIB.SCM(SCH_1):FM_BMC_DBP_PRESENT_N     I1 @SCM_LIB.SCM(SCH_1):PAGE34
    E7 PWRGD_PCH_PWROK @SCM_LIB.SCM(SCH_1):PWRGD_PCH_PWROK     I1 @SCM_LIB.SCM(SCH_1):PAGE34
    C6 JTAG_SCM_PLD_TDO @SCM_LIB.SCM(SCH_1):JTAG_SCM_PLD_TDO     I1 @SCM_LIB.SCM(SCH_1):PAGE34
    A6 JTAG_SCM_PLD_TDI @SCM_LIB.SCM(SCH_1):JTAG_SCM_PLD_TDI     I1 @SCM_LIB.SCM(SCH_1):PAGE34
    B7 IRQ_UV_DETECT_N @SCM_LIB.SCM(SCH_1):IRQ_UV_DETECT_N     I1 @SCM_LIB.SCM(SCH_1):PAGE34
    C7 RST_BMC_RSTBTN_OUT_N @SCM_LIB.SCM(SCH_1):RST_BMC_RSTBTN_OUT_N     I1 @SCM_LIB.SCM(SCH_1):PAGE34
    E6 BMC_CPLD_GPIO_2_R2 @SCM_LIB.SCM(SCH_1):BMC_CPLD_GPIO_2_R2     I1 @SCM_LIB.SCM(SCH_1):PAGE34
    D7 FM_ME_BT_DONE @SCM_LIB.SCM(SCH_1):FM_ME_BT_DONE     I1 @SCM_LIB.SCM(SCH_1):PAGE34
    F7 FM_PCIE_M2_SSD0_PRSNT_N @SCM_LIB.SCM(SCH_1):FM_PCIE_M2_SSD0_PRSNT_N     I1 @SCM_LIB.SCM(SCH_1):PAGE34
    E8 FM_BIOS_POST_CMPLT_BMC_N @SCM_LIB.SCM(SCH_1):FM_BIOS_POST_CMPLT_BMC_N     I1 @SCM_LIB.SCM(SCH_1):PAGE34
    A7 JTAG_SCM_PLD_TCK @SCM_LIB.SCM(SCH_1):JTAG_SCM_PLD_TCK     I1 @SCM_LIB.SCM(SCH_1):PAGE34
    B8 JTAG_SCM_PLD_TMS @SCM_LIB.SCM(SCH_1):JTAG_SCM_PLD_TMS     I1 @SCM_LIB.SCM(SCH_1):PAGE34
    C8 CLK_25M_OSC_FPGA @SCM_LIB.SCM(SCH_1):CLK_25M_OSC_FPGA     I1 @SCM_LIB.SCM(SCH_1):PAGE34
    A8 IRQ_BMC_PCH_NMI_R_N @SCM_LIB.SCM(SCH_1):IRQ_BMC_PCH_NMI_R_N     I1 @SCM_LIB.SCM(SCH_1):PAGE34
    D8 FM_PCH_BMC_THERMTRIP_N @SCM_LIB.SCM(SCH_1):FM_PCH_BMC_THERMTRIP_N     I1 @SCM_LIB.SCM(SCH_1):PAGE34
    E9 H_CPU1_PROCHOT_LVC1_R_N @SCM_LIB.SCM(SCH_1):H_CPU1_PROCHOT_LVC1_R_N     I1 @SCM_LIB.SCM(SCH_1):PAGE34
    D9     NC     NC     I1 @SCM_LIB.SCM(SCH_1):PAGE34
    A9 SMB_BMC_MM16_R3_SCL @SCM_LIB.SCM(SCH_1):SMB_BMC_MM16_R3_SCL     I1 @SCM_LIB.SCM(SCH_1):PAGE34
    C9 SMB_BMC_MM16_R3_SDA @SCM_LIB.SCM(SCH_1):SMB_BMC_MM16_R3_SDA     I1 @SCM_LIB.SCM(SCH_1):PAGE34
    B9 IRQ_PCH_SCI_WHEA_N @SCM_LIB.SCM(SCH_1):IRQ_PCH_SCI_WHEA_N     I1 @SCM_LIB.SCM(SCH_1):PAGE34
   A10     NC     NC     I1 @SCM_LIB.SCM(SCH_1):PAGE34
    F9     NC     NC     I1 @SCM_LIB.SCM(SCH_1):PAGE34
   E11 TP_PLD_19D @SCM_LIB.SCM(SCH_1):TP_PLD_19D     I1 @SCM_LIB.SCM(SCH_1):PAGE34
   D10     NC     NC     I1 @SCM_LIB.SCM(SCH_1):PAGE34
   E10 FM_CPU_MSMI_CATERR_LVT3_PLD_N @SCM_LIB.SCM(SCH_1):FM_CPU_MSMI_CATERR_LVT3_PLD_N     I1 @SCM_LIB.SCM(SCH_1):PAGE34
   C10 JTAG_SCM_PLD_R_JTAGEN @SCM_LIB.SCM(SCH_1):JTAG_SCM_PLD_R_JTAGEN     I1 @SCM_LIB.SCM(SCH_1):PAGE34
   B10 PU_PT20D @SCM_LIB.SCM(SCH_1):PU_PT20D     I1 @SCM_LIB.SCM(SCH_1):PAGE34
   A11 RST_EXTRST_R_N @SCM_LIB.SCM(SCH_1):RST_EXTRST_R_N     I1 @SCM_LIB.SCM(SCH_1):PAGE34
   C11 PWRGD_CPUPWRGD_LVC1 @SCM_LIB.SCM(SCH_1):PWRGD_CPUPWRGD_LVC1     I1 @SCM_LIB.SCM(SCH_1):PAGE34
   F10 IRQ_CPU0_VRHOT_N @SCM_LIB.SCM(SCH_1):IRQ_CPU0_VRHOT_N     I1 @SCM_LIB.SCM(SCH_1):PAGE34
   D11 IRQ_CPU1_VRHOT_N @SCM_LIB.SCM(SCH_1):IRQ_CPU1_VRHOT_N     I1 @SCM_LIB.SCM(SCH_1):PAGE34
   B11 IRQ_OC_DETECT_N @SCM_LIB.SCM(SCH_1):IRQ_OC_DETECT_N     I1 @SCM_LIB.SCM(SCH_1):PAGE34
   A12 FM_ADR_COMPLETE @SCM_LIB.SCM(SCH_1):FM_ADR_COMPLETE     I1 @SCM_LIB.SCM(SCH_1):PAGE34
   B13 IRQ_OC_DETECT_EN_N @SCM_LIB.SCM(SCH_1):IRQ_OC_DETECT_EN_N     I1 @SCM_LIB.SCM(SCH_1):PAGE34
   A14 SGPIO_CLK_PLD_0 @SCM_LIB.SCM(SCH_1):SGPIO_CLK_PLD_0     I1 @SCM_LIB.SCM(SCH_1):PAGE34
   C12 SGPIO_PLD_DO_0 @SCM_LIB.SCM(SCH_1):SGPIO_PLD_DO_0     I1 @SCM_LIB.SCM(SCH_1):PAGE34
   B12 SGPIO_PLD_LD_0 @SCM_LIB.SCM(SCH_1):SGPIO_PLD_LD_0     I1 @SCM_LIB.SCM(SCH_1):PAGE34
   B14 SGPIO_PLD_DI_0 @SCM_LIB.SCM(SCH_1):SGPIO_PLD_DI_0     I1 @SCM_LIB.SCM(SCH_1):PAGE34
   A15 FM_THERMTRIP_DLY_LVC1_R_N @SCM_LIB.SCM(SCH_1):FM_THERMTRIP_DLY_LVC1_R_N     I1 @SCM_LIB.SCM(SCH_1):PAGE34
   A13 PU_FPGA_NSTATUS @SCM_LIB.SCM(SCH_1):PU_FPGA_NSTATUS     I1 @SCM_LIB.SCM(SCH_1):PAGE34
   C13 PU_FPGA_CONFIG_DONE @SCM_LIB.SCM(SCH_1):PU_FPGA_CONFIG_DONE     I1 @SCM_LIB.SCM(SCH_1):PAGE34
    F8 RST_SRST_PLD_BMC_R2_N @SCM_LIB.SCM(SCH_1):RST_SRST_PLD_BMC_R2_N     I1 @SCM_LIB.SCM(SCH_1):PAGE34
   J11     NC     NC     I1 @SCM_LIB.SCM(SCH_1):PAGE35
   L12 FM_BMC_EN_DET_R @SCM_LIB.SCM(SCH_1):FM_BMC_EN_DET_R     I1 @SCM_LIB.SCM(SCH_1):PAGE35
   G16 BMC_CPLD_GPIO_12_R2 @SCM_LIB.SCM(SCH_1):BMC_CPLD_GPIO_12_R2     I1 @SCM_LIB.SCM(SCH_1):PAGE35
   H15 BMC_CPLD_GPIO_13_R2 @SCM_LIB.SCM(SCH_1):BMC_CPLD_GPIO_13_R2     I1 @SCM_LIB.SCM(SCH_1):PAGE35
   K11 FM_PCHHOT_R_N @SCM_LIB.SCM(SCH_1):FM_PCHHOT_R_N     I1 @SCM_LIB.SCM(SCH_1):PAGE35
   L13 FM_BMC_ONCTL_R_N @SCM_LIB.SCM(SCH_1):FM_BMC_ONCTL_R_N     I1 @SCM_LIB.SCM(SCH_1):PAGE35
   H14     NC     NC     I1 @SCM_LIB.SCM(SCH_1):PAGE35
   H16     NC     NC     I1 @SCM_LIB.SCM(SCH_1):PAGE35
   N15 AC_PWR_BTN_R2_N @SCM_LIB.SCM(SCH_1):AC_PWR_BTN_R2_N     I1 @SCM_LIB.SCM(SCH_1):PAGE35
   P16     NC     NC     I1 @SCM_LIB.SCM(SCH_1):PAGE35
   N16 PWRGD_P3V3_AUX_R1 @SCM_LIB.SCM(SCH_1):PWRGD_P3V3_AUX_R1     I1 @SCM_LIB.SCM(SCH_1):PAGE35
   N14 PWRGD_P2V5_AUX_R1 @SCM_LIB.SCM(SCH_1):PWRGD_P2V5_AUX_R1     I1 @SCM_LIB.SCM(SCH_1):PAGE35
   P15     NC     NC     I1 @SCM_LIB.SCM(SCH_1):PAGE35
   R16 SMB_BMC_ALERT16_R2_N @SCM_LIB.SCM(SCH_1):SMB_BMC_ALERT16_R2_N     I1 @SCM_LIB.SCM(SCH_1):PAGE35
   M14 PWR_LED_CPLD @SCM_LIB.SCM(SCH_1):PWR_LED_CPLD     I1 @SCM_LIB.SCM(SCH_1):PAGE35
   M15 PWRGD_P5V_AUX_R1 @SCM_LIB.SCM(SCH_1):PWRGD_P5V_AUX_R1     I1 @SCM_LIB.SCM(SCH_1):PAGE35
   L15     NC     NC     I1 @SCM_LIB.SCM(SCH_1):PAGE35
   M16     NC     NC     I1 @SCM_LIB.SCM(SCH_1):PAGE35
   K13 FM_BMC_READY_PLD_N @SCM_LIB.SCM(SCH_1):FM_BMC_READY_PLD_N     I1 @SCM_LIB.SCM(SCH_1):PAGE35
   K12 FM_BIOS_DEBUG_EN_N @SCM_LIB.SCM(SCH_1):FM_BIOS_DEBUG_EN_N     I1 @SCM_LIB.SCM(SCH_1):PAGE35
   L16 USB_OC0_REAR_R_N @SCM_LIB.SCM(SCH_1):USB_OC0_REAR_R_N     I1 @SCM_LIB.SCM(SCH_1):PAGE35
   L14 SMB_BMC_ALERT12_N @SCM_LIB.SCM(SCH_1):SMB_BMC_ALERT12_N     I1 @SCM_LIB.SCM(SCH_1):PAGE35
   K14 FM_PWR_R_BTN @SCM_LIB.SCM(SCH_1):FM_PWR_R_BTN     I1 @SCM_LIB.SCM(SCH_1):PAGE35
   K15 PWRGD_SYS_PWROK_PLD @SCM_LIB.SCM(SCH_1):PWRGD_SYS_PWROK_PLD     I1 @SCM_LIB.SCM(SCH_1):PAGE35
   J15 RST_BMC_HW_R @SCM_LIB.SCM(SCH_1):RST_BMC_HW_R     I1 @SCM_LIB.SCM(SCH_1):PAGE35
   K16     NC     NC     I1 @SCM_LIB.SCM(SCH_1):PAGE35
   D14 H_CPU0_MEMTRIP_LVC1_N @SCM_LIB.SCM(SCH_1):H_CPU0_MEMTRIP_LVC1_N     I1 @SCM_LIB.SCM(SCH_1):PAGE35
   E15 FM_SPD_REMOTE_EN_R @SCM_LIB.SCM(SCH_1):FM_SPD_REMOTE_EN_R     I1 @SCM_LIB.SCM(SCH_1):PAGE35
   C15 VOL_SEN_ALERT_R @SCM_LIB.SCM(SCH_1):VOL_SEN_ALERT_R     I1 @SCM_LIB.SCM(SCH_1):PAGE35
   B16 FM_PECI_SEL_N @SCM_LIB.SCM(SCH_1):FM_PECI_SEL_N     I1 @SCM_LIB.SCM(SCH_1):PAGE35
   D16 H_CPU1_MEMTRIP_LVC1_N @SCM_LIB.SCM(SCH_1):H_CPU1_MEMTRIP_LVC1_N     I1 @SCM_LIB.SCM(SCH_1):PAGE35
   E14 IRQ_SGPIO_R_N @SCM_LIB.SCM(SCH_1):IRQ_SGPIO_R_N     I1 @SCM_LIB.SCM(SCH_1):PAGE35
   C16 SMB_BMC_ALERT3_R1_N @SCM_LIB.SCM(SCH_1):SMB_BMC_ALERT3_R1_N     I1 @SCM_LIB.SCM(SCH_1):PAGE35
   D15 SMB_BMC_ALERT4_R1_N @SCM_LIB.SCM(SCH_1):SMB_BMC_ALERT4_R1_N     I1 @SCM_LIB.SCM(SCH_1):PAGE35
   F13 SMB_BMC_ALERT9_R1_N @SCM_LIB.SCM(SCH_1):SMB_BMC_ALERT9_R1_N     I1 @SCM_LIB.SCM(SCH_1):PAGE35
   G12 SMB_BMC_ALERT10_R1_N @SCM_LIB.SCM(SCH_1):SMB_BMC_ALERT10_R1_N     I1 @SCM_LIB.SCM(SCH_1):PAGE35
   F12 TP_PLD_L3 @SCM_LIB.SCM(SCH_1):TP_PLD_L3     I1 @SCM_LIB.SCM(SCH_1):PAGE35
   G13 RST_BMC_SELF_HW_R2 @SCM_LIB.SCM(SCH_1):RST_BMC_SELF_HW_R2     I1 @SCM_LIB.SCM(SCH_1):PAGE35
   E16 RST_SGPIO_RESET_R_N @SCM_LIB.SCM(SCH_1):RST_SGPIO_RESET_R_N     I1 @SCM_LIB.SCM(SCH_1):PAGE35
   F15 BMC_CPLD_GPIO_7_R2 @SCM_LIB.SCM(SCH_1):BMC_CPLD_GPIO_7_R2     I1 @SCM_LIB.SCM(SCH_1):PAGE35
   G11 FM_SLPS3_GF_R_N @SCM_LIB.SCM(SCH_1):FM_SLPS3_GF_R_N     I1 @SCM_LIB.SCM(SCH_1):PAGE35
   H12 RST_ROT_CPU_R_N @SCM_LIB.SCM(SCH_1):RST_ROT_CPU_R_N     I1 @SCM_LIB.SCM(SCH_1):PAGE35
   F14 BMC_CPLD_GPIO_8_R2 @SCM_LIB.SCM(SCH_1):BMC_CPLD_GPIO_8_R2     I1 @SCM_LIB.SCM(SCH_1):PAGE35
   F16     NC     NC     I1 @SCM_LIB.SCM(SCH_1):PAGE35
   H13 FM_ESPI_PLD_R_EN @SCM_LIB.SCM(SCH_1):FM_ESPI_PLD_R_EN     I1 @SCM_LIB.SCM(SCH_1):PAGE35
   J12 FM_THROTTLE_R_N @SCM_LIB.SCM(SCH_1):FM_THROTTLE_R_N     I1 @SCM_LIB.SCM(SCH_1):PAGE35
   J16 FM_PMBUS_ALERT_EN @SCM_LIB.SCM(SCH_1):FM_PMBUS_ALERT_EN     I1 @SCM_LIB.SCM(SCH_1):PAGE35
   J14 H_CPU0_PROCHOT_LVC1_R_N @SCM_LIB.SCM(SCH_1):H_CPU0_PROCHOT_LVC1_R_N     I1 @SCM_LIB.SCM(SCH_1):PAGE35
   H11 RST_MB_STBY_R_N @SCM_LIB.SCM(SCH_1):RST_MB_STBY_R_N     I1 @SCM_LIB.SCM(SCH_1):PAGE35
   J13 FM_ADR_TRIGGER_N @SCM_LIB.SCM(SCH_1):FM_ADR_TRIGGER_N     I1 @SCM_LIB.SCM(SCH_1):PAGE35
   G15     NC     NC     I1 @SCM_LIB.SCM(SCH_1):PAGE35
   G14     NC     NC     I1 @SCM_LIB.SCM(SCH_1):PAGE35
   M13 VCCIO1 @SCM_LIB.SCM(SCH_1):VCCIO1     I1 @SCM_LIB.SCM(SCH_1):PAGE35
   J10 VCCIO1 @SCM_LIB.SCM(SCH_1):VCCIO1     I1 @SCM_LIB.SCM(SCH_1):PAGE35
   E13 VCCIO1 @SCM_LIB.SCM(SCH_1):VCCIO1     I1 @SCM_LIB.SCM(SCH_1):PAGE35
   H10 VCCIO1 @SCM_LIB.SCM(SCH_1):VCCIO1     I1 @SCM_LIB.SCM(SCH_1):PAGE35
    M7 CLK_GEN2_BMC_RC_OE_N @SCM_LIB.SCM(SCH_1):CLK_GEN2_BMC_RC_OE_N     I1 @SCM_LIB.SCM(SCH_1):PAGE36
    N7 IRQ_SML0_ALERT_R_N @SCM_LIB.SCM(SCH_1):IRQ_SML0_ALERT_R_N     I1 @SCM_LIB.SCM(SCH_1):PAGE36
    M6 BMC_MONITER @SCM_LIB.SCM(SCH_1):BMC_MONITER     I1 @SCM_LIB.SCM(SCH_1):PAGE36
    L8 FM_PFR_DSW_PWROK_N @SCM_LIB.SCM(SCH_1):FM_PFR_DSW_PWROK_N     I1 @SCM_LIB.SCM(SCH_1):PAGE36
    T7 RST_PFR_OVR_RTC_R @SCM_LIB.SCM(SCH_1):RST_PFR_OVR_RTC_R     I1 @SCM_LIB.SCM(SCH_1):PAGE36
    R8 NC_FM_PFR_UPDATE_N @SCM_LIB.SCM(SCH_1):NC_FM_PFR_UPDATE_N     I1 @SCM_LIB.SCM(SCH_1):PAGE36
    P8 GPU_FPGA_RST_N @SCM_LIB.SCM(SCH_1):GPU_FPGA_RST_N     I1 @SCM_LIB.SCM(SCH_1):PAGE36
    T8 FM_JTAG_TCK_MUX_BMC_SEL @SCM_LIB.SCM(SCH_1):FM_JTAG_TCK_MUX_BMC_SEL     I1 @SCM_LIB.SCM(SCH_1):PAGE36
    N8 CLK_BUF1_GPU_FPGA_OE_R_N @SCM_LIB.SCM(SCH_1):CLK_BUF1_GPU_FPGA_OE_R_N     I1 @SCM_LIB.SCM(SCH_1):PAGE36
    L9 FM_BMC_CPU_FBRK_OUT_R_N @SCM_LIB.SCM(SCH_1):FM_BMC_CPU_FBRK_OUT_R_N     I1 @SCM_LIB.SCM(SCH_1):PAGE36
    M8 PWRGD_P1V8_AUX_R1 @SCM_LIB.SCM(SCH_1):PWRGD_P1V8_AUX_R1     I1 @SCM_LIB.SCM(SCH_1):PAGE36
    N9 PWRGD_P3V3_RGM_R1 @SCM_LIB.SCM(SCH_1):PWRGD_P3V3_RGM_R1     I1 @SCM_LIB.SCM(SCH_1):PAGE36
    T9 PWRGD_P1V2_AUX_R1 @SCM_LIB.SCM(SCH_1):PWRGD_P1V2_AUX_R1     I1 @SCM_LIB.SCM(SCH_1):PAGE36
    P9 PWRGD_P1V0_AUX_R1 @SCM_LIB.SCM(SCH_1):PWRGD_P1V0_AUX_R1     I1 @SCM_LIB.SCM(SCH_1):PAGE36
    R9     NC     NC     I1 @SCM_LIB.SCM(SCH_1):PAGE36
   T10     NC     NC     I1 @SCM_LIB.SCM(SCH_1):PAGE36
    M9 FM_UARTSW_LSB_R_N @SCM_LIB.SCM(SCH_1):FM_UARTSW_LSB_R_N     I1 @SCM_LIB.SCM(SCH_1):PAGE36
   L10 FM_UARTSW_MSB_R_N @SCM_LIB.SCM(SCH_1):FM_UARTSW_MSB_R_N     I1 @SCM_LIB.SCM(SCH_1):PAGE36
   N10     NC     NC     I1 @SCM_LIB.SCM(SCH_1):PAGE36
   M11     NC     NC     I1 @SCM_LIB.SCM(SCH_1):PAGE36
   P10     NC     NC     I1 @SCM_LIB.SCM(SCH_1):PAGE36
   R10     NC     NC     I1 @SCM_LIB.SCM(SCH_1):PAGE36
   T11     NC     NC     I1 @SCM_LIB.SCM(SCH_1):PAGE36
   P11     NC     NC     I1 @SCM_LIB.SCM(SCH_1):PAGE36
   M10 PU_FPGA_NCONFIG @SCM_LIB.SCM(SCH_1):PU_FPGA_NCONFIG     I1 @SCM_LIB.SCM(SCH_1):PAGE36
   N11     NC     NC     I1 @SCM_LIB.SCM(SCH_1):PAGE36
   R13     NC     NC     I1 @SCM_LIB.SCM(SCH_1):PAGE36
   T14     NC     NC     I1 @SCM_LIB.SCM(SCH_1):PAGE36
   R11     NC     NC     I1 @SCM_LIB.SCM(SCH_1):PAGE36
   T12     NC     NC     I1 @SCM_LIB.SCM(SCH_1):PAGE36
   P12     NC     NC     I1 @SCM_LIB.SCM(SCH_1):PAGE36
   T13     NC     NC     I1 @SCM_LIB.SCM(SCH_1):PAGE36
   R12 PU_PB25A @SCM_LIB.SCM(SCH_1):PU_PB25A     I1 @SCM_LIB.SCM(SCH_1):PAGE36
   P13     NC     NC     I1 @SCM_LIB.SCM(SCH_1):PAGE36
   T15 SMB_BMC_MM16_R4_SCL @SCM_LIB.SCM(SCH_1):SMB_BMC_MM16_R4_SCL     I1 @SCM_LIB.SCM(SCH_1):PAGE36
   R14 SMB_BMC_MM16_R4_SDA @SCM_LIB.SCM(SCH_1):SMB_BMC_MM16_R4_SDA     I1 @SCM_LIB.SCM(SCH_1):PAGE36
    P4 FM_P12V_HSC_ENABLE_R2 @SCM_LIB.SCM(SCH_1):FM_P12V_HSC_ENABLE_R2     I1 @SCM_LIB.SCM(SCH_1):PAGE36
    T4     NC     NC     I1 @SCM_LIB.SCM(SCH_1):PAGE36
    T2 FM_SOL_UART_CH_SEL_R2 @SCM_LIB.SCM(SCH_1):FM_SOL_UART_CH_SEL_R2     I1 @SCM_LIB.SCM(SCH_1):PAGE36
    R3 PWRGD_DSW_PWROK_R2 @SCM_LIB.SCM(SCH_1):PWRGD_DSW_PWROK_R2     I1 @SCM_LIB.SCM(SCH_1):PAGE36
    R5 FM_DEBUG_PORT_R2_PRSNT_N @SCM_LIB.SCM(SCH_1):FM_DEBUG_PORT_R2_PRSNT_N     I1 @SCM_LIB.SCM(SCH_1):PAGE36
    P5 TP_PLD_C13 @SCM_LIB.SCM(SCH_1):TP_PLD_C13     I1 @SCM_LIB.SCM(SCH_1):PAGE36
    T3 RST_WDTRST_PLD_R2_N @SCM_LIB.SCM(SCH_1):RST_WDTRST_PLD_R2_N     I1 @SCM_LIB.SCM(SCH_1):PAGE36
    R4 FM_BMC_SUSACK_R2_N @SCM_LIB.SCM(SCH_1):FM_BMC_SUSACK_R2_N     I1 @SCM_LIB.SCM(SCH_1):PAGE36
    T5 IRQ_PCH_TPM_SPI_R2_N @SCM_LIB.SCM(SCH_1):IRQ_PCH_TPM_SPI_R2_N     I1 @SCM_LIB.SCM(SCH_1):PAGE36
    R6 FM_BMC_CRASHLOG_TRIG_R2_N @SCM_LIB.SCM(SCH_1):FM_BMC_CRASHLOG_TRIG_R2_N     I1 @SCM_LIB.SCM(SCH_1):PAGE36
    N6 FM_BMC_DEBUG_SW_R2_N @SCM_LIB.SCM(SCH_1):FM_BMC_DEBUG_SW_R2_N     I1 @SCM_LIB.SCM(SCH_1):PAGE36
    L7 NC_FM_PFR_NO_SERVICE_ACT_N @SCM_LIB.SCM(SCH_1):NC_FM_PFR_NO_SERVICE_ACT_N     I1 @SCM_LIB.SCM(SCH_1):PAGE36
    P6 FM_HDD_LED_N @SCM_LIB.SCM(SCH_1):FM_HDD_LED_N     I1 @SCM_LIB.SCM(SCH_1):PAGE36
    T6 FM_PCH_BEEP_LED @SCM_LIB.SCM(SCH_1):FM_PCH_BEEP_LED     I1 @SCM_LIB.SCM(SCH_1):PAGE36
    R7 GPU_NVS_PWR_BRAKE_R_N @SCM_LIB.SCM(SCH_1):GPU_NVS_PWR_BRAKE_R_N     I1 @SCM_LIB.SCM(SCH_1):PAGE36
    P7 GPU_WP_HW_CTRL_R_N @SCM_LIB.SCM(SCH_1):GPU_WP_HW_CTRL_R_N     I1 @SCM_LIB.SCM(SCH_1):PAGE36
    K8 VCCIO2 @SCM_LIB.SCM(SCH_1):VCCIO2     I1 @SCM_LIB.SCM(SCH_1):PAGE36
    K9 VCCIO2 @SCM_LIB.SCM(SCH_1):VCCIO2     I1 @SCM_LIB.SCM(SCH_1):PAGE36
   N12 VCCIO2 @SCM_LIB.SCM(SCH_1):VCCIO2     I1 @SCM_LIB.SCM(SCH_1):PAGE36
    N5 VCCIO2 @SCM_LIB.SCM(SCH_1):VCCIO2     I1 @SCM_LIB.SCM(SCH_1):PAGE36
    L1     NC     NC     I1 @SCM_LIB.SCM(SCH_1):PAGE37
    L3     NC     NC     I1 @SCM_LIB.SCM(SCH_1):PAGE37
    K4     NC     NC     I1 @SCM_LIB.SCM(SCH_1):PAGE37
    L5     NC     NC     I1 @SCM_LIB.SCM(SCH_1):PAGE37
    K5     NC     NC     I1 @SCM_LIB.SCM(SCH_1):PAGE37
    L4     NC     NC     I1 @SCM_LIB.SCM(SCH_1):PAGE37
    L2     NC     NC     I1 @SCM_LIB.SCM(SCH_1):PAGE37
    M1     NC     NC     I1 @SCM_LIB.SCM(SCH_1):PAGE37
    M2     NC     NC     I1 @SCM_LIB.SCM(SCH_1):PAGE37
    N3     NC     NC     I1 @SCM_LIB.SCM(SCH_1):PAGE37
    R1     NC     NC     I1 @SCM_LIB.SCM(SCH_1):PAGE37
    P2     NC     NC     I1 @SCM_LIB.SCM(SCH_1):PAGE37
    M4 VCCIO3 @SCM_LIB.SCM(SCH_1):VCCIO3     I1 @SCM_LIB.SCM(SCH_1):PAGE37
    N2     NC     NC     I1 @SCM_LIB.SCM(SCH_1):PAGE37
    P1     NC     NC     I1 @SCM_LIB.SCM(SCH_1):PAGE37
    M3     NC     NC     I1 @SCM_LIB.SCM(SCH_1):PAGE37
    N1     NC     NC     I1 @SCM_LIB.SCM(SCH_1):PAGE37
    G1     NC     NC     I1 @SCM_LIB.SCM(SCH_1):PAGE38
    H2     NC     NC     I1 @SCM_LIB.SCM(SCH_1):PAGE38
    H4     NC     NC     I1 @SCM_LIB.SCM(SCH_1):PAGE38
    J6     NC     NC     I1 @SCM_LIB.SCM(SCH_1):PAGE38
    H3     NC     NC     I1 @SCM_LIB.SCM(SCH_1):PAGE38
    H1     NC     NC     I1 @SCM_LIB.SCM(SCH_1):PAGE38
    J1     NC     NC     I1 @SCM_LIB.SCM(SCH_1):PAGE38
    J3     NC     NC     I1 @SCM_LIB.SCM(SCH_1):PAGE38
    J5     NC     NC     I1 @SCM_LIB.SCM(SCH_1):PAGE38
    K6     NC     NC     I1 @SCM_LIB.SCM(SCH_1):PAGE38
    K3     NC     NC     I1 @SCM_LIB.SCM(SCH_1):PAGE38
    K2     NC     NC     I1 @SCM_LIB.SCM(SCH_1):PAGE38
    J2     NC     NC     I1 @SCM_LIB.SCM(SCH_1):PAGE38
    K1     NC     NC     I1 @SCM_LIB.SCM(SCH_1):PAGE38
    H5     NC     NC     I1 @SCM_LIB.SCM(SCH_1):PAGE38
    J4     NC     NC     I1 @SCM_LIB.SCM(SCH_1):PAGE38
    H7 VCCIO4 @SCM_LIB.SCM(SCH_1):VCCIO4     I1 @SCM_LIB.SCM(SCH_1):PAGE38
    J7 VCCIO4 @SCM_LIB.SCM(SCH_1):VCCIO4     I1 @SCM_LIB.SCM(SCH_1):PAGE38
    B1     NC     NC     I1 @SCM_LIB.SCM(SCH_1):PAGE39
    C2     NC     NC     I1 @SCM_LIB.SCM(SCH_1):PAGE39
    D3     NC     NC     I1 @SCM_LIB.SCM(SCH_1):PAGE39
    D1     NC     NC     I1 @SCM_LIB.SCM(SCH_1):PAGE39
    E2     NC     NC     I1 @SCM_LIB.SCM(SCH_1):PAGE39
    E3     NC     NC     I1 @SCM_LIB.SCM(SCH_1):PAGE39
    C1     NC     NC     I1 @SCM_LIB.SCM(SCH_1):PAGE39
    D2     NC     NC     I1 @SCM_LIB.SCM(SCH_1):PAGE39
    E1     NC     NC     I1 @SCM_LIB.SCM(SCH_1):PAGE39
    F2     NC     NC     I1 @SCM_LIB.SCM(SCH_1):PAGE39
    F4     NC     NC     I1 @SCM_LIB.SCM(SCH_1):PAGE39
    G6     NC     NC     I1 @SCM_LIB.SCM(SCH_1):PAGE39
    G2     NC     NC     I1 @SCM_LIB.SCM(SCH_1):PAGE39
    G3     NC     NC     I1 @SCM_LIB.SCM(SCH_1):PAGE39
    F5     NC     NC     I1 @SCM_LIB.SCM(SCH_1):PAGE39
    H6     NC     NC     I1 @SCM_LIB.SCM(SCH_1):PAGE39
    E4 VCCIO5 @SCM_LIB.SCM(SCH_1):VCCIO5     I1 @SCM_LIB.SCM(SCH_1):PAGE39
    G5     NC     NC     I1 @SCM_LIB.SCM(SCH_1):PAGE39
    G4     NC     NC     I1 @SCM_LIB.SCM(SCH_1):PAGE39
    F3     NC     NC     I1 @SCM_LIB.SCM(SCH_1):PAGE39
    F1     NC     NC     I1 @SCM_LIB.SCM(SCH_1):PAGE39
    B2    GND @SCM_LIB.SCM(SCH_1):GND     I1 @SCM_LIB.SCM(SCH_1):PAGE40
   B15    GND @SCM_LIB.SCM(SCH_1):GND     I1 @SCM_LIB.SCM(SCH_1):PAGE40
    C3    GND @SCM_LIB.SCM(SCH_1):GND     I1 @SCM_LIB.SCM(SCH_1):PAGE40
   C14    GND @SCM_LIB.SCM(SCH_1):GND     I1 @SCM_LIB.SCM(SCH_1):PAGE40
    D4    GND @SCM_LIB.SCM(SCH_1):GND     I1 @SCM_LIB.SCM(SCH_1):PAGE40
   D13    GND @SCM_LIB.SCM(SCH_1):GND     I1 @SCM_LIB.SCM(SCH_1):PAGE40
    E5    GND @SCM_LIB.SCM(SCH_1):GND     I1 @SCM_LIB.SCM(SCH_1):PAGE40
   E12    GND @SCM_LIB.SCM(SCH_1):GND     I1 @SCM_LIB.SCM(SCH_1):PAGE40
    F6    GND @SCM_LIB.SCM(SCH_1):GND     I1 @SCM_LIB.SCM(SCH_1):PAGE40
   F11    GND @SCM_LIB.SCM(SCH_1):GND     I1 @SCM_LIB.SCM(SCH_1):PAGE40
    H8    GND @SCM_LIB.SCM(SCH_1):GND     I1 @SCM_LIB.SCM(SCH_1):PAGE40
    H9    GND @SCM_LIB.SCM(SCH_1):GND     I1 @SCM_LIB.SCM(SCH_1):PAGE40
    J8    GND @SCM_LIB.SCM(SCH_1):GND     I1 @SCM_LIB.SCM(SCH_1):PAGE40
    J9    GND @SCM_LIB.SCM(SCH_1):GND     I1 @SCM_LIB.SCM(SCH_1):PAGE40
    L6    GND @SCM_LIB.SCM(SCH_1):GND     I1 @SCM_LIB.SCM(SCH_1):PAGE40
   L11    GND @SCM_LIB.SCM(SCH_1):GND     I1 @SCM_LIB.SCM(SCH_1):PAGE40
    M5    GND @SCM_LIB.SCM(SCH_1):GND     I1 @SCM_LIB.SCM(SCH_1):PAGE40
   M12    GND @SCM_LIB.SCM(SCH_1):GND     I1 @SCM_LIB.SCM(SCH_1):PAGE40
    N4    GND @SCM_LIB.SCM(SCH_1):GND     I1 @SCM_LIB.SCM(SCH_1):PAGE40
   N13    GND @SCM_LIB.SCM(SCH_1):GND     I1 @SCM_LIB.SCM(SCH_1):PAGE40
    P3    GND @SCM_LIB.SCM(SCH_1):GND     I1 @SCM_LIB.SCM(SCH_1):PAGE40
   P14    GND @SCM_LIB.SCM(SCH_1):GND     I1 @SCM_LIB.SCM(SCH_1):PAGE40
    R2    GND @SCM_LIB.SCM(SCH_1):GND     I1 @SCM_LIB.SCM(SCH_1):PAGE40
   R15    GND @SCM_LIB.SCM(SCH_1):GND     I1 @SCM_LIB.SCM(SCH_1):PAGE40
    A2     NC     NC     I1 @SCM_LIB.SCM(SCH_1):PAGE40
   T16 PVCCA_AUX_PLD @SCM_LIB.SCM(SCH_1):PVCCA_AUX_PLD     I1 @SCM_LIB.SCM(SCH_1):PAGE40
    T1 PVCCA_AUX_PLD @SCM_LIB.SCM(SCH_1):PVCCA_AUX_PLD     I1 @SCM_LIB.SCM(SCH_1):PAGE40
   K10 PVCCA_AUX_PLD @SCM_LIB.SCM(SCH_1):PVCCA_AUX_PLD     I1 @SCM_LIB.SCM(SCH_1):PAGE40
    K7 PVCCA_AUX_PLD @SCM_LIB.SCM(SCH_1):PVCCA_AUX_PLD     I1 @SCM_LIB.SCM(SCH_1):PAGE40
   G10 PVCCA_AUX_PLD @SCM_LIB.SCM(SCH_1):PVCCA_AUX_PLD     I1 @SCM_LIB.SCM(SCH_1):PAGE40
    G7 PVCCA_AUX_PLD @SCM_LIB.SCM(SCH_1):PVCCA_AUX_PLD     I1 @SCM_LIB.SCM(SCH_1):PAGE40
   A16 PVCCA_AUX_PLD @SCM_LIB.SCM(SCH_1):PVCCA_AUX_PLD     I1 @SCM_LIB.SCM(SCH_1):PAGE40
    A1 PVCCA_AUX_PLD @SCM_LIB.SCM(SCH_1):PVCCA_AUX_PLD     I1 @SCM_LIB.SCM(SCH_1):PAGE40

 U26 74HC1G126GW-74HC1G126GW,SMLF,IA
     2 V_VGAVS @SCM_LIB.SCM(SCH_1):V_VGAVS    I33 @SCM_LIB.SCM(SCH_1):PAGE23
     4 V_VGAVS_BUF_R @SCM_LIB.SCM(SCH_1):V_VGAVS_BUF_R    I33 @SCM_LIB.SCM(SCH_1):PAGE23
     5 BMC_DDC_BUF_PWR @SCM_LIB.SCM(SCH_1):BMC_DDC_BUF_PWR    I33 @SCM_LIB.SCM(SCH_1):PAGE23
     1 BMC_DDC_BUF_EN @SCM_LIB.SCM(SCH_1):BMC_DDC_BUF_EN    I33 @SCM_LIB.SCM(SCH_1):PAGE23
     3    GND @SCM_LIB.SCM(SCH_1):GND    I33 @SCM_LIB.SCM(SCH_1):PAGE23

 U27 DT1240E04LP7-DT1240E-04LP-7,SMA
     1 USB3_01_FB_TXP @SCM_LIB.SCM(SCH_1):USB3_01_FB_TXP   I211 @SCM_LIB.SCM(SCH_1):PAGE29
     3    GND @SCM_LIB.SCM(SCH_1):GND   I211 @SCM_LIB.SCM(SCH_1):PAGE29
     4 USB3_01_FB_RXP @SCM_LIB.SCM(SCH_1):USB3_01_FB_RXP   I211 @SCM_LIB.SCM(SCH_1):PAGE29
     6 USB3_01_FB_RXN @SCM_LIB.SCM(SCH_1):USB3_01_FB_RXN   I211 @SCM_LIB.SCM(SCH_1):PAGE29
     8    GND @SCM_LIB.SCM(SCH_1):GND   I211 @SCM_LIB.SCM(SCH_1):PAGE29
     9 USB3_01_FB_TXN @SCM_LIB.SCM(SCH_1):USB3_01_FB_TXN   I211 @SCM_LIB.SCM(SCH_1):PAGE29
    10 USB3_01_FB_TXP @SCM_LIB.SCM(SCH_1):USB3_01_FB_TXP   I211 @SCM_LIB.SCM(SCH_1):PAGE29
     2 USB3_01_FB_TXN @SCM_LIB.SCM(SCH_1):USB3_01_FB_TXN   I211 @SCM_LIB.SCM(SCH_1):PAGE29
     5 USB3_01_FB_RXN @SCM_LIB.SCM(SCH_1):USB3_01_FB_RXN   I211 @SCM_LIB.SCM(SCH_1):PAGE29
     7 USB3_01_FB_RXP @SCM_LIB.SCM(SCH_1):USB3_01_FB_RXP   I211 @SCM_LIB.SCM(SCH_1):PAGE29

 U28 74LVC1G66GV-74LVC1G66GV,SMLF,IA
     1 RMII_OCP_RCLKI @SCM_LIB.SCM(SCH_1):RMII_OCP_RCLKI   I435 @SCM_LIB.SCM(SCH_1):PAGE13
     2 RMII_OCP_RCLKI_ISO @SCM_LIB.SCM(SCH_1):RMII_OCP_RCLKI_ISO   I435 @SCM_LIB.SCM(SCH_1):PAGE13
     3    GND @SCM_LIB.SCM(SCH_1):GND   I435 @SCM_LIB.SCM(SCH_1):PAGE13
     4 PWRGD_P1V0_AUX_DELAY_R @SCM_LIB.SCM(SCH_1):PWRGD_P1V0_AUX_DELAY_R   I435 @SCM_LIB.SCM(SCH_1):PAGE13
     5 P3V3_LDO @SCM_LIB.SCM(SCH_1):P3V3_LDO   I435 @SCM_LIB.SCM(SCH_1):PAGE13

 U29 74HC1G126GW-74HC1G126GW,SMLF,IA
     2 SPA_SOUT_SW_DBG @SCM_LIB.SCM(SCH_1):SPA_SOUT_SW_DBG   I174 @SCM_LIB.SCM(SCH_1):PAGE29
     4 DEBUG_PORT_UART_TX @SCM_LIB.SCM(SCH_1):DEBUG_PORT_UART_TX   I174 @SCM_LIB.SCM(SCH_1):PAGE29
     5 P3V3_AUX @SCM_LIB.SCM(SCH_1):P3V3_AUX   I174 @SCM_LIB.SCM(SCH_1):PAGE29
     1 DEBUG_PORT_PRSNT @SCM_LIB.SCM(SCH_1):DEBUG_PORT_PRSNT   I174 @SCM_LIB.SCM(SCH_1):PAGE29
     3    GND @SCM_LIB.SCM(SCH_1):GND   I174 @SCM_LIB.SCM(SCH_1):PAGE29

 U30 IDTQS3VH257PAG_SMLF-IDTQS3VH25A
     4 SPI_PCH_MUXED_IO0 @SCM_LIB.SCM(SCH_1):SPI_PCH_MUXED_IO0   I271 @SCM_LIB.SCM(SCH_1):PAGE44
     7 SPI_PCH_MUXED_IO3 @SCM_LIB.SCM(SCH_1):SPI_PCH_MUXED_IO3   I271 @SCM_LIB.SCM(SCH_1):PAGE44
     9 SPI_PCH_MUXED_CLK @SCM_LIB.SCM(SCH_1):SPI_PCH_MUXED_CLK   I271 @SCM_LIB.SCM(SCH_1):PAGE44
    12 TP_BIOS_MUX0_PIN12 @SCM_LIB.SCM(SCH_1):TP_BIOS_MUX0_PIN12   I271 @SCM_LIB.SCM(SCH_1):PAGE44
     1 FM_BMC_BIOS_MUX_CS_SPI_R_SEL_0 @SCM_LIB.SCM(SCH_1):FM_BMC_BIOS_MUX_CS_SPI_R_SEL_0   I271 @SCM_LIB.SCM(SCH_1):PAGE44
    15 PD_BIOS_MUX_EN_N @SCM_LIB.SCM(SCH_1):PD_BIOS_MUX_EN_N   I271 @SCM_LIB.SCM(SCH_1):PAGE44
     2 SPI_SYS_MUX_MOSI @SCM_LIB.SCM(SCH_1):SPI_SYS_MUX_MOSI   I271 @SCM_LIB.SCM(SCH_1):PAGE44
     3 SPI_BMC_BIOS_ROM_R_MOSI @SCM_LIB.SCM(SCH_1):SPI_BMC_BIOS_ROM_R_MOSI   I271 @SCM_LIB.SCM(SCH_1):PAGE44
     6 SPI_BMC_BIOS_ROM_R_IO3 @SCM_LIB.SCM(SCH_1):SPI_BMC_BIOS_ROM_R_IO3   I271 @SCM_LIB.SCM(SCH_1):PAGE44
     5 SPI_SYS_MUX_HOLD_IO3 @SCM_LIB.SCM(SCH_1):SPI_SYS_MUX_HOLD_IO3   I271 @SCM_LIB.SCM(SCH_1):PAGE44
    10 SPI_BMC_BIOS_ROM_R_CLK @SCM_LIB.SCM(SCH_1):SPI_BMC_BIOS_ROM_R_CLK   I271 @SCM_LIB.SCM(SCH_1):PAGE44
    11 SPI_SYS_MUX_CLK @SCM_LIB.SCM(SCH_1):SPI_SYS_MUX_CLK   I271 @SCM_LIB.SCM(SCH_1):PAGE44
    14 TP_BIOS_MUX0_PIN14 @SCM_LIB.SCM(SCH_1):TP_BIOS_MUX0_PIN14   I271 @SCM_LIB.SCM(SCH_1):PAGE44
    13 TP_BIOS_MUX0_PIN13 @SCM_LIB.SCM(SCH_1):TP_BIOS_MUX0_PIN13   I271 @SCM_LIB.SCM(SCH_1):PAGE44
     8    GND @SCM_LIB.SCM(SCH_1):GND   I271 @SCM_LIB.SCM(SCH_1):PAGE44
    16 P3V3_AUX @SCM_LIB.SCM(SCH_1):P3V3_AUX   I271 @SCM_LIB.SCM(SCH_1):PAGE44

 U31 74LVC1G07GW-74LVC1G07GW,SMLF,IA
     5 P3V3_AUX @SCM_LIB.SCM(SCH_1):P3V3_AUX   I151 @SCM_LIB.SCM(SCH_1):PAGE50
     2 REAR_PWR_BTN_N @SCM_LIB.SCM(SCH_1):REAR_PWR_BTN_N   I151 @SCM_LIB.SCM(SCH_1):PAGE50
     3    GND @SCM_LIB.SCM(SCH_1):GND   I151 @SCM_LIB.SCM(SCH_1):PAGE50
     4 PWR_BTN_BMC_N @SCM_LIB.SCM(SCH_1):PWR_BTN_BMC_N   I151 @SCM_LIB.SCM(SCH_1):PAGE50
     1 TP_PWR_BUF @SCM_LIB.SCM(SCH_1):TP_PWR_BUF   I151 @SCM_LIB.SCM(SCH_1):PAGE50

 U32 74LVC1G17GW-74LVC1G17GW,SMLF,IA
     5 P3V3_AUX @SCM_LIB.SCM(SCH_1):P3V3_AUX    I49 @SCM_LIB.SCM(SCH_1):PAGE50
     2 REAR_ID_RST_BTN_N @SCM_LIB.SCM(SCH_1):REAR_ID_RST_BTN_N    I49 @SCM_LIB.SCM(SCH_1):PAGE50
     3    GND @SCM_LIB.SCM(SCH_1):GND    I49 @SCM_LIB.SCM(SCH_1):PAGE50
     4 ID_RST_BTN_BMC_N @SCM_LIB.SCM(SCH_1):ID_RST_BTN_BMC_N    I49 @SCM_LIB.SCM(SCH_1):PAGE50
     1 TP_ID_BUF @SCM_LIB.SCM(SCH_1):TP_ID_BUF    I49 @SCM_LIB.SCM(SCH_1):PAGE50

 U33 74HC1G126GW-74HC1G126GW,SMLF,IA
     2 V_VGAHS @SCM_LIB.SCM(SCH_1):V_VGAHS    I32 @SCM_LIB.SCM(SCH_1):PAGE23
     4 V_VGAHS_BUF_R @SCM_LIB.SCM(SCH_1):V_VGAHS_BUF_R    I32 @SCM_LIB.SCM(SCH_1):PAGE23
     5 BMC_DDC_BUF_PWR @SCM_LIB.SCM(SCH_1):BMC_DDC_BUF_PWR    I32 @SCM_LIB.SCM(SCH_1):PAGE23
     1 BMC_DDC_BUF_EN @SCM_LIB.SCM(SCH_1):BMC_DDC_BUF_EN    I32 @SCM_LIB.SCM(SCH_1):PAGE23
     3    GND @SCM_LIB.SCM(SCH_1):GND    I32 @SCM_LIB.SCM(SCH_1):PAGE23

 U34 DT1240E04LP7-DT1240E-04LP-7,SMA
     1 V_BMC_LS_DDC_SCL_R @SCM_LIB.SCM(SCH_1):V_BMC_LS_DDC_SCL_R   I156 @SCM_LIB.SCM(SCH_1):PAGE23
     3    GND @SCM_LIB.SCM(SCH_1):GND   I156 @SCM_LIB.SCM(SCH_1):PAGE23
     4 V_VGAHS_BUF @SCM_LIB.SCM(SCH_1):V_VGAHS_BUF   I156 @SCM_LIB.SCM(SCH_1):PAGE23
     6 V_VGAVS_BUF @SCM_LIB.SCM(SCH_1):V_VGAVS_BUF   I156 @SCM_LIB.SCM(SCH_1):PAGE23
     8    GND @SCM_LIB.SCM(SCH_1):GND   I156 @SCM_LIB.SCM(SCH_1):PAGE23
     9 V_BMC_LS_DDC_SDA_R @SCM_LIB.SCM(SCH_1):V_BMC_LS_DDC_SDA_R   I156 @SCM_LIB.SCM(SCH_1):PAGE23
    10 V_BMC_LS_DDC_SCL_R @SCM_LIB.SCM(SCH_1):V_BMC_LS_DDC_SCL_R   I156 @SCM_LIB.SCM(SCH_1):PAGE23
     2 V_BMC_LS_DDC_SDA_R @SCM_LIB.SCM(SCH_1):V_BMC_LS_DDC_SDA_R   I156 @SCM_LIB.SCM(SCH_1):PAGE23
     5 V_VGAVS_BUF @SCM_LIB.SCM(SCH_1):V_VGAVS_BUF   I156 @SCM_LIB.SCM(SCH_1):PAGE23
     7 V_VGAHS_BUF @SCM_LIB.SCM(SCH_1):V_VGAHS_BUF   I156 @SCM_LIB.SCM(SCH_1):PAGE23

 U35 DT1240E04LP7-DT1240E-04LP-7,SMA
     1 V_DACB_IO @SCM_LIB.SCM(SCH_1):V_DACB_IO   I155 @SCM_LIB.SCM(SCH_1):PAGE23
     3    GND @SCM_LIB.SCM(SCH_1):GND   I155 @SCM_LIB.SCM(SCH_1):PAGE23
     4 V_DACR_IO @SCM_LIB.SCM(SCH_1):V_DACR_IO   I155 @SCM_LIB.SCM(SCH_1):PAGE23
     6 TP_ESD_VGA_P4 @SCM_LIB.SCM(SCH_1):TP_ESD_VGA_P4   I155 @SCM_LIB.SCM(SCH_1):PAGE23
     8    GND @SCM_LIB.SCM(SCH_1):GND   I155 @SCM_LIB.SCM(SCH_1):PAGE23
     9 V_DACG_IO @SCM_LIB.SCM(SCH_1):V_DACG_IO   I155 @SCM_LIB.SCM(SCH_1):PAGE23
    10 V_DACB_IO @SCM_LIB.SCM(SCH_1):V_DACB_IO   I155 @SCM_LIB.SCM(SCH_1):PAGE23
     2 V_DACG_IO @SCM_LIB.SCM(SCH_1):V_DACG_IO   I155 @SCM_LIB.SCM(SCH_1):PAGE23
     5    TP4 @SCM_LIB.SCM(SCH_1):TP4   I155 @SCM_LIB.SCM(SCH_1):PAGE23
     7 V_DACR_IO @SCM_LIB.SCM(SCH_1):V_DACR_IO   I155 @SCM_LIB.SCM(SCH_1):PAGE23

 U36 74HC1G126GW-74HC1G126GW,SMLF,IA
     2 DEBUG_PORT_UART_RX @SCM_LIB.SCM(SCH_1):DEBUG_PORT_UART_RX   I164 @SCM_LIB.SCM(SCH_1):PAGE29
     4 SPA_SIN_SW_DBG @SCM_LIB.SCM(SCH_1):SPA_SIN_SW_DBG   I164 @SCM_LIB.SCM(SCH_1):PAGE29
     5 P3V3_AUX @SCM_LIB.SCM(SCH_1):P3V3_AUX   I164 @SCM_LIB.SCM(SCH_1):PAGE29
     1 DEBUG_PORT_PRSNT @SCM_LIB.SCM(SCH_1):DEBUG_PORT_PRSNT   I164 @SCM_LIB.SCM(SCH_1):PAGE29
     3    GND @SCM_LIB.SCM(SCH_1):GND   I164 @SCM_LIB.SCM(SCH_1):PAGE29

 U37 PCA9517ADP_SMLF-PCA9517ADP,IC,A
     5 DEBUG_PORT_PRSNT_BUF_EN @SCM_LIB.SCM(SCH_1):DEBUG_PORT_PRSNT_BUF_EN    I99 @SCM_LIB.SCM(SCH_1):PAGE28
     8 P3V3_AUX @SCM_LIB.SCM(SCH_1):P3V3_AUX    I99 @SCM_LIB.SCM(SCH_1):PAGE28
     2 SMB_BMC_MM15_R1_SCL @SCM_LIB.SCM(SCH_1):SMB_BMC_MM15_R1_SCL    I99 @SCM_LIB.SCM(SCH_1):PAGE28
     3 SMB_BMC_MM15_R1_SDA @SCM_LIB.SCM(SCH_1):SMB_BMC_MM15_R1_SDA    I99 @SCM_LIB.SCM(SCH_1):PAGE28
     6 SMB_DEBUG_AUX_LVC3_USB_R1_SDA @SCM_LIB.SCM(SCH_1):SMB_DEBUG_AUX_LVC3_USB_R1_SDA    I99 @SCM_LIB.SCM(SCH_1):PAGE28
     7 SMB_DEBUG_AUX_LVC3_USB_R1_SCL @SCM_LIB.SCM(SCH_1):SMB_DEBUG_AUX_LVC3_USB_R1_SCL    I99 @SCM_LIB.SCM(SCH_1):PAGE28
     1 P3V3_AUX @SCM_LIB.SCM(SCH_1):P3V3_AUX    I99 @SCM_LIB.SCM(SCH_1):PAGE28
     4    GND @SCM_LIB.SCM(SCH_1):GND    I99 @SCM_LIB.SCM(SCH_1):PAGE28

 U38 PRTR5V0U2X-PRTR5V0U2X,SMLF,IC,A
     2 USB2_01_F_DP @SCM_LIB.SCM(SCH_1):USB2_01_F_DP    I99 @SCM_LIB.SCM(SCH_1):PAGE29
     1    GND @SCM_LIB.SCM(SCH_1):GND    I99 @SCM_LIB.SCM(SCH_1):PAGE29
     4 P5V_USB_REAR @SCM_LIB.SCM(SCH_1):P5V_USB_REAR    I99 @SCM_LIB.SCM(SCH_1):PAGE29
     3 USB2_01_F_DN @SCM_LIB.SCM(SCH_1):USB2_01_F_DN    I99 @SCM_LIB.SCM(SCH_1):PAGE29

 U39 RT9059GQW-RT9059GQW,SMLF,IC,ALA
     5 PWRGD_P2V5_AUX_R @SCM_LIB.SCM(SCH_1):PWRGD_P2V5_AUX_R    I60 @SCM_LIB.SCM(SCH_1):PAGE53
     6 PWRGD_P3V3_AUX_R2 @SCM_LIB.SCM(SCH_1):PWRGD_P3V3_AUX_R2    I60 @SCM_LIB.SCM(SCH_1):PAGE53
     4 U39_ADJ @SCM_LIB.SCM(SCH_1):U39_ADJ    I60 @SCM_LIB.SCM(SCH_1):PAGE53
     1 P2V5_AUX @SCM_LIB.SCM(SCH_1):P2V5_AUX    I60 @SCM_LIB.SCM(SCH_1):PAGE53
     7 P3V3_AUX @SCM_LIB.SCM(SCH_1):P3V3_AUX    I60 @SCM_LIB.SCM(SCH_1):PAGE53
    10 P5V_AUX @SCM_LIB.SCM(SCH_1):P5V_AUX    I60 @SCM_LIB.SCM(SCH_1):PAGE53
    TH    GND @SCM_LIB.SCM(SCH_1):GND    I60 @SCM_LIB.SCM(SCH_1):PAGE53
     2 P2V5_AUX @SCM_LIB.SCM(SCH_1):P2V5_AUX    I60 @SCM_LIB.SCM(SCH_1):PAGE53
     3 P2V5_AUX @SCM_LIB.SCM(SCH_1):P2V5_AUX    I60 @SCM_LIB.SCM(SCH_1):PAGE53
     8 P3V3_AUX @SCM_LIB.SCM(SCH_1):P3V3_AUX    I60 @SCM_LIB.SCM(SCH_1):PAGE53
     9 P3V3_AUX @SCM_LIB.SCM(SCH_1):P3V3_AUX    I60 @SCM_LIB.SCM(SCH_1):PAGE53

 U40 PCA9555PW_SMLF-PCA9555PW,IC,TMA
     1 LED_POSTCODE_INT @SCM_LIB.SCM(SCH_1):LED_POSTCODE_INT   I141 @SCM_LIB.SCM(SCH_1):PAGE28
    23 SMB_DEBUG_AUX_LVC3_USB_R3_SDA @SCM_LIB.SCM(SCH_1):SMB_DEBUG_AUX_LVC3_USB_R3_SDA   I141 @SCM_LIB.SCM(SCH_1):PAGE28
    22 SMB_DEBUG_AUX_LVC3_USB_R3_SCL @SCM_LIB.SCM(SCH_1):SMB_DEBUG_AUX_LVC3_USB_R3_SCL   I141 @SCM_LIB.SCM(SCH_1):PAGE28
     4 LED_POSTCODE_0_R1 @SCM_LIB.SCM(SCH_1):LED_POSTCODE_0_R1   I141 @SCM_LIB.SCM(SCH_1):PAGE28
     5 LED_POSTCODE_1_R1 @SCM_LIB.SCM(SCH_1):LED_POSTCODE_1_R1   I141 @SCM_LIB.SCM(SCH_1):PAGE28
     6 LED_POSTCODE_2_R1 @SCM_LIB.SCM(SCH_1):LED_POSTCODE_2_R1   I141 @SCM_LIB.SCM(SCH_1):PAGE28
     7 LED_POSTCODE_3_R1 @SCM_LIB.SCM(SCH_1):LED_POSTCODE_3_R1   I141 @SCM_LIB.SCM(SCH_1):PAGE28
     8 LED_POSTCODE_4_R1 @SCM_LIB.SCM(SCH_1):LED_POSTCODE_4_R1   I141 @SCM_LIB.SCM(SCH_1):PAGE28
     9 LED_POSTCODE_5_R1 @SCM_LIB.SCM(SCH_1):LED_POSTCODE_5_R1   I141 @SCM_LIB.SCM(SCH_1):PAGE28
    10 LED_POSTCODE_6_R1 @SCM_LIB.SCM(SCH_1):LED_POSTCODE_6_R1   I141 @SCM_LIB.SCM(SCH_1):PAGE28
    11 LED_POSTCODE_7_R1 @SCM_LIB.SCM(SCH_1):LED_POSTCODE_7_R1   I141 @SCM_LIB.SCM(SCH_1):PAGE28
    13 FM_DEBUG_RST_BTN_N @SCM_LIB.SCM(SCH_1):FM_DEBUG_RST_BTN_N   I141 @SCM_LIB.SCM(SCH_1):PAGE28
    14 FM_DEBUG_PWR_BTN_N @SCM_LIB.SCM(SCH_1):FM_DEBUG_PWR_BTN_N   I141 @SCM_LIB.SCM(SCH_1):PAGE28
    15 PWRGD_SYS_PWROK_R1 @SCM_LIB.SCM(SCH_1):PWRGD_SYS_PWROK_R1   I141 @SCM_LIB.SCM(SCH_1):PAGE28
    16 RST_PLTRST_R2_N @SCM_LIB.SCM(SCH_1):RST_PLTRST_R2_N   I141 @SCM_LIB.SCM(SCH_1):PAGE28
    17 PWRGD_DSW_PWROK_R3 @SCM_LIB.SCM(SCH_1):PWRGD_DSW_PWROK_R3   I141 @SCM_LIB.SCM(SCH_1):PAGE28
    18 FM_CPU_MSMI_CATERR_LVT3_R3_N @SCM_LIB.SCM(SCH_1):FM_CPU_MSMI_CATERR_LVT3_R3_N   I141 @SCM_LIB.SCM(SCH_1):PAGE28
    19 FM_SLPS3_GF_R2_N @SCM_LIB.SCM(SCH_1):FM_SLPS3_GF_R2_N   I141 @SCM_LIB.SCM(SCH_1):PAGE28
    20 FM_UART_SWITCH_N @SCM_LIB.SCM(SCH_1):FM_UART_SWITCH_N   I141 @SCM_LIB.SCM(SCH_1):PAGE28
    21 LED_POSTCODE_A0 @SCM_LIB.SCM(SCH_1):LED_POSTCODE_A0   I141 @SCM_LIB.SCM(SCH_1):PAGE28
     2 LED_POSTCODE_A1 @SCM_LIB.SCM(SCH_1):LED_POSTCODE_A1   I141 @SCM_LIB.SCM(SCH_1):PAGE28
     3 LED_POSTCODE_A2 @SCM_LIB.SCM(SCH_1):LED_POSTCODE_A2   I141 @SCM_LIB.SCM(SCH_1):PAGE28
    24 P3V3_AUX @SCM_LIB.SCM(SCH_1):P3V3_AUX   I141 @SCM_LIB.SCM(SCH_1):PAGE28
    12    GND @SCM_LIB.SCM(SCH_1):GND   I141 @SCM_LIB.SCM(SCH_1):PAGE28

 U41 RT9059GQW-RT9059GQW,SMLF,IC,ALA
     5 PWRGD_P1V8_AUX_R @SCM_LIB.SCM(SCH_1):PWRGD_P1V8_AUX_R    I96 @SCM_LIB.SCM(SCH_1):PAGE54
     6 EN_P1V8_R @SCM_LIB.SCM(SCH_1):EN_P1V8_R    I96 @SCM_LIB.SCM(SCH_1):PAGE54
     4 U41_ADJ @SCM_LIB.SCM(SCH_1):U41_ADJ    I96 @SCM_LIB.SCM(SCH_1):PAGE54
     1 P1V8_AUX @SCM_LIB.SCM(SCH_1):P1V8_AUX    I96 @SCM_LIB.SCM(SCH_1):PAGE54
     7 P3V3_AUX @SCM_LIB.SCM(SCH_1):P3V3_AUX    I96 @SCM_LIB.SCM(SCH_1):PAGE54
    10 P5V_AUX @SCM_LIB.SCM(SCH_1):P5V_AUX    I96 @SCM_LIB.SCM(SCH_1):PAGE54
    TH    GND @SCM_LIB.SCM(SCH_1):GND    I96 @SCM_LIB.SCM(SCH_1):PAGE54
     2 P1V8_AUX @SCM_LIB.SCM(SCH_1):P1V8_AUX    I96 @SCM_LIB.SCM(SCH_1):PAGE54
     3 P1V8_AUX @SCM_LIB.SCM(SCH_1):P1V8_AUX    I96 @SCM_LIB.SCM(SCH_1):PAGE54
     8 P3V3_AUX @SCM_LIB.SCM(SCH_1):P3V3_AUX    I96 @SCM_LIB.SCM(SCH_1):PAGE54
     9 P3V3_AUX @SCM_LIB.SCM(SCH_1):P3V3_AUX    I96 @SCM_LIB.SCM(SCH_1):PAGE54

 U42 MC74VHC1G32DTT1G-MC74VHC1G32DTA
     4 EN_P3V3 @SCM_LIB.SCM(SCH_1):EN_P3V3   I104 @SCM_LIB.SCM(SCH_1):PAGE52
     1 PWRGD_P5V_AUX @SCM_LIB.SCM(SCH_1):PWRGD_P5V_AUX   I104 @SCM_LIB.SCM(SCH_1):PAGE52
     2 PWRGD_P1V8_AUX @SCM_LIB.SCM(SCH_1):PWRGD_P1V8_AUX   I104 @SCM_LIB.SCM(SCH_1):PAGE52
     3    GND @SCM_LIB.SCM(SCH_1):GND   I104 @SCM_LIB.SCM(SCH_1):PAGE52
     5 P3V3_LDO @SCM_LIB.SCM(SCH_1):P3V3_LDO   I104 @SCM_LIB.SCM(SCH_1):PAGE52

 U43 TPS3808G18DBVR-TPS3808G01DBVR,A
     1 PWRGD_P1V0_AUX_DELAY_R1 @SCM_LIB.SCM(SCH_1):PWRGD_P1V0_AUX_DELAY_R1    I90 @SCM_LIB.SCM(SCH_1):PAGE22
     2    GND @SCM_LIB.SCM(SCH_1):GND    I90 @SCM_LIB.SCM(SCH_1):PAGE22
     3 PWRGD_P1V0_AUX_R2 @SCM_LIB.SCM(SCH_1):PWRGD_P1V0_AUX_R2    I90 @SCM_LIB.SCM(SCH_1):PAGE22
     6 P3V3_AUX @SCM_LIB.SCM(SCH_1):P3V3_AUX    I90 @SCM_LIB.SCM(SCH_1):PAGE22
     4 U43_CT @SCM_LIB.SCM(SCH_1):U43_CT    I90 @SCM_LIB.SCM(SCH_1):PAGE22
     5 P1V0_AUX @SCM_LIB.SCM(SCH_1):P1V0_AUX    I90 @SCM_LIB.SCM(SCH_1):PAGE22

 U44 SN74LVC1G07DCKR-SN74LVC1G07DCKA
     5 P3V3_AUX @SCM_LIB.SCM(SCH_1):P3V3_AUX    I61 @SCM_LIB.SCM(SCH_1):PAGE25
     2 RST_SPI_FLASH_R_N @SCM_LIB.SCM(SCH_1):RST_SPI_FLASH_R_N    I61 @SCM_LIB.SCM(SCH_1):PAGE25
     3    GND @SCM_LIB.SCM(SCH_1):GND    I61 @SCM_LIB.SCM(SCH_1):PAGE25
     4 RST_SPI_FLASH_BUF_R3_N @SCM_LIB.SCM(SCH_1):RST_SPI_FLASH_BUF_R3_N    I61 @SCM_LIB.SCM(SCH_1):PAGE25
     1     NC     NC    I61 @SCM_LIB.SCM(SCH_1):PAGE25

 U47 74LVC2G07DW7-74LVC2G07DW-7,SMLA
     1 UART_BMC_5_TXD_R @SCM_LIB.SCM(SCH_1):UART_BMC_5_TXD_R   I247 @SCM_LIB.SCM(SCH_1):PAGE30
     3 UART_BMC_5_RXD_BUF1 @SCM_LIB.SCM(SCH_1):UART_BMC_5_RXD_BUF1   I247 @SCM_LIB.SCM(SCH_1):PAGE30
     6 UART_BMC_5_TXD_BUF1 @SCM_LIB.SCM(SCH_1):UART_BMC_5_TXD_BUF1   I247 @SCM_LIB.SCM(SCH_1):PAGE30
     4 UART_BMC_5_RXD_BUF1_R @SCM_LIB.SCM(SCH_1):UART_BMC_5_RXD_BUF1_R   I247 @SCM_LIB.SCM(SCH_1):PAGE30
     2    GND @SCM_LIB.SCM(SCH_1):GND   I247 @SCM_LIB.SCM(SCH_1):PAGE30
     5 P3V3_AUX @SCM_LIB.SCM(SCH_1):P3V3_AUX   I247 @SCM_LIB.SCM(SCH_1):PAGE30

 U48 BAS70057F-BAS70-05-7-F,SMLF,ICA
     2 P3V3_AUX @SCM_LIB.SCM(SCH_1):P3V3_AUX   I161 @SCM_LIB.SCM(SCH_1):PAGE50
     1 P3V_BAT_R @SCM_LIB.SCM(SCH_1):P3V_BAT_R   I161 @SCM_LIB.SCM(SCH_1):PAGE50
     3 P3V3_RTC_AUX @SCM_LIB.SCM(SCH_1):P3V3_RTC_AUX   I161 @SCM_LIB.SCM(SCH_1):PAGE50

 U49 MC74VHC1G32DTT1G-MC74VHC1G32DTA
     4 EN_P1V8 @SCM_LIB.SCM(SCH_1):EN_P1V8   I116 @SCM_LIB.SCM(SCH_1):PAGE54
     1 PWRGD_P5V_AUX @SCM_LIB.SCM(SCH_1):PWRGD_P5V_AUX   I116 @SCM_LIB.SCM(SCH_1):PAGE54
     2 PWRGD_P3V3_RGM_R2 @SCM_LIB.SCM(SCH_1):PWRGD_P3V3_RGM_R2   I116 @SCM_LIB.SCM(SCH_1):PAGE54
     3    GND @SCM_LIB.SCM(SCH_1):GND   I116 @SCM_LIB.SCM(SCH_1):PAGE54
     5 P3V3_LDO @SCM_LIB.SCM(SCH_1):P3V3_LDO   I116 @SCM_LIB.SCM(SCH_1):PAGE54

 U50 NC7SB3157_SMLF-NC7SB3157P6X,NCA
     1 UART_BIC_DBG_TX_R @SCM_LIB.SCM(SCH_1):UART_BIC_DBG_TX_R    I23 @SCM_LIB.SCM(SCH_1):PAGE31
     2    GND @SCM_LIB.SCM(SCH_1):GND    I23 @SCM_LIB.SCM(SCH_1):PAGE31
     3 UART_6_BMC_RXD_R @SCM_LIB.SCM(SCH_1):UART_6_BMC_RXD_R    I23 @SCM_LIB.SCM(SCH_1):PAGE31
     6 FM_BIC_DEBUG_SW_N @SCM_LIB.SCM(SCH_1):FM_BIC_DEBUG_SW_N    I23 @SCM_LIB.SCM(SCH_1):PAGE31
     5 P3V3_AUX @SCM_LIB.SCM(SCH_1):P3V3_AUX    I23 @SCM_LIB.SCM(SCH_1):PAGE31
     4 UART_BIC_GF_RXD @SCM_LIB.SCM(SCH_1):UART_BIC_GF_RXD    I23 @SCM_LIB.SCM(SCH_1):PAGE31

 U51 NC7SB3157_SMLF-NC7SB3157P6X,NCA
     1 UART_BIC_DBG_RX_R @SCM_LIB.SCM(SCH_1):UART_BIC_DBG_RX_R    I24 @SCM_LIB.SCM(SCH_1):PAGE31
     2    GND @SCM_LIB.SCM(SCH_1):GND    I24 @SCM_LIB.SCM(SCH_1):PAGE31
     3 UART_6_BMC_TXD_R @SCM_LIB.SCM(SCH_1):UART_6_BMC_TXD_R    I24 @SCM_LIB.SCM(SCH_1):PAGE31
     6 FM_BIC_DEBUG_SW_N @SCM_LIB.SCM(SCH_1):FM_BIC_DEBUG_SW_N    I24 @SCM_LIB.SCM(SCH_1):PAGE31
     5 P3V3_AUX @SCM_LIB.SCM(SCH_1):P3V3_AUX    I24 @SCM_LIB.SCM(SCH_1):PAGE31
     4 UART_BIC_GF_TXD @SCM_LIB.SCM(SCH_1):UART_BIC_GF_TXD    I24 @SCM_LIB.SCM(SCH_1):PAGE31

 U52 74LVC1G08GW_SM-74LVC1G08GW,IC,A
     1 PWRGD_P5V_AUX @SCM_LIB.SCM(SCH_1):PWRGD_P5V_AUX    I63 @SCM_LIB.SCM(SCH_1):PAGE55
     2 PWRGD_P3V3_RGM @SCM_LIB.SCM(SCH_1):PWRGD_P3V3_RGM    I63 @SCM_LIB.SCM(SCH_1):PAGE55
     4 EN_P1V2_AUX @SCM_LIB.SCM(SCH_1):EN_P1V2_AUX    I63 @SCM_LIB.SCM(SCH_1):PAGE55
     5 P3V3_LDO @SCM_LIB.SCM(SCH_1):P3V3_LDO    I63 @SCM_LIB.SCM(SCH_1):PAGE55
     3    GND @SCM_LIB.SCM(SCH_1):GND    I63 @SCM_LIB.SCM(SCH_1):PAGE55

 U53 74LVC1G08GW_SM-74LVC1G08GW,IC,A
     1 PWRGD_P5V_AUX @SCM_LIB.SCM(SCH_1):PWRGD_P5V_AUX    I66 @SCM_LIB.SCM(SCH_1):PAGE56
     2 PWRGD_P1V2_AUX @SCM_LIB.SCM(SCH_1):PWRGD_P1V2_AUX    I66 @SCM_LIB.SCM(SCH_1):PAGE56
     4 EN_P1V0_AUX @SCM_LIB.SCM(SCH_1):EN_P1V0_AUX    I66 @SCM_LIB.SCM(SCH_1):PAGE56
     5 P3V3_LDO @SCM_LIB.SCM(SCH_1):P3V3_LDO    I66 @SCM_LIB.SCM(SCH_1):PAGE56
     3    GND @SCM_LIB.SCM(SCH_1):GND    I66 @SCM_LIB.SCM(SCH_1):PAGE56

 U54 74LVC1G74DP-74LVC1G74DP,SMLF,IA
     1 FLASH_LATCH_CP @SCM_LIB.SCM(SCH_1):FLASH_LATCH_CP   I138 @SCM_LIB.SCM(SCH_1):PAGE25
     2 FLASH_LATCH_D @SCM_LIB.SCM(SCH_1):FLASH_LATCH_D   I138 @SCM_LIB.SCM(SCH_1):PAGE25
     3 FLASH_LATCH_Q_N_R @SCM_LIB.SCM(SCH_1):FLASH_LATCH_Q_N_R   I138 @SCM_LIB.SCM(SCH_1):PAGE25
     4    GND @SCM_LIB.SCM(SCH_1):GND   I138 @SCM_LIB.SCM(SCH_1):PAGE25
     8 P3V3_AUX @SCM_LIB.SCM(SCH_1):P3V3_AUX   I138 @SCM_LIB.SCM(SCH_1):PAGE25
     6   RD_N @SCM_LIB.SCM(SCH_1):RD_N   I138 @SCM_LIB.SCM(SCH_1):PAGE25
     7 FM_FLASH_LATCH_N @SCM_LIB.SCM(SCH_1):FM_FLASH_LATCH_N   I138 @SCM_LIB.SCM(SCH_1):PAGE25
     5 NC_U54_P1 @SCM_LIB.SCM(SCH_1):NC_U54_P1   I138 @SCM_LIB.SCM(SCH_1):PAGE25

 U55 SN74LVC1G14DCKR_SMLF-IC,SN74LVA
     2 FLASH_LATCH_Q_N_R2 @SCM_LIB.SCM(SCH_1):FLASH_LATCH_Q_N_R2   I150 @SCM_LIB.SCM(SCH_1):PAGE25
     4 FLASH_R_WP_STATUS @SCM_LIB.SCM(SCH_1):FLASH_R_WP_STATUS   I150 @SCM_LIB.SCM(SCH_1):PAGE25
     1 NC_U55_P1 @SCM_LIB.SCM(SCH_1):NC_U55_P1   I150 @SCM_LIB.SCM(SCH_1):PAGE25
     5 P3V3_AUX @SCM_LIB.SCM(SCH_1):P3V3_AUX   I150 @SCM_LIB.SCM(SCH_1):PAGE25
     3    GND @SCM_LIB.SCM(SCH_1):GND   I150 @SCM_LIB.SCM(SCH_1):PAGE25

 U56 AP2205W57-AP2205-W5-7,SMLF,IC,A
     5 P3V3_LDO @SCM_LIB.SCM(SCH_1):P3V3_LDO    I56 @SCM_LIB.SCM(SCH_1):PAGE51
     4 U56_ADJ_1 @SCM_LIB.SCM(SCH_1):U56_ADJ_1    I56 @SCM_LIB.SCM(SCH_1):PAGE51
     1 P12V_AUX @SCM_LIB.SCM(SCH_1):P12V_AUX    I56 @SCM_LIB.SCM(SCH_1):PAGE51
     2    GND @SCM_LIB.SCM(SCH_1):GND    I56 @SCM_LIB.SCM(SCH_1):PAGE51
     3 P12V_AUX @SCM_LIB.SCM(SCH_1):P12V_AUX    I56 @SCM_LIB.SCM(SCH_1):PAGE51

 U57 74LVC1G07GW-74LVC1G07GW,SMLF,IA
     5 P3V3_AUX @SCM_LIB.SCM(SCH_1):P3V3_AUX   I278 @SCM_LIB.SCM(SCH_1):PAGE50
     2 REAR_AC_PWR_BMC_BTN_N @SCM_LIB.SCM(SCH_1):REAR_AC_PWR_BMC_BTN_N   I278 @SCM_LIB.SCM(SCH_1):PAGE50
     3    GND @SCM_LIB.SCM(SCH_1):GND   I278 @SCM_LIB.SCM(SCH_1):PAGE50
     4 AC_PWR_BMC_BTN_N @SCM_LIB.SCM(SCH_1):AC_PWR_BMC_BTN_N   I278 @SCM_LIB.SCM(SCH_1):PAGE50
     1 NC_U57_P1 @SCM_LIB.SCM(SCH_1):NC_U57_P1   I278 @SCM_LIB.SCM(SCH_1):PAGE50

 U58 MC74VHC1G32DTT1G-MC74VHC1G32DTA
     4 RST_BMC_HW_OUT @SCM_LIB.SCM(SCH_1):RST_BMC_HW_OUT    I94 @SCM_LIB.SCM(SCH_1):PAGE22
     1 RST_BMC_SELF_HW_R3 @SCM_LIB.SCM(SCH_1):RST_BMC_SELF_HW_R3    I94 @SCM_LIB.SCM(SCH_1):PAGE22
     2 RST_BMC_HW_R1 @SCM_LIB.SCM(SCH_1):RST_BMC_HW_R1    I94 @SCM_LIB.SCM(SCH_1):PAGE22
     3    GND @SCM_LIB.SCM(SCH_1):GND    I94 @SCM_LIB.SCM(SCH_1):PAGE22
     5 P3V3_AUX @SCM_LIB.SCM(SCH_1):P3V3_AUX    I94 @SCM_LIB.SCM(SCH_1):PAGE22

  X1 TP_TDR_4P_FTS_TH-TP_TDR_4P_DIPA
     2 GND_P1 @SCM_LIB.SCM(SCH_1):GND_P1    I13 @SCM_LIB.SCM(SCH_1):PAGE60
     3 GND_P1 @SCM_LIB.SCM(SCH_1):GND_P1    I13 @SCM_LIB.SCM(SCH_1):PAGE60
     1 TDR_DIFF_85_TOP_DP @SCM_LIB.SCM(SCH_1):TDR_DIFF_85_TOP_DP    I13 @SCM_LIB.SCM(SCH_1):PAGE60
     4 TDR_DIFF_85_TOP_DN @SCM_LIB.SCM(SCH_1):TDR_DIFF_85_TOP_DN    I13 @SCM_LIB.SCM(SCH_1):PAGE60

  X2 TP_TDR_4P_FTS_TH-TP_TDR_4P_DIPA
     2 GND_P1 @SCM_LIB.SCM(SCH_1):GND_P1    I35 @SCM_LIB.SCM(SCH_1):PAGE60
     3 GND_P1 @SCM_LIB.SCM(SCH_1):GND_P1    I35 @SCM_LIB.SCM(SCH_1):PAGE60
     1 TDR_DIFF_85_IN1_DP @SCM_LIB.SCM(SCH_1):TDR_DIFF_85_IN1_DP    I35 @SCM_LIB.SCM(SCH_1):PAGE60
     4 TDR_DIFF_85_IN1_DN @SCM_LIB.SCM(SCH_1):TDR_DIFF_85_IN1_DN    I35 @SCM_LIB.SCM(SCH_1):PAGE60

  X5 TP_TDR_4P_FTS_TH-TP_TDR_4P_DIPA
     2 GND_P1 @SCM_LIB.SCM(SCH_1):GND_P1    I23 @SCM_LIB.SCM(SCH_1):PAGE60
     3 GND_P1 @SCM_LIB.SCM(SCH_1):GND_P1    I23 @SCM_LIB.SCM(SCH_1):PAGE60
     1 TDR_DIFF_85_IN4_DP @SCM_LIB.SCM(SCH_1):TDR_DIFF_85_IN4_DP    I23 @SCM_LIB.SCM(SCH_1):PAGE60
     4 TDR_DIFF_85_IN4_DN @SCM_LIB.SCM(SCH_1):TDR_DIFF_85_IN4_DN    I23 @SCM_LIB.SCM(SCH_1):PAGE60

  X6 TP_TDR_4P_FTS_TH-TP_TDR_4P_DIPA
     2 GND_P1 @SCM_LIB.SCM(SCH_1):GND_P1    I19 @SCM_LIB.SCM(SCH_1):PAGE60
     3 GND_P1 @SCM_LIB.SCM(SCH_1):GND_P1    I19 @SCM_LIB.SCM(SCH_1):PAGE60
     1 TDR_DIFF_85_BOT_DP @SCM_LIB.SCM(SCH_1):TDR_DIFF_85_BOT_DP    I19 @SCM_LIB.SCM(SCH_1):PAGE60
     4 TDR_DIFF_85_BOT_DN @SCM_LIB.SCM(SCH_1):TDR_DIFF_85_BOT_DN    I19 @SCM_LIB.SCM(SCH_1):PAGE60

  X7 TP_TDR_4P_FTS_TH-TP_TDR_4P_DIPA
     2 GND_P1 @SCM_LIB.SCM(SCH_1):GND_P1    I14 @SCM_LIB.SCM(SCH_1):PAGE60
     3 GND_P1 @SCM_LIB.SCM(SCH_1):GND_P1    I14 @SCM_LIB.SCM(SCH_1):PAGE60
     1 TDR_DIFF_85_TOP_DN @SCM_LIB.SCM(SCH_1):TDR_DIFF_85_TOP_DN    I14 @SCM_LIB.SCM(SCH_1):PAGE60
     4 TDR_DIFF_85_TOP_DP @SCM_LIB.SCM(SCH_1):TDR_DIFF_85_TOP_DP    I14 @SCM_LIB.SCM(SCH_1):PAGE60

  X8 TP_TDR_4P_FTS_TH-TP_TDR_4P_DIPA
     2 GND_P1 @SCM_LIB.SCM(SCH_1):GND_P1    I34 @SCM_LIB.SCM(SCH_1):PAGE60
     3 GND_P1 @SCM_LIB.SCM(SCH_1):GND_P1    I34 @SCM_LIB.SCM(SCH_1):PAGE60
     1 TDR_DIFF_85_IN1_DN @SCM_LIB.SCM(SCH_1):TDR_DIFF_85_IN1_DN    I34 @SCM_LIB.SCM(SCH_1):PAGE60
     4 TDR_DIFF_85_IN1_DP @SCM_LIB.SCM(SCH_1):TDR_DIFF_85_IN1_DP    I34 @SCM_LIB.SCM(SCH_1):PAGE60

 X11 TP_TDR_4P_FTS_TH-TP_TDR_4P_DIPA
     2 GND_P1 @SCM_LIB.SCM(SCH_1):GND_P1    I22 @SCM_LIB.SCM(SCH_1):PAGE60
     3 GND_P1 @SCM_LIB.SCM(SCH_1):GND_P1    I22 @SCM_LIB.SCM(SCH_1):PAGE60
     1 TDR_DIFF_85_IN4_DN @SCM_LIB.SCM(SCH_1):TDR_DIFF_85_IN4_DN    I22 @SCM_LIB.SCM(SCH_1):PAGE60
     4 TDR_DIFF_85_IN4_DP @SCM_LIB.SCM(SCH_1):TDR_DIFF_85_IN4_DP    I22 @SCM_LIB.SCM(SCH_1):PAGE60

 X12 TP_TDR_4P_FTS_TH-TP_TDR_4P_DIPA
     2 GND_P1 @SCM_LIB.SCM(SCH_1):GND_P1    I18 @SCM_LIB.SCM(SCH_1):PAGE60
     3 GND_P1 @SCM_LIB.SCM(SCH_1):GND_P1    I18 @SCM_LIB.SCM(SCH_1):PAGE60
     1 TDR_DIFF_85_BOT_DN @SCM_LIB.SCM(SCH_1):TDR_DIFF_85_BOT_DN    I18 @SCM_LIB.SCM(SCH_1):PAGE60
     4 TDR_DIFF_85_BOT_DP @SCM_LIB.SCM(SCH_1):TDR_DIFF_85_BOT_DP    I18 @SCM_LIB.SCM(SCH_1):PAGE60

 X13 TP_TDR_4P_FTS_TH-TP_TDR_4P_DIPA
     2 GND_P1 @SCM_LIB.SCM(SCH_1):GND_P1    I39 @SCM_LIB.SCM(SCH_1):PAGE60
     3 GND_P1 @SCM_LIB.SCM(SCH_1):GND_P1    I39 @SCM_LIB.SCM(SCH_1):PAGE60
     1 TDR_DIFF_100_TOP_DP @SCM_LIB.SCM(SCH_1):TDR_DIFF_100_TOP_DP    I39 @SCM_LIB.SCM(SCH_1):PAGE60
     4 TDR_DIFF_100_TOP_DN @SCM_LIB.SCM(SCH_1):TDR_DIFF_100_TOP_DN    I39 @SCM_LIB.SCM(SCH_1):PAGE60

 X14 TP_TDR_4P_FTS_TH-TP_TDR_4P_DIPA
     2 GND_P1 @SCM_LIB.SCM(SCH_1):GND_P1    I58 @SCM_LIB.SCM(SCH_1):PAGE60
     3 GND_P1 @SCM_LIB.SCM(SCH_1):GND_P1    I58 @SCM_LIB.SCM(SCH_1):PAGE60
     1 TDR_DIFF_100_IN1_DP @SCM_LIB.SCM(SCH_1):TDR_DIFF_100_IN1_DP    I58 @SCM_LIB.SCM(SCH_1):PAGE60
     4 TDR_DIFF_100_IN1_DN @SCM_LIB.SCM(SCH_1):TDR_DIFF_100_IN1_DN    I58 @SCM_LIB.SCM(SCH_1):PAGE60

 X17 TP_TDR_4P_FTS_TH-TP_TDR_4P_DIPA
     2 GND_P1 @SCM_LIB.SCM(SCH_1):GND_P1    I46 @SCM_LIB.SCM(SCH_1):PAGE60
     3 GND_P1 @SCM_LIB.SCM(SCH_1):GND_P1    I46 @SCM_LIB.SCM(SCH_1):PAGE60
     1 TDR_DIFF_100_IN4_DP @SCM_LIB.SCM(SCH_1):TDR_DIFF_100_IN4_DP    I46 @SCM_LIB.SCM(SCH_1):PAGE60
     4 TDR_DIFF_100_IN4_DN @SCM_LIB.SCM(SCH_1):TDR_DIFF_100_IN4_DN    I46 @SCM_LIB.SCM(SCH_1):PAGE60

 X18 TP_TDR_4P_FTS_TH-TP_TDR_4P_DIPA
     2 GND_P1 @SCM_LIB.SCM(SCH_1):GND_P1    I42 @SCM_LIB.SCM(SCH_1):PAGE60
     3 GND_P1 @SCM_LIB.SCM(SCH_1):GND_P1    I42 @SCM_LIB.SCM(SCH_1):PAGE60
     1 TDR_DIFF_100_BOT_DP @SCM_LIB.SCM(SCH_1):TDR_DIFF_100_BOT_DP    I42 @SCM_LIB.SCM(SCH_1):PAGE60
     4 TDR_DIFF_100_BOT_DN @SCM_LIB.SCM(SCH_1):TDR_DIFF_100_BOT_DN    I42 @SCM_LIB.SCM(SCH_1):PAGE60

 X19 TP_TDR_4P_FTS_TH-TP_TDR_4P_DIPA
     2 GND_P1 @SCM_LIB.SCM(SCH_1):GND_P1    I38 @SCM_LIB.SCM(SCH_1):PAGE60
     3 GND_P1 @SCM_LIB.SCM(SCH_1):GND_P1    I38 @SCM_LIB.SCM(SCH_1):PAGE60
     1 TDR_DIFF_100_TOP_DN @SCM_LIB.SCM(SCH_1):TDR_DIFF_100_TOP_DN    I38 @SCM_LIB.SCM(SCH_1):PAGE60
     4 TDR_DIFF_100_TOP_DP @SCM_LIB.SCM(SCH_1):TDR_DIFF_100_TOP_DP    I38 @SCM_LIB.SCM(SCH_1):PAGE60

 X20 TP_TDR_4P_FTS_TH-TP_TDR_4P_DIPA
     2 GND_P1 @SCM_LIB.SCM(SCH_1):GND_P1    I59 @SCM_LIB.SCM(SCH_1):PAGE60
     3 GND_P1 @SCM_LIB.SCM(SCH_1):GND_P1    I59 @SCM_LIB.SCM(SCH_1):PAGE60
     1 TDR_DIFF_100_IN1_DN @SCM_LIB.SCM(SCH_1):TDR_DIFF_100_IN1_DN    I59 @SCM_LIB.SCM(SCH_1):PAGE60
     4 TDR_DIFF_100_IN1_DP @SCM_LIB.SCM(SCH_1):TDR_DIFF_100_IN1_DP    I59 @SCM_LIB.SCM(SCH_1):PAGE60

 X23 TP_TDR_4P_FTS_TH-TP_TDR_4P_DIPA
     2 GND_P1 @SCM_LIB.SCM(SCH_1):GND_P1    I47 @SCM_LIB.SCM(SCH_1):PAGE60
     3 GND_P1 @SCM_LIB.SCM(SCH_1):GND_P1    I47 @SCM_LIB.SCM(SCH_1):PAGE60
     1 TDR_DIFF_100_IN4_DN @SCM_LIB.SCM(SCH_1):TDR_DIFF_100_IN4_DN    I47 @SCM_LIB.SCM(SCH_1):PAGE60
     4 TDR_DIFF_100_IN4_DP @SCM_LIB.SCM(SCH_1):TDR_DIFF_100_IN4_DP    I47 @SCM_LIB.SCM(SCH_1):PAGE60

 X24 TP_TDR_4P_FTS_TH-TP_TDR_4P_DIPA
     2 GND_P1 @SCM_LIB.SCM(SCH_1):GND_P1    I43 @SCM_LIB.SCM(SCH_1):PAGE60
     3 GND_P1 @SCM_LIB.SCM(SCH_1):GND_P1    I43 @SCM_LIB.SCM(SCH_1):PAGE60
     1 TDR_DIFF_100_BOT_DN @SCM_LIB.SCM(SCH_1):TDR_DIFF_100_BOT_DN    I43 @SCM_LIB.SCM(SCH_1):PAGE60
     4 TDR_DIFF_100_BOT_DP @SCM_LIB.SCM(SCH_1):TDR_DIFF_100_BOT_DP    I43 @SCM_LIB.SCM(SCH_1):PAGE60

END GLOBAL PART CROSS REFERENCE
